FILE_TYPE = MULTI_PHYS_TABLE;

PART 'Q_RES'

{========================================================================================}
:VALUE        | TOLERANCE | WATTAGE  | PACK_TYPE | MATERIAL | PART_NUMBER             = STANDARD        | LIFECYCLE          | PART_NUMBER             | JEDEC_TYPE          | ALT_SYMBOLS                    | VALUE     | TOL     | WATTAGE  | CLASS      | DESCRIPTION                                        | COMPONENT_TYPE | LEAD_LENGTH | DFM_EXCLUSION | DAY        ;
{========================================================================================}
 '64.9K'      | '1%'      | '1/10W'  | '0603LF'  | 'CHIP'   | 'TMP_QCS36493F913'(!)   = 'End of Design' | 'Comp-Approve'     | 'CS36493F913'           |'R0603'| '(SMR0603AW)'                  | '64.9K'   | '1%'    | '1/10W'  | 'DISCRETE' | '64.9Kohm 0603'                                    | 'CHIP0603'     | ''          | ''            | ''        
 '64.9K'      | '1%'      | '1/10W'  | '0603LF'  | 'EMPTY'  | 'TMP_QCS36493F913'(!)   = 'End of Design' | 'Comp-Approve'     | 'CS36493F913'           |'R0603'| '(SMR0603AW)'                  | '64.9K'   | '1%'    | '1/10W'  | 'IO'       | '64.9Kohm 0603'                                    | 'CHIP0603'     | ''          | ''            | ''        
 '107K'       | '1%'      | '1/10W'  | '0603LF'  | 'CHIP'   | 'TMP_QCS41073F918'(!)   = 'End of Design' | 'Comp-Approve'     | 'CS41073F918'           |'R0603'| '(SMR0603AW)'                  | '107K'    | '1%'    | '1/10W'  | 'DISCRETE' | '107Kohm 0603'                                     | 'CHIP0603'     | ''          | ''            | ''        
 '107K'       | '1%'      | '1/10W'  | '0603LF'  | 'EMPTY'  | 'TMP_QCS41073F918'(!)   = 'End of Design' | 'Comp-Approve'     | 'CS41073F918'           |'R0603'| '(SMR0603AW)'                  | '107K'    | '1%'    | '1/10W'  | 'IO'       | '107Kohm 0603'                                     | 'CHIP0603'     | ''          | ''            | ''        
 '3.6K'       | '1%'      | '1/10W'  | '0603LF'  | 'CHIP'   | 'TMP_QCS23603F910'(!)   = ''              | ''                 | 'CS23603F910'           |'R0603'| '(SMR0603AW)'                  | '3.6K'    | '1%'    | '1/10W'  | 'DISCRETE' | '3.6Kohm 0603'                                     | 'CHIP0603'     | ''          | ''            | ''        
 '3.6K'       | '1%'      | '1/10W'  | '0603LF'  | 'EMPTY'  | 'TMP_QCS23603F910'(!)   = ''              | ''                 | 'CS23603F910'           |'R0603'| '(SMR0603AW)'                  | '3.6K'    | '1%'    | '1/10W'  | 'IO'       | '3.6Kohm 0603'                                     | 'CHIP0603'     | ''          | ''            | ''        
 '169'        | '1%'      | '1/10W'  | '0603LF'  | 'CHIP'   | 'TMP_QCS11693F913'(!)   = 'End of Design' | 'Comp-Approve'     | 'CS11693F913'           |'R0603'| '(SMR0603AW)'                  | '169'     | '1%'    | '1/10W'  | 'DISCRETE' | '169ohm 0603'                                      | 'CHIP0603'     | ''          | ''            | ''        
 '169'        | '1%'      | '1/10W'  | '0603LF'  | 'EMPTY'  | 'TMP_QCS11693F913'(!)   = 'End of Design' | 'Comp-Approve'     | 'CS11693F913'           |'R0603'| '(SMR0603AW)'                  | '169'     | '1%'    | '1/10W'  | 'IO'       | '169ohm 0603'                                      | 'CHIP0603'     | ''          | ''            | ''        
 '210'        | '1%'      | '1/10W'  | '0603LF'  | 'CHIP'   | 'TMP_QCS12103F909'(!)   = ''              | ''                 | 'CS12103F909'           |'R0603'| '(SMR0603AW)'                  | '210'     | '1%'    | '1/10W'  | 'DISCRETE' | '210ohm 0603'                                      | 'CHIP0603'     | ''          | ''            | ''        
 '210'        | '1%'      | '1/10W'  | '0603LF'  | 'EMPTY'  | 'TMP_QCS12103F909'(!)   = ''              | ''                 | 'CS12103F909'           |'R0603'| '(SMR0603AW)'                  | '210'     | '1%'    | '1/10W'  | 'IO'       | '210ohm 0603'                                      | 'CHIP0603'     | ''          | ''            | ''        
 '9.53K'      | '1%'      | '1/10W'  | '0603LF'  | 'CHIP'   | 'TMP_QCS29533F908'(!)   = ''              | ''                 | 'CS29533F908'           |'R0603'| '(SMR0603AW)'                  | '9.53K'   | '1%'    | '1/10W'  | 'DISCRETE' | '9.53Kohm 0603'                                    | 'CHIP0603'     | ''          | ''            | ''        
 '9.53K'      | '1%'      | '1/10W'  | '0603LF'  | 'EMPTY'  | 'TMP_QCS29533F908'(!)   = ''              | ''                 | 'CS29533F908'           |'R0603'| '(SMR0603AW)'                  | '9.53K'   | '1%'    | '1/10W'  | 'IO'       | '9.53Kohm 0603'                                    | 'CHIP0603'     | ''          | ''            | ''        
 '787'        | '1%'      | '1/10W'  | '0603'    | 'CHIP'   | 'TMP_QCS17873F900'(!)   = ''              | ''                 | 'CS17873F900'           |'R0603'| '(SMR0603AW)'                  | '787'     | '1%'    | '1/10W'  | 'DISCRETE' | '787ohm 0603'                                      | 'CHIP0603'     | ''          | ''            | ''        
 '787'        | '1%'      | '1/10W'  | '0603'    | 'EMPTY'  | 'TMP_QCS17873F900'(!)   = ''              | ''                 | 'CS17873F900'           |'R0603'| '(SMR0603AW)'                  | '787'     | '1%'    | '1/10W'  | 'IO'       | '787ohm 0603'                                      | 'CHIP0603'     | ''          | ''            | ''        
 '30.1'       | '1%'      | '1/10W'  | '0603LF'  | 'CHIP'   | 'TMP_QCS03013F919'(!)   = ''              | ''                 | 'CS03013F919'           |'R0603'| '(SMR0603AW)'                  | '30.1'    | '1%'    | '1/10W'  | 'DISCRETE' | '30.1ohm 0603'                                     | 'CHIP0603'     | ''          | ''            | ''        
 '30.1'       | '1%'      | '1/10W'  | '0603LF'  | 'EMPTY'  | 'TMP_QCS03013F919'(!)   = ''              | ''                 | 'CS03013F919'           |'R0603'| '(SMR0603AW)'                  | '30.1'    | '1%'    | '1/10W'  | 'IO'       | '30.1ohm 0603'                                     | 'CHIP0603'     | ''          | ''            | ''        
 '2.2'        | '1%'      | '1/10W'  | '0603LF'  | 'CHIP'   | 'TMP_QCS-2203F911'(!)   = ''              | ''                 | 'CS-2203F911'           |'R0603'| '(SMR0603AW)'                  | '2.2'     | '1%'    | '1/10W'  | 'DISCRETE' | '2.2ohm 0603'                                      | 'CHIP0603'     | ''          | ''            | ''        
 '2.2'        | '1%'      | '1/10W'  | '0603LF'  | 'EMPTY'  | 'TMP_QCS-2203F911'(!)   = ''              | ''                 | 'CS-2203F911'           |'R0603'| '(SMR0603AW)'                  | '2.2'     | '1%'    | '1/10W'  | 'IO'       | '2.2ohm 0603'                                      | 'CHIP0603'     | ''          | ''            | ''        
 '32.4K'      | '1%'      | '1/10W'  | '0603LF'  | 'CHIP'   | 'TMP_QCS33243F915'(!)   = 'End of Design' | 'Comp-Approve'     | 'CS33243F915'           |'R0603'| '(SMR0603AW)'                  | '32.4K'   | '1%'    | '1/10W'  | 'DISCRETE' | '32.4Kohm 0603'                                    | 'CHIP0603'     | ''          | ''            | ''        
 '32.4K'      | '1%'      | '1/10W'  | '0603LF'  | 'EMPTY'  | 'TMP_QCS33243F915'(!)   = 'End of Design' | 'Comp-Approve'     | 'CS33243F915'           |'R0603'| '(SMR0603AW)'                  | '32.4K'   | '1%'    | '1/10W'  | 'IO'       | '32.4Kohm 0603'                                    | 'CHIP0603'     | ''          | ''            | ''        
 '1.87K'      | '1%'      | '1/16W'  | '0402LF'  | 'CHIP'   | 'TMP_QCS21872FB17'(!)   = 'End of Design' | 'Comp-Approve'     | 'CS21872FB17'           |'R0402'| '(R0402-0201)'                 | '1.87K'   | '1%'    | '1/16W'  | 'DISCRETE' | '1.87Kohm 0402'                                    | 'CHIP0402'     | ''          | ''            | ''        
 '1.87K'      | '1%'      | '1/16W'  | '0402LF'  | 'EMPTY'  | 'TMP_QCS21872FB17'(!)   = 'End of Design' | 'Comp-Approve'     | 'CS21872FB17'           |'R0402'| '(R0402-0201)'                 | '1.87K'   | '1%'    | '1/16W'  | 'IO'       | '1.87Kohm 0402'                                    | 'CHIP0402'     | ''          | ''            | ''        
 '18K'        | '1%'      | '1/16W'  | '0402LF'  | 'CHIP'   | 'TMP_QCS31802FB10'(!)   = 'End of Design' | 'Comp-Approve'     | 'CS31802FB10'           |'R0402'| '(R0402-0201)'                 | '18K'     | '1%'    | '1/16W'  | 'DISCRETE' | '18Kohm 0402'                                      | 'CHIP0402'     | ''          | ''            | ''        
 '18K'        | '1%'      | '1/16W'  | '0402LF'  | 'EMPTY'  | 'TMP_QCS31802FB10'(!)   = 'End of Design' | 'Comp-Approve'     | 'CS31802FB10'           |'R0402'| '(R0402-0201)'                 | '18K'     | '1%'    | '1/16W'  | 'IO'       | '18Kohm 0402'                                      | 'CHIP0402'     | ''          | ''            | ''        
 '17.8K'      | '1%'      | '1/16W'  | '0402LF'  | 'CHIP'   | 'TMP_QCS31782FB10'(!)   = 'End of Design' | 'Comp-Approve'     | 'CS31782FB10'           |'R0402'| '(R0402-0201)'                 | '17.8K'   | '1%'    | '1/16W'  | 'DISCRETE' | '17.8Kohm 0402'                                    | 'CHIP0402'     | ''          | ''            | ''        
 '17.8K'      | '1%'      | '1/16W'  | '0402LF'  | 'EMPTY'  | 'TMP_QCS31782FB10'(!)   = 'End of Design' | 'Comp-Approve'     | 'CS31782FB10'           |'R0402'| '(R0402-0201)'                 | '17.8K'   | '1%'    | '1/16W'  | 'IO'       | '17.8Kohm 0402'                                    | 'CHIP0402'     | ''          | ''            | ''        
 '4.53K'      | '1%'      | '1/16W'  | '0402LF'  | 'CHIP'   | 'TMP_QCS24532FB08'(!)   = 'End of Design' | 'Comp-Approve'     | 'CS24532FB08'           |'R0402'| '(R0402-0201)'                 | '4.53K'   | '1%'    | '1/16W'  | 'DISCRETE' | '4.53Kohm 0402'                                    | 'CHIP0402'     | ''          | ''            | ''        
 '4.53K'      | '1%'      | '1/16W'  | '0402LF'  | 'EMPTY'  | 'TMP_QCS24532FB08'(!)   = 'End of Design' | 'Comp-Approve'     | 'CS24532FB08'           |'R0402'| '(R0402-0201)'                 | '4.53K'   | '1%'    | '1/16W'  | 'IO'       | '4.53Kohm 0402'                                    | 'CHIP0402'     | ''          | ''            | ''        
 '715'        | '1%'      | '1/16W'  | '0402LF'  | 'CHIP'   | 'TMP_QCS17152FB17'(!)   = 'End of Design' | 'Comp-Approve'     | 'CS17152FB17'           |'R0402'| '(R0402-0201)'                 | '715'     | '1%'    | '1/16W'  | 'DISCRETE' | '715ohm 0402'                                      | 'CHIP0402'     | ''          | ''            | ''        
 '715'        | '1%'      | '1/16W'  | '0402LF'  | 'EMPTY'  | 'TMP_QCS17152FB17'(!)   = 'End of Design' | 'Comp-Approve'     | 'CS17152FB17'           |'R0402'| '(R0402-0201)'                 | '715'     | '1%'    | '1/16W'  | 'IO'       | '715ohm 0402'                                      | 'CHIP0402'     | ''          | ''            | ''        
 '1.15K'      | '1%'      | '1/16W'  | '0402LF'  | 'CHIP'   | 'TMP_QCS21152FB12'(!)   = 'End of Design' | 'Comp-Approve'     | 'CS21152FB12'           |'R0402'| '(R0402-0201)'                 | '1.15K'   | '1%'    | '1/16W'  | 'DISCRETE' | '1.15Kohm 0402'                                    | 'CHIP0402'     | ''          | ''            | ''        
 '1.15K'      | '1%'      | '1/16W'  | '0402LF'  | 'EMPTY'  | 'TMP_QCS21152FB12'(!)   = 'End of Design' | 'Comp-Approve'     | 'CS21152FB12'           |'R0402'| '(R0402-0201)'                 | '1.15K'   | '1%'    | '1/16W'  | 'IO'       | '1.15Kohm 0402'                                    | 'CHIP0402'     | ''          | ''            | ''        
 '68.1'       | '1%'      | '1/4W'   | '1206LF'  | 'CHIP'   | 'TMP_QCS06816F200'(!)   = ''              | ''                 | 'CS06816F200'           |'R1206'| '(SMR1206AW)'                  | '68.1'    | '1%'    | '1/4W'   | 'DISCRETE' | '68.1ohm 1206'                                     | 'CHIP1206'     | ''          | ''            | ''        
 '68.1'       | '1%'      | '1/4W'   | '1206LF'  | 'EMPTY'  | 'TMP_QCS06816F200'(!)   = ''              | ''                 | 'CS06816F200'           |'R1206'| '(SMR1206AW)'                  | '68.1'    | '1%'    | '1/4W'   | 'IO'       | '68.1ohm 1206'                                     | 'CHIP1206'     | ''          | ''            | ''        
 '549'        | '1%'      | '1/4W'   | '1206LF'  | 'CHIP'   | 'TMP_QCS15496F200'(!)   = ''              | ''                 | 'CS15496F200'           |'R1206'| '(SMR1206AW)'                  | '549'     | '1%'    | '1/4W'   | 'DISCRETE' | '549ohm 1206'                                      | 'CHIP1206'     | ''          | ''            | ''        
 '549'        | '1%'      | '1/4W'   | '1206LF'  | 'EMPTY'  | 'TMP_QCS15496F200'(!)   = ''              | ''                 | 'CS15496F200'           |'R1206'| '(SMR1206AW)'                  | '549'     | '1%'    | '1/4W'   | 'IO'       | '549ohm 1206'                                      | 'CHIP1206'     | ''          | ''            | ''        
 '649'        | '1%'      | '1/4W'   | '1206LF'  | 'CHIP'   | 'TMP_QCS16496F200'(!)   = ''              | ''                 | 'CS16496F200'           |'R1206'| '(SMR1206AW)'                  | '649'     | '1%'    | '1/4W'   | 'DISCRETE' | '649ohm 1206'                                      | 'CHIP1206'     | ''          | ''            | ''        
 '649'        | '1%'      | '1/4W'   | '1206LF'  | 'EMPTY'  | 'TMP_QCS16496F200'(!)   = ''              | ''                 | 'CS16496F200'           |'R1206'| '(SMR1206AW)'                  | '649'     | '1%'    | '1/4W'   | 'IO'       | '649ohm 1206'                                      | 'CHIP1206'     | ''          | ''            | ''        
 '5.49K'      | '1%'      | '1/4W'   | '1206LF'  | 'CHIP'   | 'TMP_QCS25496F200'(!)   = ''              | ''                 | 'CS25496F200'           |'R1206'| '(SMR1206AW)'                  | '5.49K'   | '1%'    | '1/4W'   | 'DISCRETE' | '5.49Kohm 1206'                                    | 'CHIP1206'     | ''          | ''            | ''        
 '5.49K'      | '1%'      | '1/4W'   | '1206LF'  | 'EMPTY'  | 'TMP_QCS25496F200'(!)   = ''              | ''                 | 'CS25496F200'           |'R1206'| '(SMR1206AW)'                  | '5.49K'   | '1%'    | '1/4W'   | 'IO'       | '5.49Kohm 1206'                                    | 'CHIP1206'     | ''          | ''            | ''        
 '6.04K'      | '1%'      | '1/4W'   | '1206LF'  | 'CHIP'   | 'TMP_QCS26046F200'(!)   = ''              | ''                 | 'CS26046F200'           |'R1206'| '(SMR1206AW)'                  | '6.04K'   | '1%'    | '1/4W'   | 'DISCRETE' | '6.04Kohm 1206'                                    | 'CHIP1206'     | ''          | ''            | ''        
 '6.04K'      | '1%'      | '1/4W'   | '1206LF'  | 'EMPTY'  | 'TMP_QCS26046F200'(!)   = ''              | ''                 | 'CS26046F200'           |'R1206'| '(SMR1206AW)'                  | '6.04K'   | '1%'    | '1/4W'   | 'IO'       | '6.04Kohm 1206'                                    | 'CHIP1206'     | ''          | ''            | ''        
 '9.53K'      | '1%'      | '1/4W'   | '1206LF'  | 'CHIP'   | 'TMP_QCS29536F200'(!)   = ''              | ''                 | 'CS29536F200'           |'R1206'| '(SMR1206AW)'                  | '9.53K'   | '1%'    | '1/4W'   | 'DISCRETE' | '9.53Kohm 1206'                                    | 'CHIP1206'     | ''          | ''            | ''        
 '9.53K'      | '1%'      | '1/4W'   | '1206LF'  | 'EMPTY'  | 'TMP_QCS29536F200'(!)   = ''              | ''                 | 'CS29536F200'           |'R1206'| '(SMR1206AW)'                  | '9.53K'   | '1%'    | '1/4W'   | 'IO'       | '9.53Kohm 1206'                                    | 'CHIP1206'     | ''          | ''            | ''        
 '63.4K'      | '1%'      | '1/4W'   | '1206LF'  | 'CHIP'   | 'TMP_QCS36346F200'(!)   = ''              | ''                 | 'CS36346F200'           |'R1206'| '(SMR1206AW)'                  | '63.4K'   | '1%'    | '1/4W'   | 'DISCRETE' | '63.4Kohm 1206'                                    | 'CHIP1206'     | ''          | ''            | ''        
 '63.4K'      | '1%'      | '1/4W'   | '1206LF'  | 'EMPTY'  | 'TMP_QCS36346F200'(!)   = ''              | ''                 | 'CS36346F200'           |'R1206'| '(SMR1206AW)'                  | '63.4K'   | '1%'    | '1/4W'   | 'IO'       | '63.4Kohm 1206'                                    | 'CHIP1206'     | ''          | ''            | ''        
 '0.015'      | '1%'      | '1/4W'   | '1206LF'  | 'CHIP'   | 'TMP_QCS+0156F200'(!)   = ''              | ''                 | 'CS+0156F200'           |'R1206'| '(SMR1206AW)'                  | '0.015'   | '1%'    | '1/4W'   | 'DISCRETE' | '0.015ohm 1206'                                    | 'CHIP1206'     | ''          | ''            | ''        
 '0.015'      | '1%'      | '1/4W'   | '1206LF'  | 'EMPTY'  | 'TMP_QCS+0156F200'(!)   = ''              | ''                 | 'CS+0156F200'           |'R1206'| '(SMR1206AW)'                  | '0.015'   | '1%'    | '1/4W'   | 'IO'       | '0.015ohm 1206'                                    | 'CHIP1206'     | ''          | ''            | ''        
 '0.025'      | '1%'      | '1/4W'   | '1206LF'  | 'CHIP'   | 'TMP_QCS+0256F200'(!)   = ''              | ''                 | 'CS+0256F200'           |'R1206'| '(SMR1206AW)'                  | '0.025'   | '1%'    | '1/4W'   | 'DISCRETE' | '0.025ohm 1206'                                    | 'CHIP1206'     | ''          | ''            | ''        
 '0.025'      | '1%'      | '1/4W'   | '1206LF'  | 'EMPTY'  | 'TMP_QCS+0256F200'(!)   = ''              | ''                 | 'CS+0256F200'           |'R1206'| '(SMR1206AW)'                  | '0.025'   | '1%'    | '1/4W'   | 'IO'       | '0.025ohm 1206'                                    | 'CHIP1206'     | ''          | ''            | ''        
 '5.11'       | '1%'      | '1/4W'   | '1206LF'  | 'CHIP'   | 'TMP_QCS-5116F208'(!)   = ''              | ''                 | 'CS-5116F208'           |'R1206'| '(SMR1206AW)'                  | '5.11'    | '1%'    | '1/4W'   | 'DISCRETE' | '5.11ohm 1206'                                     | 'CHIP1206'     | ''          | ''            | ''        
 '5.11'       | '1%'      | '1/4W'   | '1206LF'  | 'EMPTY'  | 'TMP_QCS-5116F208'(!)   = ''              | ''                 | 'CS-5116F208'           |'R1206'| '(SMR1206AW)'                  | '5.11'    | '1%'    | '1/4W'   | 'IO'       | '5.115ohm 1206'                                    | 'CHIP1206'     | ''          | ''            | ''        
 '22'         | '5%'      | '1/4W'   | '1206LF'  | 'CHIP'   | 'TMP_QCS02206J216'(!)   = 'End of Design' | 'Comp-Release Qty' | 'CS02206J216'           |'R1206'| '(SMR1206AW)'                  | '22'      | '5%'    | '1/4W'   | 'DISCRETE' | '22ohm 1206'                                       | 'CHIP1206'     | ''          | ''            | ''        
 '22'         | '5%'      | '1/4W'   | '1206LF'  | 'EMPTY'  | 'TMP_QCS02206J216'(!)   = 'End of Design' | 'Comp-Release Qty' | 'CS02206J216'           |'R1206'| '(SMR1206AW)'                  | '22'      | '5%'    | '1/4W'   | 'IO'       | '22ohm 1206'                                       | 'CHIP1206'     | ''          | ''            | ''        
 '53.6'       | '1%'      | '1/8W'   | '1206LF'  | 'CHIP'   | 'TMP_QCS05364FA07'(!)   = ''              | ''                 | 'CS05364FA07'           |'R1206'| '(SMR1206AW)'                  | '53.6'    | '1%'    | '1/8W'   | 'DISCRETE' | '53.6ohm 1206'                                     | 'CHIP1206'     | ''          | ''            | ''        
 '53.6'       | '1%'      | '1/8W'   | '1206LF'  | 'EMPTY'  | 'TMP_QCS05364FA07'(!)   = ''              | ''                 | 'CS05364FA07'           |'R1206'| '(SMR1206AW)'                  | '53.6'    | '1%'    | '1/8W'   | 'IO'       | '53.6ohm 1206'                                     | 'CHIP1206'     | ''          | ''            | ''        
 '2.49K'      | '1%'      | '1/8W'   | '0805LF'  | 'CHIP'   | 'TMP_QCS22494FA00'(!)   = ''              | ''                 | 'CS22494FA00'           |'R0805'| '(SMR0805AW)'                  | '2.49K'   | '1%'    | '1/8W'   | 'DISCRETE' | '2.49Kohm 0805'                                    | 'CHIP0805'     | ''          | ''            | ''        
 '2.49K'      | '1%'      | '1/8W'   | '0805LF'  | 'EMPTY'  | 'TMP_QCS22494FA00'(!)   = ''              | ''                 | 'CS22494FA00'           |'R0805'| '(SMR0805AW)'                  | '2.49K'   | '1%'    | '1/8W'   | 'IO'       | '2.49Kohm 0805'                                    | 'CHIP0805'     | ''          | ''            | ''        
 '174'        | '1%'      | '1/4W'   | '1206LF'  | 'CHIP'   | 'TMP_QCS11746F200'(!)   = ''              | ''                 | 'CS11746F200'           |'R1206'| '(SMR1206AW)'                  | '174'     | '1%'    | '1/4W'   | 'DISCRETE' | '174ohm 1206'                                      | 'CHIP1206'     | ''          | ''            | ''        
 '174'        | '1%'      | '1/4W'   | '1206LF'  | 'EMPTY'  | 'TMP_QCS11746F200'(!)   = ''              | ''                 | 'CS11746F200'           |'R1206'| '(SMR1206AW)'                  | '174'     | '1%'    | '1/4W'   | 'IO'       | '174ohm 1206'                                      | 'CHIP1206'     | ''          | ''            | ''        
 '3.16K'      | '1%'      | '1/4W'   | '1206LF'  | 'CHIP'   | 'TMP_QCS23166F200'(!)   = ''              | ''                 | 'CS23166F200'           |'R1206'| '(SMR1206AW)'                  | '3.16K'   | '1%'    | '1/4W'   | 'DISCRETE' | '3.16Kohm 1206'                                    | 'CHIP1206'     | ''          | ''            | ''        
 '3.16K'      | '1%'      | '1/4W'   | '1206LF'  | 'EMPTY'  | 'TMP_QCS23166F200'(!)   = ''              | ''                 | 'CS23166F200'           |'R1206'| '(SMR1206AW)'                  | '3.16K'   | '1%'    | '1/4W'   | 'IO'       | '3.16Kohm 1206'                                    | 'CHIP1206'     | ''          | ''            | ''        
 '3.83K'      | '1%'      | '1/4W'   | '1206LF'  | 'CHIP'   | 'TMP_QCS23836F200'(!)   = ''              | ''                 | 'CS23836F200'           |'R1206'| '(SMR1206AW)'                  | '3.83K'   | '1%'    | '1/4W'   | 'DISCRETE' | '3.83Kohm 1206'                                    | 'CHIP1206'     | ''          | ''            | ''        
 '3.83K'      | '1%'      | '1/4W'   | '1206LF'  | 'EMPTY'  | 'TMP_QCS23836F200'(!)   = ''              | ''                 | 'CS23836F200'           |'R1206'| '(SMR1206AW)'                  | '3.83K'   | '1%'    | '1/4W'   | 'IO'       | '3.83Kohm 1206'                                    | 'CHIP1206'     | ''          | ''            | ''        
 '15.4K'      | '1%'      | '1/4W'   | '1206LF'  | 'CHIP'   | 'TMP_QCS31546F200'(!)   = ''              | ''                 | 'CS31546F200'           |'R1206'| '(SMR1206AW)'                  | '15.4K'   | '1%'    | '1/4W'   | 'DISCRETE' | '15.4Kohm 1206'                                    | 'CHIP1206'     | ''          | ''            | ''        
 '15.4K'      | '1%'      | '1/4W'   | '1206LF'  | 'EMPTY'  | 'TMP_QCS31546F200'(!)   = ''              | ''                 | 'CS31546F200'           |'R1206'| '(SMR1206AW)'                  | '15.4K'   | '1%'    | '1/4W'   | 'IO'       | '15.4Kohm 1206'                                    | 'CHIP1206'     | ''          | ''            | ''        
 '20K'        | '1%'      | '1/4W'   | '1206LF'  | 'CHIP'   | 'TMP_QCS32006F200'(!)   = ''              | ''                 | 'CS32006F200'           |'R1206'| '(SMR1206AW)'                  | '20K'     | '1%'    | '1/4W'   | 'DISCRETE' | '20Kohm 1206'                                      | 'CHIP1206'     | ''          | ''            | ''        
 '20K'        | '1%'      | '1/4W'   | '1206LF'  | 'EMPTY'  | 'TMP_QCS32006F200'(!)   = ''              | ''                 | 'CS32006F200'           |'R1206'| '(SMR1206AW)'                  | '20K'     | '1%'    | '1/4W'   | 'IO'       | '20Kohm 1206'                                      | 'CHIP1206'     | ''          | ''            | ''        
 '22.1K'      | '1%'      | '1/4W'   | '1206LF'  | 'CHIP'   | 'TMP_QCS32216F200'(!)   = ''              | ''                 | 'CS32216F200'           |'R1206'| '(SMR1206AW)'                  | '22.1K'   | '1%'    | '1/4W'   | 'DISCRETE' | '22.1Kohm 1206'                                    | 'CHIP1206'     | ''          | ''            | ''        
 '22.1K'      | '1%'      | '1/4W'   | '1206LF'  | 'EMPTY'  | 'TMP_QCS32216F200'(!)   = ''              | ''                 | 'CS32216F200'           |'R1206'| '(SMR1206AW)'                  | '22.1K'   | '1%'    | '1/4W'   | 'IO'       | '22.1Kohm 1206'                                    | 'CHIP1206'     | ''          | ''            | ''        
 '1.5M'       | '1%'      | '1/4W'   | '1206LF'  | 'CHIP'   | 'TMP_QCS51506F200'(!)   = ''              | ''                 | 'CS51506F200'           |'R1206'| '(SMR1206AW)'                  | '1.5M'    | '1%'    | '1/4W'   | 'DISCRETE' | '1.5Mohm 1206'                                     | 'CHIP1206'     | ''          | ''            | ''        
 '1.5M'       | '1%'      | '1/4W'   | '1206LF'  | 'EMPTY'  | 'TMP_QCS51506F200'(!)   = ''              | ''                 | 'CS51506F200'           |'R1206'| '(SMR1206AW)'                  | '1.5M'    | '1%'    | '1/4W'   | 'IO'       | '1.5Mohm 1206'                                     | 'CHIP1206'     | ''          | ''            | ''        
 '60.4'       | '1%'      | '1/4W'   | '1206LF'  | 'CHIP'   | 'TMP_QCS06046F200'(!)   = ''              | ''                 | 'CS06046F200'           |'R1206'| '(SMR1206AW)'                  | '60.4'    | '1%'    | '1/4W'   | 'DISCRETE' | '60.4ohm 1206'                                     | 'CHIP1206'     | ''          | ''            | ''        
 '60.4'       | '1%'      | '1/4W'   | '1206LF'  | 'EMPTY'  | 'TMP_QCS06046F200'(!)   = ''              | ''                 | 'CS06046F200'           |'R1206'| '(SMR1206AW)'                  | '60.4'    | '1%'    | '1/4W'   | 'IO'       | '60.4ohm 1206'                                     | 'CHIP1206'     | ''          | ''            | ''        
 '787'        | '1%'      | '1/4W'   | '1206LF'  | 'CHIP'   | 'TMP_QCS17876F200'(!)   = ''              | ''                 | 'CS17876F200'           |'R1206'| '(SMR1206AW)'                  | '787'     | '1%'    | '1/4W'   | 'DISCRETE' | '787ohm 1206'                                      | 'CHIP1206'     | ''          | ''            | ''        
 '787'        | '1%'      | '1/4W'   | '1206LF'  | 'EMPTY'  | 'TMP_QCS17876F200'(!)   = ''              | ''                 | 'CS17876F200'           |'R1206'| '(SMR1206AW)'                  | '787'     | '1%'    | '1/4W'   | 'IO'       | '787ohm 1206'                                      | 'CHIP1206'     | ''          | ''            | ''        
 '953'        | '1%'      | '1/4W'   | '1206LF'  | 'CHIP'   | 'TMP_QCS19536F200'(!)   = ''              | ''                 | 'CS19536F200'           |'R1206'| '(SMR1206AW)'                  | '953'     | '1%'    | '1/4W'   | 'DISCRETE' | '953ohm 1206'                                      | 'CHIP1206'     | ''          | ''            | ''        
 '953'        | '1%'      | '1/4W'   | '1206LF'  | 'EMPTY'  | 'TMP_QCS19536F200'(!)   = ''              | ''                 | 'CS19536F200'           |'R1206'| '(SMR1206AW)'                  | '953'     | '1%'    | '1/4W'   | 'IO'       | '953ohm 1206'                                      | 'CHIP1206'     | ''          | ''            | ''        
 '1.3K'       | '1%'      | '1/4W'   | '1206LF'  | 'CHIP'   | 'TMP_QCS21306F200'(!)   = ''              | ''                 | 'CS21306F200'           |'R1206'| '(SMR1206AW)'                  | '1.3K'    | '1%'    | '1/4W'   | 'DISCRETE' | '1.3Kohm 1206'                                     | 'CHIP1206'     | ''          | ''            | ''        
 '1.3K'       | '1%'      | '1/4W'   | '1206LF'  | 'EMPTY'  | 'TMP_QCS21306F200'(!)   = ''              | ''                 | 'CS21306F200'           |'R1206'| '(SMR1206AW)'                  | '1.3K'    | '1%'    | '1/4W'   | 'IO'       | '1.3Kohm 1206'                                     | 'CHIP1206'     | ''          | ''            | ''        
 '1.82K'      | '1%'      | '1/4W'   | '1206LF'  | 'CHIP'   | 'TMP_QCS21826F200'(!)   = ''              | ''                 | 'CS21826F200'           |'R1206'| '(SMR1206AW)'                  | '1.82K'   | '1%'    | '1/4W'   | 'DISCRETE' | '1.82Kohm 1206'                                    | 'CHIP1206'     | ''          | ''            | ''        
 '1.82K'      | '1%'      | '1/4W'   | '1206LF'  | 'EMPTY'  | 'TMP_QCS21826F200'(!)   = ''              | ''                 | 'CS21826F200'           |'R1206'| '(SMR1206AW)'                  | '1.82K'   | '1%'    | '1/4W'   | 'IO'       | '1.82Kohm 1206'                                    | 'CHIP1206'     | ''          | ''            | ''        
 '4.7K'       | '1%'      | '1/4W'   | '1206LF'  | 'CHIP'   | 'TMP_QCS24706F200'(!)   = 'End of Design' | 'Comp-Approve'     | 'CS24706F200'           |'R1206'| '(SMR1206AW)'                  | '4.7K'    | '1%'    | '1/4W'   | 'DISCRETE' | '4.7Kohm 1206'                                     | 'CHIP1206'     | ''          | ''            | ''        
 '4.7K'       | '1%'      | '1/4W'   | '1206LF'  | 'EMPTY'  | 'TMP_QCS24706F200'(!)   = 'End of Design' | 'Comp-Approve'     | 'CS24706F200'           |'R1206'| '(SMR1206AW)'                  | '4.7K'    | '1%'    | '1/4W'   | 'IO'       | '4.7Kohm 1206'                                     | 'CHIP1206'     | ''          | ''            | ''        
 '17.4K'      | '1%'      | '1/4W'   | '1206LF'  | 'CHIP'   | 'TMP_QCS31746F200'(!)   = 'End of Design' | 'Comp-Approve'     | 'CS24706F200'           |'R1206'| '(SMR1206AW)'                  | '17.4K'   | '1%'    | '1/4W'   | 'DISCRETE' | '17.4Kohm 1206'                                    | 'CHIP1206'     | ''          | ''            | ''        
 '17.4K'      | '1%'      | '1/4W'   | '1206LF'  | 'EMPTY'  | 'TMP_QCS31746F200'(!)   = 'End of Design' | 'Comp-Approve'     | 'CS24706F200'           |'R1206'| '(SMR1206AW)'                  | '17.4K'   | '1%'    | '1/4W'   | 'IO'       | '17.4Kohm 1206'                                    | 'CHIP1206'     | ''          | ''            | ''        
 '130K'       | '1%'      | '1/10W'  | '0603LF'  | 'CHIP'   | 'TMP_QCS41303F917'(!)   = ''              | ''                 | 'CS41303F917'           |'R0603'| '(SMR0603AW)'                  | '130K'    | '1%'    | '1/10W'  | 'DISCRETE' | '130Kohm 0603'                                     | 'CHIP0603'     | ''          | ''            | ''        
 '130K'       | '1%'      | '1/10W'  | '0603LF'  | 'EMPTY'  | 'TMP_QCS41303F917'(!)   = ''              | ''                 | 'CS41303F917'           |'R0603'| '(SMR0603AW)'                  | '130K'    | '1%'    | '1/10W'  | 'IO'       | '130Kohm 0603'                                     | 'CHIP0603'     | ''          | ''            | ''        
 '12K'        | '1%'      | '1/16W'  | '0402LF'  | 'CHIP'   | 'TMP_QCS31202FB15'(!)   = 'End of Design' | 'Comp-Approve'     | 'CS31202FB15'           |'R0402'| '(R0402-0201)'                 | '12K'     | '1%'    | '1/16W'  | 'DISCRETE' | '12Kohm 0402'                                      | 'CHIP0402'     | ''          | ''            | ''        
 '12K'        | '1%'      | '1/16W'  | '0402LF'  | 'EMPTY'  | 'TMP_QCS31202FB15'(!)   = 'End of Design' | 'Comp-Approve'     | 'CS31202FB15'           |'R0402'| '(R0402-0201)'                 | '12K'     | '1%'    | '1/16W'  | 'IO'       | '12Kohm 0402'                                      | 'CHIP0402'     | ''          | ''            | ''        
 '68.1K'      | '1%'      | '1/4W'   | '1206LF'  | 'CHIP'   | 'TMP_QCS36816F200'(!)   = ''              | ''                 | 'CS36816F200'           |'R1206'| '(SMR1206AW)'                  | '68.1K'   | '1%'    | '1/4W'   | 'DISCRETE' | '68.1Kohm 1206'                                    | 'CHIP1206'     | ''          | ''            | ''        
 '68.1K'      | '1%'      | '1/4W'   | '1206LF'  | 'EMPTY'  | 'TMP_QCS36816F200'(!)   = ''              | ''                 | 'CS36816F200'           |'R1206'| '(SMR1206AW)'                  | '68.1K'   | '1%'    | '1/4W'   | 'IO'       | '68.1Kohm 1206'                                    | 'CHIP1206'     | ''          | ''            | ''        
 '1'          | '5%'      | '1/10W'  | '0603LF'  | 'CHIP'   | 'TMP_QCS-1003J913'(!)   = ''              | ''                 | 'CS-1003J913'           |'R0603'| '(SMR0603AW)'                  | '1'       | '5%'    | '1/10W'  | 'DISCRETE' | '1ohm 0603'                                        | 'CHIP0603'     | ''          | ''            | ''        
 '1'          | '5%'      | '1/10W'  | '0603LF'  | 'EMPTY'  | 'TMP_QCS-1003J913'(!)   = ''              | ''                 | 'CS-1003J913'           |'R0603'| '(SMR0603AW)'                  | '1'       | '5%'    | '1/10W'  | 'IO'       | '1ohm 0603'                                        | 'CHIP0603'     | ''          | ''            | ''        
 '10K'        | '1%'      | '1/4W'   | '1206LF'  | 'CHIP'   | 'TMP_QCS31006F200'(!)   = ''              | ''                 | 'CS31006F200'           |'R1206'| '(SMR1206AW)'                  | '10K'     | '1%'    | '1/4W'   | 'DISCRETE' | '10Kohm 1206'                                      | 'CHIP1206'     | ''          | ''            | ''        
 '10K'        | '1%'      | '1/4W'   | '1206LF'  | 'EMPTY'  | 'TMP_QCS31006F200'(!)   = ''              | ''                 | 'CS31006F200'           |'R1206'| '(SMR1206AW)'                  | '10K'     | '1%'    | '1/4W'   | 'IO'       | '10Kohm 1206'                                      | 'CHIP1206'     | ''          | ''            | ''        
 '8.66K'      | '1%'      | '1/4W'   | '1206LF'  | 'CHIP'   | 'TMP_QCS28666F200'(!)   = ''              | ''                 | 'CS28666F200'           |'R1206'| '(SMR1206AW)'                  | '8.66K'   | '1%'    | '1/4W'   | 'DISCRETE' | '8.66Kohm 1206'                                    | 'CHIP1206'     | ''          | ''            | ''        
 '8.66K'      | '1%'      | '1/4W'   | '1206LF'  | 'EMPTY'  | 'TMP_QCS28666F200'(!)   = ''              | ''                 | 'CS28666F200'           |'R1206'| '(SMR1206AW)'                  | '8.66K'   | '1%'    | '1/4W'   | 'IO'       | '8.66Kohm 1206'                                    | 'CHIP1206'     | ''          | ''            | ''        
 '7.15K'      | '1%'      | '1/4W'   | '1206LF'  | 'CHIP'   | 'TMP_QCS27156F200'(!)   = ''              | ''                 | 'CS27156F200'           |'R1206'| '(SMR1206AW)'                  | '7.15K'   | '1%'    | '1/4W'   | 'DISCRETE' | '7.15Kohm 1206'                                    | 'CHIP1206'     | ''          | ''            | ''        
 '7.15K'      | '1%'      | '1/4W'   | '1206LF'  | 'EMPTY'  | 'TMP_QCS27156F200'(!)   = ''              | ''                 | 'CS27156F200'           |'R1206'| '(SMR1206AW)'                  | '7.15K'   | '1%'    | '1/4W'   | 'IO'       | '7.15Kohm 1206'                                    | 'CHIP1206'     | ''          | ''            | ''        
 '2.15K'      | '1%'      | '1/4W'   | '1206LF'  | 'CHIP'   | 'TMP_QCS22156F200'(!)   = ''              | ''                 | 'CS22156F200'           |'R1206'| '(SMR1206AW)'                  | '2.15K'   | '1%'    | '1/4W'   | 'DISCRETE' | '2.15Kohm 1206'                                    | 'CHIP1206'     | ''          | ''            | ''        
 '2.15K'      | '1%'      | '1/4W'   | '1206LF'  | 'EMPTY'  | 'TMP_QCS22156F200'(!)   = ''              | ''                 | 'CS22156F200'           |'R1206'| '(SMR1206AW)'                  | '2.15K'   | '1%'    | '1/4W'   | 'IO'       | '2.15Kohm 1206'                                    | 'CHIP1206'     | ''          | ''            | ''        
 '4.32K'      | '1%'      | '1/4W'   | '1206LF'  | 'CHIP'   | 'TMP_QCS24326F200'(!)   = ''              | ''                 | 'CS24326F200'           |'R1206'| '(SMR1206AW)'                  | '4.32K'   | '1%'    | '1/4W'   | 'DISCRETE' | '4.32Kohm 1206'                                    | 'CHIP1206'     | ''          | ''            | ''        
 '4.32K'      | '1%'      | '1/4W'   | '1206LF'  | 'EMPTY'  | 'TMP_QCS24326F200'(!)   = ''              | ''                 | 'CS24326F200'           |'R1206'| '(SMR1206AW)'                  | '4.32K'   | '1%'    | '1/4W'   | 'IO'       | '4.32Kohm 1206'                                    | 'CHIP1206'     | ''          | ''            | ''        
 '5.9K'       | '1%'      | '1/4W'   | '1206LF'  | 'CHIP'   | 'TMP_QCS25906F200'(!)   = ''              | ''                 | 'CS25906F200'           |'R1206'| '(SMR1206AW)'                  | '5.9K'    | '1%'    | '1/4W'   | 'DISCRETE' | '5.9Kohm 1206'                                     | 'CHIP1206'     | ''          | ''            | ''        
 '5.9K'       | '1%'      | '1/4W'   | '1206LF'  | 'EMPTY'  | 'TMP_QCS25906F200'(!)   = ''              | ''                 | 'CS25906F200'           |'R1206'| '(SMR1206AW)'                  | '5.9K'    | '1%'    | '1/4W'   | 'IO'       | '5.9Kohm 1206'                                     | 'CHIP1206'     | ''          | ''            | ''        
 '243'        | '1%'      | '1/4W'   | '1206LF'  | 'CHIP'   | 'TMP_QCS12436F200'(!)   = ''              | ''                 | 'CS12436F200'           |'R1206'| '(SMR1206AW)'                  | '243'     | '1%'    | '1/4W'   | 'DISCRETE' | '243ohm 1206'                                      | 'CHIP1206'     | ''          | ''            | ''        
 '243'        | '1%'      | '1/4W'   | '1206LF'  | 'EMPTY'  | 'TMP_QCS12436F200'(!)   = ''              | ''                 | 'CS12436F200'           |'R1206'| '(SMR1206AW)'                  | '243'     | '1%'    | '1/4W'   | 'IO'       | '243ohm 1206'                                      | 'CHIP1206'     | ''          | ''            | ''        
 '0.020'      | '1%'      | '2W'     | '2512LF'  | 'CHIP'   | 'TMP_QCS+020AFR00'(!)   = ''              | ''                 | 'CS+020AFR00'           |'R2512'| '(SMR2512AW)'                  | '0.020'   | '1%'    | '2W'     | 'DISCRETE' | '0.020ohm 2512'                                    | 'CHIP2512'     | ''          | ''            | ''        
 '0.020'      | '1%'      | '2W'     | '2512LF'  | 'EMPTY'  | 'TMP_QCS+020AFR00'(!)   = ''              | ''                 | 'CS+020AFR00'           |'R2512'| '(SMR2512AW)'                  | '0.020'   | '1%'    | '2W'     | 'IO'       | '0.020ohm 2512'                                    | 'CHIP2512'     | ''          | ''            | ''        
 '8.2K'       | '1%'      | '1/4W'   | '1206LF'  | 'CHIP'   | 'TMP-C_T2I_0912_ALEX_2'(!) = ''              | ''                 | 'TMP-C_T2I_0912_ALEX_2' |'R1206'| '(SMR1206AW)'                  | '8.2K'    | '1%'    | '1/4W'   | 'DISCRETE' | '8.2Kohm 1206'                                     | 'CHIP1206'     | ''          | ''            | ''        
 '8.2K'       | '1%'      | '1/4W'   | '1206LF'  | 'EMPTY'  | 'TMP-C_T2I_0912_ALEX_2'(!) = ''              | ''                 | 'TMP-C_T2I_0912_ALEX_2' |'R1206'| '(SMR1206AW)'                  | '8.2K'    | '1%'    | '1/4W'   | 'IO'       | '8.2Kohm 1206'                                     | 'CHIP1206'     | ''          | ''            | ''        
 '48.7k'      | '1%'      | '1/4W'   | '1206LF'  | 'CHIP'   | 'TMP-C_T2I_0912_ALEX_3'(!) = ''              | ''                 | 'TMP-C_T2I_0912_ALEX_3' |'R1206'| '(SMR1206AW)'                  | '48.7k'   | '1%'    | '1/4W'   | 'DISCRETE' | '48.7kohm 1206'                                    | 'CHIP1206'     | ''          | ''            | ''        
 '48.7k'      | '1%'      | '1/4W'   | '1206LF'  | 'EMPTY'  | 'TMP-C_T2I_0912_ALEX_3'(!) = ''              | ''                 | 'TMP-C_T2I_0912_ALEX_3' |'R1206'| '(SMR1206AW)'                  | '48.7k'   | '1%'    | '1/4W'   | 'IO'       | '48.7kohm 1206'                                    | 'CHIP1206'     | ''          | ''            | ''        
 '3.4K'       | '1%'      | '1/4W'   | '1206LF'  | 'CHIP'   | 'TMP-C_T2I_0912_ALEX_4'(!) = ''              | ''                 | 'TMP-C_T2I_0912_ALEX_4' |'R1206'| '(SMR1206AW)'                  | '3.4K'    | '1%'    | '1/4W'   | 'DISCRETE' | '3.4Kohm 1206'                                     | 'CHIP1206'     | ''          | ''            | ''        
 '3.4K'       | '1%'      | '1/4W'   | '1206LF'  | 'EMPTY'  | 'TMP-C_T2I_0912_ALEX_4'(!) = ''              | ''                 | 'TMP-C_T2I_0912_ALEX_4' |'R1206'| '(SMR1206AW)'                  | '3.4K'    | '1%'    | '1/4W'   | 'IO'       | '3.4Kohm 1206'                                     | 'CHIP1206'     | ''          | ''            | ''        
 '3.3K'       | '1%'      | '1/4W'   | '1206LF'  | 'CHIP'   | 'TMP-C_T2I_0912_ALEX_5'(!) = ''              | ''                 | 'TMP-C_T2I_0912_ALEX_5' |'R1206'| '(SMR1206AW)'                  | '3.3K'    | '1%'    | '1/4W'   | 'DISCRETE' | '3.3Kohm 1206'                                     | 'CHIP1206'     | ''          | ''            | ''        
 '3.3K'       | '1%'      | '1/4W'   | '1206LF'  | 'EMPTY'  | 'TMP-C_T2I_0912_ALEX_5'(!) = ''              | ''                 | 'TMP-C_T2I_0912_ALEX_5' |'R1206'| '(SMR1206AW)'                  | '3.3K'    | '1%'    | '1/4W'   | 'IO'       | '3.3Kohm 1206'                                     | 'CHIP1206'     | ''          | ''            | ''        
 '6.65K'      | '1%'      | '1/4W'   | '1206LF'  | 'CHIP'   | 'TMP-C_T2I_0912_ALEX_6'(!) = ''              | ''                 | 'TMP-C_T2I_0912_ALEX_6' |'R1206'| '(SMR1206AW)'                  | '6.65K'   | '1%'    | '1/4W'   | 'DISCRETE' | '6.65Kohm 1206'                                    | 'CHIP1206'     | ''          | ''            | ''        
 '6.65K'      | '1%'      | '1/4W'   | '1206LF'  | 'EMPTY'  | 'TMP-C_T2I_0912_ALEX_6'(!) = ''              | ''                 | 'TMP-C_T2I_0912_ALEX_6' |'R1206'| '(SMR1206AW)'                  | '6.65K'   | '1%'    | '1/4W'   | 'IO'       | '6.65Kohm 1206'                                    | 'CHIP1206'     | ''          | ''            | ''        
 '2K'         | '1%'      | '1/4W'   | '1206LF'  | 'CHIP'   | 'TMP_QCS22006F200'(!)   = ''              | ''                 | 'CS22006F200'           |'R1206'| '(SMR1206AW)'                  | '2K'      | '1%'    | '1/4W'   | 'DISCRETE' | '2Kohm 1206'                                       | 'CHIP1206'     | ''          | ''            | ''        
 '2K'         | '1%'      | '1/4W'   | '1206LF'  | 'EMPTY'  | 'TMP_QCS22006F200'(!)   = ''              | ''                 | 'CS22006F200'           |'R1206'| '(SMR1206AW)'                  | '2K'      | '1%'    | '1/4W'   | 'IO'       | '2Kohm 1206'                                       | 'CHIP1206'     | ''          | ''            | ''        
 '27'         | '1%'      | '1/4W'   | '1206LF'  | 'CHIP'   | 'TMP_QCS02706F200'(!)   = 'End of Design' | 'Comp-Approve'     | 'CS02706F200'           |'R1206'| '(SMR1206AW)'                  | '27'      | '1%'    | '1/4W'   | 'DISCRETE' | '27ohm 1206'                                       | 'CHIP1206'     | ''          | ''            | ''        
 '27'         | '1%'      | '1/4W'   | '1206LF'  | 'EMPTY'  | 'TMP_QCS02706F200'(!)   = 'End of Design' | 'Comp-Approve'     | 'CS02706F200'           |'R1206'| '(SMR1206AW)'                  | '27'      | '1%'    | '1/4W'   | 'IO'       | '27ohm 1206'                                       | 'CHIP1206'     | ''          | ''            | ''        
 '4.99K'      | '1%'      | '1/4W'   | '1206LF'  | 'CHIP'   | 'TMP_QCS24996F210'(!)   = ''              | ''                 | 'CS24996F210'           |'R1206'| '(SMR1206AW)'                  | '4.99K'   | '1%'    | '1/4W'   | 'DISCRETE' | '4.99Kohm 1206'                                    | 'CHIP1206'     | ''          | ''            | ''        
 '4.99K'      | '1%'      | '1/4W'   | '1206LF'  | 'EMPTY'  | 'TMP_QCS24996F210'(!)   = ''              | ''                 | 'CS24996F210'           |'R1206'| '(SMR1206AW)'                  | '4.99K'   | '1%'    | '1/4W'   | 'IO'       | '4.99Kohm 1206'                                    | 'CHIP1206'     | ''          | ''            | ''        
 '3.24K'      | '1%'      | '1/4W'   | '1206LF'  | 'CHIP'   | 'TMP_QCS23246F200'(!)   = ''              | ''                 | 'CS23246F200'           |'R1206'| '(SMR1206AW)'                  | '3.24K'   | '1%'    | '1/4W'   | 'DISCRETE' | '3.24Kohm 1206'                                    | 'CHIP1206'     | ''          | ''            | ''        
 '3.24K'      | '1%'      | '1/4W'   | '1206LF'  | 'EMPTY'  | 'TMP_QCS23246F200'(!)   = ''              | ''                 | 'CS23246F200'           |'R1206'| '(SMR1206AW)'                  | '3.24K'   | '1%'    | '1/4W'   | 'IO'       | '3.24Kohm 1206'                                    | 'CHIP1206'     | ''          | ''            | ''        
 '301K'       | '1%'      | '1/4W'   | '1206LF'  | 'CHIP'   | 'TMP_QCS43016F200'(!)   = ''              | ''                 | 'CS43016F200'           |'R1206'| '(SMR1206AW)'                  | '301K'    | '1%'    | '1/4W'   | 'DISCRETE' | '301Kohm 1206'                                     | 'CHIP1206'     | ''          | ''            | ''        
 '301K'       | '1%'      | '1/4W'   | '1206LF'  | 'EMPTY'  | 'TMP_QCS43016F200'(!)   = ''              | ''                 | 'CS43016F200'           |'R1206'| '(SMR1206AW)'                  | '301K'    | '1%'    | '1/4W'   | 'IO'       | '301Kohm 1206'                                     | 'CHIP1206'     | ''          | ''            | ''        
 '1K'         | '0.1%'    | '1/8W'   | '1206LF'  | 'CHIP'   | 'TMP_QCS21004B200'(!)   = ''              | ''                 | 'CS21004B200'           |'R1206'| '(SMR1206AW)'                  | '1K'      | '0.1%'  | '1/8W'   | 'DISCRETE' | '1Kohm 1206'                                       | 'CHIP1206'     | ''          | ''            | ''        
 '1K'         | '0.1%'    | '1/8W'   | '1206LF'  | 'EMPTY'  | 'TMP_QCS21004B200'(!)   = ''              | ''                 | 'CS21004B200'           |'R1206'| '(SMR1206AW)'                  | '1K'      | '0.1%'  | '1/8W'   | 'IO'       | '1Kohm 1206'                                       | 'CHIP1206'     | ''          | ''            | ''        
 '2K'         | '0.1%'    | '1/8W'   | '1206LF'  | 'CHIP'   | 'TMP_QCS22004B200'(!)   = ''              | ''                 | 'CS22004B200'           |'R1206'| '(SMR1206AW)'                  | '2K'      | '0.1%'  | '1/8W'   | 'DISCRETE' | '2Kohm 1206'                                       | 'CHIP1206'     | ''          | ''            | ''        
 '2K'         | '0.1%'    | '1/8W'   | '1206LF'  | 'EMPTY'  | 'TMP_QCS22004B200'(!)   = ''              | ''                 | 'CS22004B200'           |'R1206'| '(SMR1206AW)'                  | '2K'      | '0.1%'  | '1/8W'   | 'IO'       | '2Kohm 1206'                                       | 'CHIP1206'     | ''          | ''            | ''        
 '49.9K'      | '1%'      | '1/4W'   | '1206LF'  | 'CHIP'   | 'TMP_QCS34996F200'(!)   = ''              | ''                 | 'CS34996F200'           |'R1206'| '(SMR1206AW)'                  | '49.9K'   | '1%'    | '1/4W'   | 'DISCRETE' | '49.9Kohm 1206'                                    | 'CHIP1206'     | ''          | ''            | ''        
 '49.9K'      | '1%'      | '1/4W'   | '1206LF'  | 'EMPTY'  | 'TMP_QCS34996F200'(!)   = ''              | ''                 | 'CS34996F200'           |'R1206'| '(SMR1206AW)'                  | '49.9K'   | '1%'    | '1/4W'   | 'IO'       | '49.9Kohm 1206'                                    | 'CHIP1206'     | ''          | ''            | ''        
 '100K'       | '1%'      | '1/4W'   | '1206LF'  | 'CHIP'   | 'TMP_QCS41006F200'(!)   = ''              | ''                 | 'CS41006F200'           |'R1206'| '(SMR1206AW)'                  | '100K'    | '1%'    | '1/4W'   | 'DISCRETE' | '100Kohm 1206'                                     | 'CHIP1206'     | ''          | ''            | ''        
 '100K'       | '1%'      | '1/4W'   | '1206LF'  | 'EMPTY'  | 'TMP_QCS41006F200'(!)   = ''              | ''                 | 'CS41006F200'           |'R1206'| '(SMR1206AW)'                  | '100K'    | '1%'    | '1/4W'   | 'IO'       | '100Kohm 1206'                                     | 'CHIP1206'     | ''          | ''            | ''        
 '1.2M'       | '1%'      | '1/4W'   | '1206LF'  | 'CHIP'   | 'TMP_QCS51206F200'(!)   = ''              | ''                 | 'CS51206F200'           |'R1206'| '(SMR1206AW)'                  | '1.2M'    | '1%'    | '1/4W'   | 'DISCRETE' | '1.2Mohm 1206'                                     | 'CHIP1206'     | ''          | ''            | ''        
 '1.2M'       | '1%'      | '1/4W'   | '1206LF'  | 'EMPTY'  | 'TMP_QCS51206F200'(!)   = ''              | ''                 | 'CS51206F200'           |'R1206'| '(SMR1206AW)'                  | '1.2M'    | '1%'    | '1/4W'   | 'IO'       | '1.2Mohm 1206'                                     | 'CHIP1206'     | ''          | ''            | ''        
 '1.54K'      | '0.1%'    | '1/8W'   | '1206LF'  | 'CHIP'   | 'TMP_QCS21544B200'(!)   = ''              | ''                 | 'CS21544B200'           |'R1206'| '(SMR1206AW)'                  | '1.54K'   | '0.1%'  | '1/8W'   | 'DISCRETE' | '1.54Kohm 1206'                                    | 'CHIP1206'     | ''          | ''            | ''        
 '1.54K'      | '0.1%'    | '1/8W'   | '1206LF'  | 'EMPTY'  | 'TMP_QCS21544B200'(!)   = ''              | ''                 | 'CS21544B200'           |'R1206'| '(SMR1206AW)'                  | '1.54K'   | '0.1%'  | '1/8W'   | 'IO'       | '1.54Kohm 1206'                                    | 'CHIP1206'     | ''          | ''            | ''        
 '3.16K'      | '0.1%'    | '1/8W'   | '1206LF'  | 'CHIP'   | 'TMP_QCS23164B200'(!)   = ''              | ''                 | 'CS23164B200'           |'R1206'| '(SMR1206AW)'                  | '3.16K'   | '0.1%'  | '1/8W'   | 'DISCRETE' | '3.16Kohm 1206'                                    | 'CHIP1206'     | ''          | ''            | ''        
 '3.16K'      | '0.1%'    | '1/8W'   | '1206LF'  | 'EMPTY'  | 'TMP_QCS23164B200'(!)   = ''              | ''                 | 'CS23164B200'           |'R1206'| '(SMR1206AW)'                  | '3.16K'   | '0.1%'  | '1/8W'   | 'IO'       | '3.16Kohm 1206'                                    | 'CHIP1206'     | ''          | ''            | ''        
 '10K'        | '0.1%'    | '1/8W'   | '1206LF'  | 'CHIP'   | 'TMP_QCS31004B200'(!)   = ''              | ''                 | 'CS31004B200'           |'R1206'| '(SMR1206AW)'                  | '10K'     | '0.1%'  | '1/8W'   | 'DISCRETE' | '10Kohm 1206'                                      | 'CHIP1206'     | ''          | ''            | ''        
 '10K'        | '0.1%'    | '1/8W'   | '1206LF'  | 'EMPTY'  | 'TMP_QCS31004B200'(!)   = ''              | ''                 | 'CS31004B200'           |'R1206'| '(SMR1206AW)'                  | '10K'     | '0.1%'  | '1/8W'   | 'IO'       | '10Kohm 1206'                                      | 'CHIP1206'     | ''          | ''            | ''        
 '0.5'        | '1%'      | '1W'     | '2512LF'  | 'CHIP'   | 'TMP_QCS+5008FR00'(!)   = ''              | ''                 | 'CS+5008FR00'           |'R2512'| '(SMR2512AW)'                  | '0.5'     | '1%'    | '1W'     | 'DISCRETE' | '0.5ohm 2512'                                      | 'CHIP2512'     | ''          | ''            | ''        
 '0.5'        | '1%'      | '1W'     | '2512LF'  | 'EMPTY'  | 'TMP_QCS+5008FR00'(!)   = ''              | ''                 | 'CS+5008FR00'           |'R2512'| '(SMR2512AW)'                  | '0.5'     | '1%'    | '1W'     | 'IO'       | '0.5ohm 2512'                                      | 'CHIP2512'     | ''          | ''            | ''        
 '255'        | '1%'      | '1/4W'   | '1206LF'  | 'CHIP'   | 'TMP_QCS12556F200'(!)   = ''              | ''                 | 'CS12556F200'           |'R1206'| '(SMR1206AW)'                  | '255'     | '1%'    | '1/4W'   | 'DISCRETE' | '255ohm 1206'                                      | 'CHIP1206'     | ''          | ''            | ''        
 '255'        | '1%'      | '1/4W'   | '1206LF'  | 'EMPTY'  | 'TMP_QCS12556F200'(!)   = ''              | ''                 | 'CS12556F200'           |'R1206'| '(SMR1206AW)'                  | '255'     | '1%'    | '1/4W'   | 'IO'       | '255ohm 1206'                                      | 'CHIP1206'     | ''          | ''            | ''        
 '4.53K'      | '1%'      | '1/4W'   | '1206LF'  | 'CHIP'   | 'TMP_QCS24536F200'(!)   = ''              | ''                 | 'CS24536F200'           |'R1206'| '(SMR1206AW)'                  | '4.53K'   | '1%'    | '1/4W'   | 'DISCRETE' | '4.53Kohm 1206'                                    | 'CHIP1206'     | ''          | ''            | ''        
 '4.53K'      | '1%'      | '1/4W'   | '1206LF'  | 'EMPTY'  | 'TMP_QCS24536F200'(!)   = ''              | ''                 | 'CS24536F200'           |'R1206'| '(SMR1206AW)'                  | '4.53K'   | '1%'    | '1/4W'   | 'IO'       | '4.53Kohm 1206'                                    | 'CHIP1206'     | ''          | ''            | ''        
 '130'        | '1%'      | '1/4W'   | '1206LF'  | 'CHIP'   | 'TMP_QCS11306F200'(!)   = ''              | ''                 | 'CS11306F200'           |'R1206'| '(SMR1206AW)'                  | '130'     | '1%'    | '1/4W'   | 'DISCRETE' | '130ohm 1206'                                      | 'CHIP1206'     | ''          | ''            | ''        
 '130'        | '1%'      | '1/4W'   | '1206LF'  | 'EMPTY'  | 'TMP_QCS11306F200'(!)   = ''              | ''                 | 'CS11306F200'           |'R1206'| '(SMR1206AW)'                  | '130'     | '1%'    | '1/4W'   | 'IO'       | '130ohm 1206'                                      | 'CHIP1206'     | ''          | ''            | ''        
 '261'        | '1%'      | '1/4W'   | '1206LF'  | 'CHIP'   | 'TMP_QCS12616F200'(!)   = ''              | ''                 | 'CS12616F200'           |'R1206'| '(SMR1206AW)'                  | '261'     | '1%'    | '1/4W'   | 'DISCRETE' | '261ohm 1206'                                      | 'CHIP1206'     | ''          | ''            | ''        
 '261'        | '1%'      | '1/4W'   | '1206LF'  | 'EMPTY'  | 'TMP_QCS12616F200'(!)   = ''              | ''                 | 'CS12616F200'           |'R1206'| '(SMR1206AW)'                  | '261'     | '1%'    | '1/4W'   | 'IO'       | '261ohm 1206'                                      | 'CHIP1206'     | ''          | ''            | ''        
 '1K'         | '1%'      | '1/4W'   | '1206LF'  | 'CHIP'   | 'TMP_QCS21006F200'(!)   = ''              | ''                 | 'CS21006F200'           |'R1206'| '(SMR1206AW)'                  | '1K'      | '1%'    | '1/4W'   | 'DISCRETE' | '1Kohm 1206'                                       | 'CHIP1206'     | ''          | ''            | ''        
 '1K'         | '1%'      | '1/4W'   | '1206LF'  | 'EMPTY'  | 'TMP_QCS21006F200'(!)   = ''              | ''                 | 'CS21006F200'           |'R1206'| '(SMR1206AW)'                  | '1K'      | '1%'    | '1/4W'   | 'IO'       | '1Kohm 1206'                                       | 'CHIP1206'     | ''          | ''            | ''        
 '2.2'        | '1%'      | '1/4W'   | '1206LF'  | 'CHIP'   | 'TMP_QCS-2206F200'(!)   = ''              | ''                 | 'CS-2206F200'           |'R1206'| '(SMR1206AW)'                  | '2.2'     | '1%'    | '1/4W'   | 'DISCRETE' | '2.2ohm 1206'                                      | 'CHIP1206'     | ''          | ''            | ''        
 '2.2'        | '1%'      | '1/4W'   | '1206LF'  | 'EMPTY'  | 'TMP_QCS-2206F200'(!)   = ''              | ''                 | 'CS-2206F200'           |'R1206'| '(SMR1206AW)'                  | '2.2'     | '1%'    | '1/4W'   | 'IO'       | '2.2ohm 1206'                                      | 'CHIP1206'     | ''          | ''            | ''        
 '732'        | '1%'      | '1/4W'   | '1206LF'  | 'CHIP'   | 'TMP_QCS17326F200'(!)   = ''              | ''                 | 'CS17326F200'           |'R1206'| '(SMR1206AW)'                  | '732'     | '1%'    | '1/4W'   | 'DISCRETE' | '732ohm 1206'                                      | 'CHIP1206'     | ''          | ''            | ''        
 '732'        | '1%'      | '1/4W'   | '1206LF'  | 'EMPTY'  | 'TMP_QCS17326F200'(!)   = ''              | ''                 | 'CS17326F200'           |'R1206'| '(SMR1206AW)'                  | '732'     | '1%'    | '1/4W'   | 'IO'       | '732ohm 1206'                                      | 'CHIP1206'     | ''          | ''            | ''        
 '143K'       | '1%'      | '1/16W'  | '0402LF'  | 'CHIP'   | 'TMP_QCS41432FB18'(!)   = 'End of Design' | 'Comp-Approve'     | 'CS41432FB18'           |'R0402'| '(R0402-0201)'                 | '143K'    | '1%'    | '1/16W'  | 'DISCRETE' | '143Kohm 0402'                                     | 'CHIP0402'     | ''          | ''            | ''        
 '143K'       | '1%'      | '1/16W'  | '0402LF'  | 'EMPTY'  | 'TMP_QCS41432FB18'(!)   = 'End of Design' | 'Comp-Approve'     | 'CS41432FB18'           |'R0402'| '(R0402-0201)'                 | '143K'    | '1%'    | '1/16W'  | 'IO'       | '143Kohm 0402'                                     | 'CHIP0402'     | ''          | ''            | ''        
 '255'        | '1%'      | '1/2W'   | '1206LF'  | 'CHIP'   | 'TMP_QCS12557F200'(!)   = ''              | ''                 | 'CS12557F200'           |'R1206'| '(SMR1206AW)'                  | '255'     | '1%'    | '1/2W'   | 'DISCRETE' | '255ohm 1206'                                      | 'CHIP1206'     | ''          | ''            | ''        
 '255'        | '1%'      | '1/2W'   | '1206LF'  | 'EMPTY'  | 'TMP_QCS12557F200'(!)   = ''              | ''                 | 'CS12557F200'           |'R1206'| '(SMR1206AW)'                  | '255'     | '1%'    | '1/2W'   | 'IO'       | '255ohm 1206'                                      | 'CHIP1206'     | ''          | ''            | ''        
 '100'        | '1%'      | '1/2W'   | '1206LF'  | 'CHIP'   | 'TMP_QCS11007F200'(!)   = ''              | ''                 | 'CS11007F200'           |'R1206XI'| '(SMR1206AW)'                  | '100'     | '1%'    | '1/2W'   | 'DISCRETE' | 'RES CHIP 100 1/2W +-1%(1206)'                     | 'CHIP1206'     | ''          | ''            | '20221027'
 '100'        | '1%'      | '1/2W'   | '1206LF'  | 'EMPTY'  | 'TMP_QCS11007F200'(!)   = ''              | ''                 | 'CS11007F200'           |'R1206XI'| '(SMR1206AW)'                  | '100'     | '1%'    | '1/2W'   | 'IO'       | 'RES CHIP 100 1/2W +-1%(1206)'                     | 'CHIP1206'     | ''          | ''            | '20221027'
 '18'         | '1%'      | '1/4W'   | '0805LF'  | 'CHIP'   | 'TMP_QCS01806FA00'(!)   = ''              | ''                 | 'CS01806FA00'           |'R0805'| '(SMR0805AW)'                  | '18'      | '1%'    | '1/4W'   | 'DISCRETE' | '18ohm 0805'                                       | 'CHIP0805'     | ''          | ''            | ''        
 '18'         | '1%'      | '1/4W'   | '0805LF'  | 'EMPTY'  | 'TMP_QCS01806FA00'(!)   = ''              | ''                 | 'CS01806FA00'           |'R0805'| '(SMR0805AW)'                  | '18'      | '1%'    | '1/4W'   | 'IO'       | '18ohm 0805'                                       | 'CHIP0805'     | ''          | ''            | ''        
 '820'        | '1%'      | '1/4W'   | '0805LF'  | 'CHIP'   | 'TMP_QCS18206FA00'(!)   = ''              | ''                 | 'CS18206FA00'           |'R0805'| '(SMR0805AW)'                  | '820'     | '1%'    | '1/4W'   | 'DISCRETE' | '820ohm 0805'                                      | 'CHIP0805'     | ''          | ''            | ''        
 '820'        | '1%'      | '1/4W'   | '0805LF'  | 'EMPTY'  | 'TMP_QCS18206FA00'(!)   = ''              | ''                 | 'CS18206FA00'           |'R0805'| '(SMR0805AW)'                  | '820'     | '1%'    | '1/4W'   | 'IO'       | '820ohm 0805'                                      | 'CHIP0805'     | ''          | ''            | ''        
 '10K'        | '5%'      | '1/10W'  | '0603'    | 'CHIP'   | 'TMP_QCS31003J941'(!)   = ''              | ''                 | 'CS31003J941'           |'R0603'| '(SMR0603AW)'                  | '10K'     | '5%'    | '1/10W'  | 'DISCRETE' | '10Kohm 0603'                                      | 'CHIP0603'     | ''          | ''            | ''        
 '10K'        | '5%'      | '1/10W'  | '0603'    | 'EMPTY'  | 'TMP_QCS31003J941'(!)   = ''              | ''                 | 'CS31003J941'           |'R0603'| '(SMR0603AW)'                  | '10K'     | '5%'    | '1/10W'  | 'IO'       | '10Kohm 0603'                                      | 'CHIP0603'     | ''          | ''            | ''        
 '243'        | '1%'      | '1/10W'  | '0603'    | 'CHIP'   | 'TMP_QCS12433F900'(!)   = ''              | ''                 | 'CS12433F900'           |'R0603'| '(SMR0603AW)'                  | '243'     | '1%'    | '1/10W'  | 'DISCRETE' | '243ohm 0603'                                      | 'CHIP0603'     | ''          | ''            | ''        
 '243'        | '1%'      | '1/10W'  | '0603'    | 'EMPTY'  | 'TMP_QCS12433F900'(!)   = ''              | ''                 | 'CS12433F900'           |'R0603'| '(SMR0603AW)'                  | '243'     | '1%'    | '1/10W'  | 'IO'       | '243ohm 0603'                                      | 'CHIP0603'     | ''          | ''            | ''        
 '69.8'       | '1%'      | '1/10W'  | '0603'    | 'CHIP'   | 'TMP_QCS06983F911'(!)   = ''              | ''                 | 'CS06983F911'           |'R0603'| '(SMR0603AW)'                  | '69.8'    | '1%'    | '1/10W'  | 'DISCRETE' | '69.8ohm 0603'                                     | 'CHIP0603'     | ''          | ''            | ''        
 '69.8'       | '1%'      | '1/10W'  | '0603'    | 'EMPTY'  | 'TMP_QCS06983F911'(!)   = ''              | ''                 | 'CS06983F911'           |'R0603'| '(SMR0603AW)'                  | '69.8'    | '1%'    | '1/10W'  | 'IO'       | '69.8ohm 0603'                                     | 'CHIP0603'     | ''          | ''            | ''        
 '10'         | '1%'      | '1/4W'   | '1206LF'  | 'CHIP'   | 'TMP_QCS01006F214'(!)   = ''              | ''                 | 'CS01006F214'           |'R1206'| '(SMR1206AW)'                  | '10'      | '1%'    | '1/4W'   | 'DISCRETE' | '10ohm 1206'                                       | 'CHIP1206'     | ''          | ''            | ''        
 '10'         | '1%'      | '1/4W'   | '1206LF'  | 'EMPTY'  | 'TMP_QCS01006F214'(!)   = ''              | ''                 | 'CS01006F214'           |'R1206'| '(SMR1206AW)'                  | '10'      | '1%'    | '1/4W'   | 'IO'       | '10ohm 1206'                                       | 'CHIP1206'     | ''          | ''            | ''        
 '0.05'       | '1%'      | '1W'     | '2512LF'  | 'CHIP'   | 'TMP_QCS+0508FR00'(!)   = ''              | ''                 | 'CS+0508FR00'           |'R2512'| '(SMR2512AW)'                  | '0.05'    | '1%'    | '1W'     | 'DISCRETE' | '0.05ohm 2512'                                     | 'CHIP2512'     | ''          | ''            | ''        
 '0.05'       | '1%'      | '1W'     | '2512LF'  | 'EMPTY'  | 'TMP_QCS+0508FR00'(!)   = ''              | ''                 | 'CS+0508FR00'           |'R2512'| '(SMR2512AW)'                  | '0.05'    | '1%'    | '1W'     | 'IO'       | '0.05ohm 2512'                                     | 'CHIP2512'     | ''          | ''            | ''        
 '0.3'        | '1%'      | '1W'     | '2512LF'  | 'CHIP'   | 'TMP_QCS+3008FR00'(!)   = ''              | ''                 | 'CS+3008FR00'           |'R2512'| '(SMR2512AW)'                  | '0.3'     | '1%'    | '1W'     | 'DISCRETE' | '0.3ohm 2512'                                      | 'CHIP2512'     | ''          | ''            | ''        
 '0.3'        | '1%'      | '1W'     | '2512LF'  | 'EMPTY'  | 'TMP_QCS+3008FR00'(!)   = ''              | ''                 | 'CS+3008FR00'           |'R2512'| '(SMR2512AW)'                  | '0.3'     | '1%'    | '1W'     | 'IO'       | '0.3ohm 2512'                                      | 'CHIP2512'     | ''          | ''            | ''        
 '110'        | '1%'      | '1/16W'  | '0402LF'  | 'CHIP'   | 'TMP_QCS11102FB18'(!)   = 'End of Design' | 'Comp-Approve'     | 'CS11102FB18'           |'R0402'| '(R0402-0201)'                 | '110'     | '1%'    | '1/16W'  | 'DISCRETE' | '110ohm 0402'                                      | 'CHIP0402'     | ''          | ''            | ''        
 '110'        | '1%'      | '1/16W'  | '0402LF'  | 'EMPTY'  | 'TMP_QCS11102FB18'(!)   = 'End of Design' | 'Comp-Approve'     | 'CS11102FB18'           |'R0402'| '(R0402-0201)'                 | '110'     | '1%'    | '1/16W'  | 'IO'       | '110ohm 0402'                                      | 'CHIP0402'     | ''          | ''            | ''        
 '4.02K'      | '1%'      | '1/16W'  | '0402LF'  | 'CHIP'   | 'TMP_QCS24022FB13'(!)   = 'End of Design' | 'Comp-Approve'     | 'CS24022FB13'           |'R0402'| '(R0402-0201)'                 | '4.02K'   | '1%'    | '1/16W'  | 'DISCRETE' | '4.02Kohm 0402'                                    | 'CHIP0402'     | ''          | ''            | ''        
 '4.02K'      | '1%'      | '1/16W'  | '0402LF'  | 'EMPTY'  | 'TMP_QCS24022FB13'(!)   = 'End of Design' | 'Comp-Approve'     | 'CS24022FB13'           |'R0402'| '(R0402-0201)'                 | '4.02K'   | '1%'    | '1/16W'  | 'IO'       | '4.02Kohm 0402'                                    | 'CHIP0402'     | ''          | ''            | ''        
 '8.06K'      | '1%'      | '1/16W'  | '0402LF'  | 'CHIP'   | 'TMP_QCS28062FB21'(!)   = 'End of Design' | 'Comp-Approve'     | 'CS28062FB21'           |'R0402'| '(R0402-0201)'                 | '8.06K'   | '1%'    | '1/16W'  | 'DISCRETE' | '8.06Kohm 0402'                                    | 'CHIP0402'     | ''          | ''            | ''        
 '8.06K'      | '1%'      | '1/16W'  | '0402LF'  | 'EMPTY'  | 'TMP_QCS28062FB21'(!)   = 'End of Design' | 'Comp-Approve'     | 'CS28062FB21'           |'R0402'| '(R0402-0201)'                 | '8.06K'   | '1%'    | '1/16W'  | 'IO'       | '8.06Kohm 0402'                                    | 'CHIP0402'     | ''          | ''            | ''        
 '2.49K'      | '1%'      | '1/16W'  | '0402LF'  | 'CHIP'   | 'TMP_QCS22492FB22'(!)   = 'End of Design' | 'Comp-Approve'     | 'CS22492FB22'           |'R0402'| '(R0402-0201)'                 | '2.49K'   | '1%'    | '1/16W'  | 'DISCRETE' | '2.49Kohm 0402'                                    | 'CHIP0402'     | ''          | ''            | ''        
 '2.49K'      | '1%'      | '1/16W'  | '0402LF'  | 'EMPTY'  | 'TMP_QCS22492FB22'(!)   = 'End of Design' | 'Comp-Approve'     | 'CS22492FB22'           |'R0402'| '(R0402-0201)'                 | '2.49K'   | '1%'    | '1/16W'  | 'IO'       | '2.49Kohm 0402'                                    | 'CHIP0402'     | ''          | ''            | ''        
 '11K'        | '1%'      | '1/16W'  | '0402LF'  | 'CHIP'   | 'TMP_QCS31102FB11'(!)   = 'End of Design' | 'Comp-Approve'     | 'CS31102FB11'           |'R0402'| '(R0402-0201)'                 | '11K'     | '1%'    | '1/16W'  | 'DISCRETE' | '11Kohm 0402'                                      | 'CHIP0402'     | ''          | ''            | ''        
 '11K'        | '1%'      | '1/16W'  | '0402LF'  | 'EMPTY'  | 'TMP_QCS31102FB11'(!)   = 'End of Design' | 'Comp-Approve'     | 'CS31102FB11'           |'R0402'| '(R0402-0201)'                 | '11K'     | '1%'    | '1/16W'  | 'IO'       | '11Kohm 0402'                                      | 'CHIP0402'     | ''          | ''            | ''        
 '10.7K'      | '0.1%'    | '1/4W'   | '1206LF'  | 'CHIP'   | 'TMP_QCS31076B200'(!)   = ''              | ''                 | 'CS31076B200'           |'R1206'| '(SMR1206AW)'                  | '10.7K'   | '0.1%'  | '1/4W'   | 'DISCRETE' | '10.7Kohm 1206'                                    | 'CHIP1206'     | ''          | ''            | ''        
 '10.7K'      | '0.1%'    | '1/4W'   | '1206LF'  | 'EMPTY'  | 'TMP_QCS31076B200'(!)   = ''              | ''                 | 'CS31076B200'           |'R1206'| '(SMR1206AW)'                  | '10.7K'   | '0.1%'  | '1/4W'   | 'IO'       | '10.7Kohm 1206'                                    | 'CHIP1206'     | ''          | ''            | ''        
 '56.2K'      | '0.1%'    | '1/4W'   | '1206LF'  | 'CHIP'   | 'TMP_QCS35626B200'(!)   = ''              | ''                 | 'CS35626B200'           |'R1206'| '(SMR1206AW)'                  | '56.2K'   | '0.1%'  | '1/4W'   | 'DISCRETE' | '56.2Kohm 1206'                                    | 'CHIP1206'     | ''          | ''            | ''        
 '56.2K'      | '0.1%'    | '1/4W'   | '1206LF'  | 'EMPTY'  | 'TMP_QCS35626B200'(!)   = ''              | ''                 | 'CS35626B200'           |'R1206'| '(SMR1206AW)'                  | '56.2K'   | '0.1%'  | '1/4W'   | 'IO'       | '56.2Kohm 1206'                                    | 'CHIP1206'     | ''          | ''            | ''        
 '80.6K'      | '0.1%'    | '1/4W'   | '1206LF'  | 'CHIP'   | 'TMP_QCS38066B200'(!)   = ''              | ''                 | 'CS38066B200'           |'R1206'| '(SMR1206AW)'                  | '80.6K'   | '0.1%'  | '1/4W'   | 'DISCRETE' | '80.6Kohm 1206'                                    | 'CHIP1206'     | ''          | ''            | ''        
 '80.6K'      | '0.1%'    | '1/4W'   | '1206LF'  | 'EMPTY'  | 'TMP_QCS38066B200'(!)   = ''              | ''                 | 'CS38066B200'           |'R1206'| '(SMR1206AW)'                  | '80.6K'   | '0.1%'  | '1/4W'   | 'IO'       | '80.6Kohm 1206'                                    | 'CHIP1206'     | ''          | ''            | ''        
 '0.001'      | '0.1%'    | '1W'     | '2512LF'  | 'CHIP'   | 'TMP_QCS+0018BR00'(!)   = 'End of Design' | 'Comp-Release Qty' | 'CS+0018BR00'           |'R2512'| '(SMR2512AW)'                  | '0.001'   | '0.1%'  | '1W'     | 'DISCRETE' | '0.001ohm 2512'                                    | 'CHIP2512'     | ''          | ''            | ''        
 '0.001'      | '0.1%'    | '1W'     | '2512LF'  | 'EMPTY'  | 'TMP_QCS+0018BR00'(!)   = 'End of Design' | 'Comp-Release Qty' | 'CS+0018BR00'           |'R2512'| '(SMR2512AW)'                  | '0.001'   | '0.1%'  | '1W'     | 'IO'       | '0.001ohm 2512'                                    | 'CHIP2512'     | ''          | ''            | ''        
 '0.2'        | '0.1%'    | '1W'     | '2512LF'  | 'CHIP'   | 'TMP_QCS+2008BR00'(!)   = ''              | ''                 | 'CS+2008BR00'           |'R2512'| '(SMR2512AW)'                  | '0.2'     | '0.1%'  | '1W'     | 'DISCRETE' | '0.2ohm 2512'                                      | 'CHIP2512'     | ''          | ''            | ''        
 '0.2'        | '0.1%'    | '1W'     | '2512LF'  | 'EMPTY'  | 'TMP_QCS+2008BR00'(!)   = ''              | ''                 | 'CS+2008BR00'           |'R2512'| '(SMR2512AW)'                  | '0.2'     | '0.1%'  | '1W'     | 'IO'       | '0.2ohm 2512'                                      | 'CHIP2512'     | ''          | ''            | ''        
 '0.03'       | '0.1%'    | '1W'     | '2512LF'  | 'CHIP'   | 'TMP_QCS+0308BR00'(!)   = ''              | ''                 | 'CS+0308BR00'           |'R2512'| '(SMR2512AW)'                  | '0.03'    | '0.1%'  | '1W'     | 'DISCRETE' | '0.03ohm 2512'                                     | 'CHIP2512'     | ''          | ''            | ''        
 '0.03'       | '0.1%'    | '1W'     | '2512LF'  | 'EMPTY'  | 'TMP_QCS+0308BR00'(!)   = ''              | ''                 | 'CS+0308BR00'           |'R2512'| '(SMR2512AW)'                  | '0.03'    | '0.1%'  | '1W'     | 'IO'       | '0.03ohm 2512'                                     | 'CHIP2512'     | ''          | ''            | ''        
 '2.67K'      | '1%'      | '1/10W'  | '0603'    | 'CHIP'   | 'TMP_QCS22673F927'(!)   = 'End of Design' | 'Comp-Approve'     | 'CS22673F927'           |'R0603'| '(SMR0603AW)'                  | '2.67K'   | '1%'    | '1/10W'  | 'DISCRETE' | '2.67Kohm 0603'                                    | 'CHIP0603'     | ''          | ''            | ''        
 '2.67K'      | '1%'      | '1/10W'  | '0603'    | 'EMPTY'  | 'TMP_QCS22673F927'(!)   = 'End of Design' | 'Comp-Approve'     | 'CS22673F927'           |'R0603'| '(SMR0603AW)'                  | '2.67K'   | '1%'    | '1/10W'  | 'IO'       | '2.67Kohm 0603'                                    | 'CHIP0603'     | ''          | ''            | ''        
 '23.2K'      | '1%'      | '1/16W'  | '0402LF'  | 'CHIP'   | 'TMP_QCS32322FB11'(!)   = 'End of Design' | 'Comp-Approve'     | 'CS32322FB11'           |'R0402'| '(R0402-0201)'                 | '23.2K'   | '1%'    | '1/16W'  | 'DISCRETE' | '23.2Kohm 0402'                                    | 'CHIP0402'     | ''          | ''            | ''        
 '23.2K'      | '1%'      | '1/16W'  | '0402LF'  | 'EMPTY'  | 'TMP_QCS32322FB11'(!)   = 'End of Design' | 'Comp-Approve'     | 'CS32322FB11'           |'R0402'| '(R0402-0201)'                 | '23.2K'   | '1%'    | '1/16W'  | 'IO'       | '23.2Kohm 0402'                                    | 'CHIP0402'     | ''          | ''            | ''        
 '174'        | '1%'      | '1/10W'  | '0603'    | 'CHIP'   | 'TMP_QCS11743F900'(!)   = ''              | ''                 | 'CS11743F900'           |'R0603'| '(SMR0603AW)'                  | '174'     | '1%'    | '1/10W'  | 'DISCRETE' | '174ohm 0603'                                      | 'CHIP0603'     | ''          | ''            | ''        
 '174'        | '1%'      | '1/10W'  | '0603'    | 'EMPTY'  | 'TMP_QCS11743F900'(!)   = ''              | ''                 | 'CS11743F900'           |'R0603'| '(SMR0603AW)'                  | '174'     | '1%'    | '1/10W'  | 'IO'       | '174ohm 0603'                                      | 'CHIP0603'     | ''          | ''            | ''        
 '7.32K'      | '1%'      | '1/10W'  | '0603'    | 'CHIP'   | 'TMP_QCS27323F919'(!)   = ''              | ''                 | 'CS27323F919'           |'R0603'| '(SMR0603AW)'                  | '7.32K'   | '1%'    | '1/10W'  | 'DISCRETE' | '7.32Kohm 0603'                                    | 'CHIP0603'     | ''          | ''            | ''        
 '7.32K'      | '1%'      | '1/10W'  | '0603'    | 'EMPTY'  | 'TMP_QCS27323F919'(!)   = ''              | ''                 | 'CS27323F919'           |'R0603'| '(SMR0603AW)'                  | '7.32K'   | '1%'    | '1/10W'  | 'IO'       | '7.32Kohm 0603'                                    | 'CHIP0603'     | ''          | ''            | ''        
 '255'        | '0.1%'    | '1/10W'  | '0603'    | 'CHIP'   | 'TMP_QCS12553B900'(!)   = ''              | ''                 | 'CS12553B900'           |'R0603'| '(SMR0603AW)'                  | '255'     | '0.1%'  | '1/10W'  | 'DISCRETE' | '255ohm 0603'                                      | 'CHIP0603'     | ''          | ''            | ''        
 '255'        | '0.1%'    | '1/10W'  | '0603'    | 'EMPTY'  | 'TMP_QCS12553B900'(!)   = ''              | ''                 | 'CS12553B900'           |'R0603'| '(SMR0603AW)'                  | '255'     | '0.1%'  | '1/10W'  | 'IO'       | '255ohm 0603'                                      | 'CHIP0603'     | ''          | ''            | ''        
 '22'         | '1%'      | '1/10W'  | '0603'    | 'CHIP'   | 'TMP_QCS02203F919'(!)   = 'End of Design' | 'Comp-Approve'     | 'CS02203F919'           |'R0603'| '(SMR0603AW)'                  | '22'      | '1%'    | '1/10W'  | 'DISCRETE' | '22ohm 0603'                                       | 'CHIP0603'     | ''          | ''            | ''        
 '22'         | '1%'      | '1/10W'  | '0603'    | 'EMPTY'  | 'TMP_QCS02203F919'(!)   = 'End of Design' | 'Comp-Approve'     | 'CS02203F919'           |'R0603'| '(SMR0603AW)'                  | '22'      | '1%'    | '1/10W'  | 'IO'       | '22ohm 0603'                                       | 'CHIP0603'     | ''          | ''            | ''        
 '4.99K'      | '1%'      | '1/10W'  | '0603'    | 'CHIP'   | 'TMP_QCS24993F949'(!)   = 'End of Design' | 'Comp-Approve'     | 'CS24993F949'           |'R0603'| '(SMR0603AW)'                  | '4.99K'   | '1%'    | '1/10W'  | 'DISCRETE' | '4.99Kohm 0603'                                    | 'CHIP0603'     | ''          | ''            | ''        
 '4.99K'      | '1%'      | '1/10W'  | '0603'    | 'EMPTY'  | 'TMP_QCS24993F949'(!)   = 'End of Design' | 'Comp-Approve'     | 'CS24993F949'           |'R0603'| '(SMR0603AW)'                  | '4.99K'   | '1%'    | '1/10W'  | 'IO'       | '4.99Kohm 0603'                                    | 'CHIP0603'     | ''          | ''            | ''        
 '0.5'        | '1%'      | '1/4W'   | '1206'    | 'CHIP'   | 'TMP_QCS+5006F200'(!)   = ''              | ''                 | 'CS+5006F200'           |'R1206'| '(SMR1206AW)'                  | '0.5'     | '1%'    | '1/4W'   | 'DISCRETE' | '0.5ohm 1206'                                      | 'CHIP1206'     | ''          | ''            | ''        
 '0.5'        | '1%'      | '1/4W'   | '1206'    | 'EMPTY'  | 'TMP_QCS+5006F200'(!)   = ''              | ''                 | 'CS+5006F200'           |'R1206'| '(SMR1206AW)'                  | '0.5'     | '1%'    | '1/4W'   | 'IO'       | '0.5ohm 1206'                                      | 'CHIP1206'     | ''          | ''            | ''        
 '0.51'       | '5%'      | '1/4W'   | '1206'    | 'CHIP'   | 'TMP_QCS+5106J203'(!)   = ''              | ''                 | 'CS+5106J203'           |'R1206'| '(SMR1206AW)'                  | '0.51'    | '5%'    | '1/4W'   | 'DISCRETE' | '0.51ohm 1206'                                     | 'CHIP1206'     | ''          | ''            | ''        
 '0.51'       | '5%'      | '1/4W'   | '1206'    | 'EMPTY'  | 'TMP_QCS+5106J203'(!)   = ''              | ''                 | 'CS+5106J203'           |'R1206'| '(SMR1206AW)'                  | '0.51'    | '5%'    | '1/4W'   | 'IO'       | '0.51ohm 1206'                                     | 'CHIP1206'     | ''          | ''            | ''        
 '1.5K'       | '5%'      | '1/16W'  | '0402LF'  | 'CHIP'   | 'TMP_QCS21502JB16'(!)   = 'End of Design' | 'Comp-Approve'     | 'CS21502JB16'           |'R0402'| '(R0402-0201)'                 | '1.5K'    | '5%'    | '1/16W'  | 'DISCRETE' | '1.5Kohm 0402'                                     | 'CHIP0402'     | ''          | ''            | ''        
 '1.5K'       | '5%'      | '1/16W'  | '0402LF'  | 'EMPTY'  | 'TMP_QCS21502JB16'(!)   = 'End of Design' | 'Comp-Approve'     | 'CS21502JB16'           |'R0402'| '(R0402-0201)'                 | '1.5K'    | '5%'    | '1/16W'  | 'IO'       | '1.5Kohm 0402'                                     | 'CHIP0402'     | ''          | ''            | ''        
 '3.3K'       | '5%'      | '1/16W'  | '0402LF'  | 'CHIP'   | 'TMP_QCS23302JB22'(!)   = 'End of Design' | 'Comp-Approve'     | 'CS23302JB22'           |'R0402'| '(R0402-0201)'                 | '3.3K'    | '5%'    | '1/16W'  | 'DISCRETE' | '3.3Kohm 0402'                                     | 'CHIP0402'     | ''          | ''            | ''        
 '3.3K'       | '5%'      | '1/16W'  | '0402LF'  | 'EMPTY'  | 'TMP_QCS23302JB22'(!)   = 'End of Design' | 'Comp-Approve'     | 'CS23302JB22'           |'R0402'| '(R0402-0201)'                 | '3.3K'    | '5%'    | '1/16W'  | 'IO'       | '3.3Kohm 0402'                                     | 'CHIP0402'     | ''          | ''            | ''        
 '4.7K'       | '5%'      | '1/16W'  | '0402LF'  | 'CHIP'   | 'TMP_QCS24702JB38'(!)   = 'End of Design' | 'Comp-Approve'     | 'CS24702JB38'           |'R0402'| '(R0402-0201)'                 | '4.7K'    | '5%'    | '1/16W'  | 'DISCRETE' | '4.7Kohm 0402'                                     | 'CHIP0402'     | ''          | ''            | ''        
 '4.7K'       | '5%'      | '1/16W'  | '0402LF'  | 'EMPTY'  | 'TMP_QCS24702JB38'(!)   = 'End of Design' | 'Comp-Approve'     | 'CS24702JB38'           |'R0402'| '(R0402-0201)'                 | '4.7K'    | '5%'    | '1/16W'  | 'IO'       | '4.7Kohm 0402'                                     | 'CHIP0402'     | ''          | ''            | ''        
 '470K'       | '1%'      | '1/16W'  | '0402LF'  | 'CHIP'   | 'TMP_QCS44702FB13'(!)   = 'End of Design' | 'Comp-Approve'     | 'CS44702FB13'           |'R0402'| '(R0402-0201)'                 | '470K'    | '1%'    | '1/16W'  | 'DISCRETE' | '470Kohm 0402'                                     | 'CHIP0402'     | ''          | ''            | ''        
 '470K'       | '1%'      | '1/16W'  | '0402LF'  | 'EMPTY'  | 'TMP_QCS44702FB13'(!)   = 'End of Design' | 'Comp-Approve'     | 'CS44702FB13'           |'R0402'| '(R0402-0201)'                 | '470K'    | '1%'    | '1/16W'  | 'IO'       | '470Kohm 0402'                                     | 'CHIP0402'     | ''          | ''            | ''        
 '15K'        | '5%'      | '1/16W'  | '0402LF'  | 'CHIP'   | 'TMP_QCS31502JB26'(!)   = 'End of Design' | 'Comp-Approve'     | 'CS31502JB26'           |'R0402'| '(R0402-0201)'                 | '15K'     | '5%'    | '1/16W'  | 'DISCRETE' | '15Kohm 0402'                                      | 'CHIP0402'     | ''          | ''            | ''        
 '15K'        | '5%'      | '1/16W'  | '0402LF'  | 'EMPTY'  | 'TMP_QCS31502JB26'(!)   = 'End of Design' | 'Comp-Approve'     | 'CS31502JB26'           |'R0402'| '(R0402-0201)'                 | '15K'     | '5%'    | '1/16W'  | 'IO'       | '15Kohm 0402'                                      | 'CHIP0402'     | ''          | ''            | ''        
 '47K'        | '5%'      | '1/16W'  | '0402LF'  | 'CHIP'   | 'TMP_QCS34702JB21'(!)   = 'End of Design' | 'Comp-Approve'     | 'CS34702JB21'           |'R0402'| '(R0402-0201)'                 | '47K'     | '5%'    | '1/16W'  | 'DISCRETE' | '47Kohm 0402'                                      | 'CHIP0402'     | ''          | ''            | ''        
 '47K'        | '5%'      | '1/16W'  | '0402LF'  | 'EMPTY'  | 'TMP_QCS34702JB21'(!)   = 'End of Design' | 'Comp-Approve'     | 'CS34702JB21'           |'R0402'| '(R0402-0201)'                 | '47K'     | '5%'    | '1/16W'  | 'IO'       | '47Kohm 0402'                                      | 'CHIP0402'     | ''          | ''            | ''        
 '100'        | '0.1%'    | '1/10W'  | '0603'    | 'CHIP'   | 'TMP_QCS11003B900'(!)   = 'End of Design' | 'Comp-Approve'     | 'CS11003B900'           |'R0603'| '(SMR0603AW)'                  | '100'     | '0.1%'  | '1/10W'  | 'DISCRETE' | '100ohm 0603'                                      | 'CHIP0603'     | ''          | ''            | ''        
 '100'        | '0.1%'    | '1/10W'  | '0603'    | 'EMPTY'  | 'TMP_QCS11003B900'(!)   = 'End of Design' | 'Comp-Approve'     | 'CS11003B900'           |'R0603'| '(SMR0603AW)'                  | '100'     | '0.1%'  | '1/10W'  | 'IO'       | '100ohm 0603'                                      | 'CHIP0603'     | ''          | ''            | ''        
 '10.7K'      | '0.1%'    | '1/10W'  | '0603'    | 'CHIP'   | 'TMP_QCS31073B900'(!)   = ''              | ''                 | 'CS31073B900'           |'R0603'| '(SMR0603AW)'                  | '10.7K'   | '0.1%'  | '1/10W'  | 'DISCRETE' | '10.7Kohm 0603'                                    | 'CHIP0603'     | ''          | ''            | ''        
 '10.7K'      | '0.1%'    | '1/10W'  | '0603'    | 'EMPTY'  | 'TMP_QCS31073B900'(!)   = ''              | ''                 | 'CS31073B900'           |'R0603'| '(SMR0603AW)'                  | '10.7K'   | '0.1%'  | '1/10W'  | 'IO'       | '10.7Kohm 0603'                                    | 'CHIP0603'     | ''          | ''            | ''        
 '80.6K'      | '0.1%'    | '1/10W'  | '0603'    | 'CHIP'   | 'TMP_QCS38063B900'(!)   = ''              | ''                 | 'CS38063B900'           |'R0603'| '(SMR0603AW)'                  | '80.6K'   | '0.1%'  | '1/10W'  | 'DISCRETE' | '80.6Kohm 0603'                                    | 'CHIP0603'     | ''          | ''            | ''        
 '80.6K'      | '0.1%'    | '1/10W'  | '0603'    | 'EMPTY'  | 'TMP_QCS38063B900'(!)   = ''              | ''                 | 'CS38063B900'           |'R0603'| '(SMR0603AW)'                  | '80.6K'   | '0.1%'  | '1/10W'  | 'IO'       | '80.6Kohm 0603'                                    | 'CHIP0603'     | ''          | ''            | ''        
 '56.2K'      | '0.1%'    | '1/10W'  | '0603'    | 'CHIP'   | 'TMP_QCS35623B900'(!)   = ''              | ''                 | 'CS35623B900'           |'R0603'| '(SMR0603AW)'                  | '56.2K'   | '0.1%'  | '1/10W'  | 'DISCRETE' | '56.2Kohm 0603'                                    | 'CHIP0603'     | ''          | ''            | ''        
 '56.2K'      | '0.1%'    | '1/10W'  | '0603'    | 'EMPTY'  | 'TMP_QCCS35623B90'(!)   = ''              | ''                 | 'CS35623B900'           |'R0603'| '(SMR0603AW)'                  | '56.2K'   | '0.1%'  | '1/10W'  | 'IO'       | '56.2Kohm 0603'                                    | 'CHIP0603'     | ''          | ''            | ''        
 '215K'       | '0.1%'    | '1/10W'  | '0603'    | 'CHIP'   | 'TMP_QCS42153B900'(!)   = ''              | ''                 | 'CS42153B900'           |'R0603'| '(SMR0603AW)'                  | '215K'    | '0.1%'  | '1/10W'  | 'DISCRETE' | '215Kohm 0603'                                     | 'CHIP0603'     | ''          | ''            | ''        
 '215K'       | '0.1%'    | '1/10W'  | '0603'    | 'EMPTY'  | 'TMP_QCS42153B900'(!)   = ''              | ''                 | 'CS42153B900'           |'R0603'| '(SMR0603AW)'                  | '215K'    | '0.1%'  | '1/10W'  | 'IO'       | '215Kohm 0603'                                     | 'CHIP0603'     | ''          | ''            | ''        
 '1.65K'      | '1%'      | '1/16W'  | '0402LF'  | 'CHIP'   | 'TMP_QCS21652FB29'(!)   = 'End of Design' | 'Comp-Approve'     | 'CS21652FB29'           |'R0402'| '(R0402-0201)'                 | '1.65K'   | '1%'    | '1/16W'  | 'DISCRETE' | '1.65Kohm 0402'                                    | 'CHIP0402'     | ''          | ''            | ''        
 '1.65K'      | '1%'      | '1/16W'  | '0402LF'  | 'EMPTY'  | 'TMP_QCS21652FB29'(!)   = 'End of Design' | 'Comp-Approve'     | 'CS21652FB29'           |'R0402'| '(R0402-0201)'                 | '1.65K'   | '1%'    | '1/16W'  | 'IO'       | '1.65Kohm 0402'                                    | 'CHIP0402'     | ''          | ''            | ''        
 '41.2K'      | '1%'      | '1/16W'  | '0402LF'  | 'CHIP'   | 'TMP_QCS34122FB19'(!)   = ''              | ''                 | 'CS34122FB19'           |'R0402'| '(R0402-0201)'                 | '41.2K'   | '1%'    | '1/16W'  | 'DISCRETE' | '41.2Kohm 0402'                                    | 'CHIP0402'     | ''          | ''            | ''        
 '41.2K'      | '1%'      | '1/16W'  | '0402LF'  | 'EMPTY'  | 'TMP_QCS34122FB19'(!)   = ''              | ''                 | 'CS34122FB19'           |'R0402'| '(R0402-0201)'                 | '41.2K'   | '1%'    | '1/16W'  | 'IO'       | '41.2Kohm 0402'                                    | 'CHIP0402'     | ''          | ''            | ''        
 '1.62K'      | '1%'      | '1/16W'  | '0402LF'  | 'CHIP'   | 'TMP_QCS21622FB17'(!)   = 'End of Design' | 'Comp-Approve'     | 'CS21622FB17'           |'R0402'| '(R0402-0201)'                 | '1.62K'   | '1%'    | '1/16W'  | 'DISCRETE' | '1.62Kohm 0402'                                    | 'CHIP0402'     | ''          | ''            | ''        
 '1.62K'      | '1%'      | '1/16W'  | '0402LF'  | 'EMPTY'  | 'TMP_QCS21622FB17'(!)   = 'End of Design' | 'Comp-Approve'     | 'CS21622FB17'           |'R0402'| '(R0402-0201)'                 | '1.62K'   | '1%'    | '1/16W'  | 'IO'       | '1.62Kohm 0402'                                    | 'CHIP0402'     | ''          | ''            | ''        
 '86.6K'      | '1%'      | '1/16W'  | '0402LF'  | 'CHIP'   | 'TMP_QCS38662FB16'(!)   = 'End of Design' | 'Comp-Approve'     | 'CS38662FB16'           |'R0402'| '(R0402-0201)'                 | '86.6K'   | '1%'    | '1/16W'  | 'DISCRETE' | '86.6Kohm 0402'                                    | 'CHIP0402'     | ''          | ''            | ''        
 '86.6K'      | '1%'      | '1/16W'  | '0402LF'  | 'EMPTY'  | 'TMP_QCS38662FB16'(!)   = 'End of Design' | 'Comp-Approve'     | 'CS38662FB16'           |'R0402'| '(R0402-0201)'                 | '86.6K'   | '1%'    | '1/16W'  | 'IO'       | '86.6Kohm 0402'                                    | 'CHIP0402'     | ''          | ''            | ''        
 '40.2K'      | '1%'      | '1/16W'  | '0402LF'  | 'CHIP'   | 'TMP_QCS34022FB15'(!)   = 'End of Design' | 'Comp-Approve'     | 'CS34022FB15'           |'R0402'| '(R0402-0201)'                 | '40.2K'   | '1%'    | '1/16W'  | 'DISCRETE' | '40.2Kohm 0402'                                    | 'CHIP0402'     | ''          | ''            | ''        
 '40.2K'      | '1%'      | '1/16W'  | '0402LF'  | 'EMPTY'  | 'TMP_QCS34022FB15'(!)   = 'End of Design' | 'Comp-Approve'     | 'CS34022FB15'           |'R0402'| '(R0402-0201)'                 | '40.2K'   | '1%'    | '1/16W'  | 'IO'       | '40.2Kohm 0402'                                    | 'CHIP0402'     | ''          | ''            | ''        
 '27K'        | '1%'      | '1/16W'  | '0402LF'  | 'CHIP'   | 'TMP_QCS32702FB16'(!)   = 'End of Design' | 'Comp-Approve'     | 'CS32702FB16'           |'R0402'| '(R0402-0201)'                 | '27K'     | '1%'    | '1/16W'  | 'DISCRETE' | '27Kohm 0402'                                      | 'CHIP0402'     | ''          | ''            | ''        
 '27K'        | '1%'      | '1/16W'  | '0402LF'  | 'EMPTY'  | 'TMP_QCS32702FB16'(!)   = 'End of Design' | 'Comp-Approve'     | 'CS32702FB16'           |'R0402'| '(R0402-0201)'                 | '27K'     | '1%'    | '1/16W'  | 'IO'       | '27Kohm 0402'                                      | 'CHIP0402'     | ''          | ''            | ''        
 '47'         | '1%'      | '1/16W'  | '0402LF'  | 'CHIP'   | 'TMP_QCS04702FB16'(!)   = 'End of Design' | 'Comp-Approve'     | 'CS04702FB16'           |'R0402'| '(R0402-0201)'                 | '47'      | '1%'    | '1/16W'  | 'DISCRETE' | '47ohm 0402'                                       | 'CHIP0402'     | ''          | ''            | ''        
 '47'         | '1%'      | '1/16W'  | '0402LF'  | 'EMPTY'  | 'TMP_QCS04702FB16'(!)   = 'End of Design' | 'Comp-Approve'     | 'CS04702FB16'           |'R0402'| '(R0402-0201)'                 | '47'      | '1%'    | '1/16W'  | 'IO'       | '47ohm 0402'                                       | 'CHIP0402'     | ''          | ''            | ''        
 '16.2K'      | '1%'      | '1/16W'  | '0402LF'  | 'CHIP'   | 'TMP_QCS31622FB27'(!)   = 'End of Design' | 'Comp-Approve'     | 'CS31622FB27'           |'R0402'| '(R0402-0201)'                 | '16.2K'   | '1%'    | '1/16W'  | 'DISCRETE' | '16.2Kohm 0402'                                    | 'CHIP0402'     | ''          | ''            | ''        
 '16.2K'      | '1%'      | '1/16W'  | '0402LF'  | 'EMPTY'  | 'TMP_QCS31622FB27'(!)   = 'End of Design' | 'Comp-Approve'     | 'CS31622FB27'           |'R0402'| '(R0402-0201)'                 | '16.2K'   | '1%'    | '1/16W'  | 'IO'       | '16.2Kohm 0402'                                    | 'CHIP0402'     | ''          | ''            | ''        
 '69.8K'      | '1%'      | '1/16W'  | '0402LF'  | 'CHIP'   | 'TMP_QCS36982FB11'(!)   = 'End of Design' | 'Comp-Approve'     | 'CS36982FB11'           |'R0402'| '(R0402-0201)'                 | '69.8K'   | '1%'    | '1/16W'  | 'DISCRETE' | '69.8Kohm 0402'                                    | 'CHIP0402'     | ''          | ''            | ''        
 '69.8K'      | '1%'      | '1/16W'  | '0402LF'  | 'EMPTY'  | 'TMP_QCS36982FB11'(!)   = 'End of Design' | 'Comp-Approve'     | 'CS36982FB11'           |'R0402'| '(R0402-0201)'                 | '69.8K'   | '1%'    | '1/16W'  | 'IO'       | '69.8Kohm 0402'                                    | 'CHIP0402'     | ''          | ''            | ''        
 '7.32K'      | '1%'      | '1/16W'  | '0402LF'  | 'CHIP'   | 'TMP_QCS27322FB12'(!)   = 'End of Design' | 'Comp-Approve'     | 'CS27322FB12'           |'R0402'| '(R0402-0201)'                 | '7.32K'   | '1%'    | '1/16W'  | 'DISCRETE' | '7.32Kohm 0402'                                    | 'CHIP0402'     | ''          | ''            | ''        
 '7.32K'      | '1%'      | '1/16W'  | '0402LF'  | 'EMPTY'  | 'TMP_QCS27322FB12'(!)   = 'End of Design' | 'Comp-Approve'     | 'CS27322FB12'           |'R0402'| '(R0402-0201)'                 | '7.32K'   | '1%'    | '1/16W'  | 'IO'       | '7.32Kohm 0402'                                    | 'CHIP0402'     | ''          | ''            | ''        
 '57.6K'      | '1%'      | '1/16W'  | '0402LF'  | 'CHIP'   | 'TMP_QCS35762FB11'(!)   = 'End of Design' | 'Comp-Approve'     | 'CS35762FB11'           |'R0402'| '(R0402-0201)'                 | '57.6K'   | '1%'    | '1/16W'  | 'DISCRETE' | '57.6Kohm 0402'                                    | 'CHIP0402'     | ''          | ''            | ''        
 '57.6K'      | '1%'      | '1/16W'  | '0402LF'  | 'EMPTY'  | 'TMP_QCS35762FB11'(!)   = 'End of Design' | 'Comp-Approve'     | 'CS35762FB11'           |'R0402'| '(R0402-0201)'                 | '57.6K'   | '1%'    | '1/16W'  | 'IO'       | '57.6Kohm 0402'                                    | 'CHIP0402'     | ''          | ''            | ''        
 '4.99K'      | '1%'      | '1/16W'  | '0402LF'  | 'CHIP'   | 'TMP_QCS24992FB26'(!)   = 'End of Design' | 'Comp-Approve'     | 'CS24992FB26'           |'R0402'| '(R0402-0201)'                 | '4.99K'   | '1%'    | '1/16W'  | 'DISCRETE' | '4.99Kohm 0402'                                    | 'CHIP0402'     | ''          | ''            | ''        
 '4.99K'      | '1%'      | '1/16W'  | '0402LF'  | 'EMPTY'  | 'TMP_QCS24992FB26'(!)   = 'End of Design' | 'Comp-Approve'     | 'CS24992FB26'           |'R0402'| '(R0402-0201)'                 | '4.99K'   | '1%'    | '1/16W'  | 'IO'       | '4.99Kohm 0402'                                    | 'CHIP0402'     | ''          | ''            | ''        
 '82K'        | '1%'      | '1/16W'  | '0402LF'  | 'CHIP'   | 'TMP_QCS38202FB14'(!)   = 'End of Design' | 'Comp-Approve'     | 'CS38202FB14'           |'R0402'| '(R0402-0201)'                 | '82K'     | '1%'    | '1/16W'  | 'DISCRETE' | '82Kohm 0402'                                      | 'CHIP0402'     | ''          | ''            | ''        
 '82K'        | '1%'      | '1/16W'  | '0402LF'  | 'EMPTY'  | 'TMP_QCS38202FB14'(!)   = 'End of Design' | 'Comp-Approve'     | 'CS38202FB14'           |'R0402'| '(R0402-0201)'                 | '82K'     | '1%'    | '1/16W'  | 'IO'       | '82Kohm 0402'                                      | 'CHIP0402'     | ''          | ''            | ''        
 '11.8K'      | '1%'      | '1/16W'  | '0402LF'  | 'CHIP'   | 'TMP_QCS31182FB18'(!)   = 'End of Design' | 'Comp-Approve'     | 'CS31182FB18'           |'R0402'| '(R0402-0201)'                 | '11.8K'   | '1%'    | '1/16W'  | 'DISCRETE' | '11.8Kohm 0402'                                    | 'CHIP0402'     | ''          | ''            | ''        
 '11.8K'      | '1%'      | '1/16W'  | '0402LF'  | 'EMPTY'  | 'TMP_QCS31182FB18'(!)   = 'End of Design' | 'Comp-Approve'     | 'CS31182FB18'           |'R0402'| '(R0402-0201)'                 | '11.8K'   | '1%'    | '1/16W'  | 'IO'       | '11.8Kohm 0402'                                    | 'CHIP0402'     | ''          | ''            | ''        
 '45.3K'      | '1%'      | '1/16W'  | '0402LF'  | 'CHIP'   | 'TMP_QCS34532FB18'(!)   = 'End of Design' | 'Comp-Approve'     | 'CS34532FB18'           |'R0402'| '(R0402-0201)'                 | '45.3K'   | '1%'    | '1/16W'  | 'DISCRETE' | '45.3Kohm 0402'                                    | 'CHIP0402'     | ''          | ''            | ''        
 '45.3K'      | '1%'      | '1/16W'  | '0402LF'  | 'EMPTY'  | 'TMP_QCS34532FB18'(!)   = 'End of Design' | 'Comp-Approve'     | 'CS34532FB18'           |'R0402'| '(R0402-0201)'                 | '45.3K'   | '1%'    | '1/16W'  | 'IO'       | '45.3Kohm 0402'                                    | 'CHIP0402'     | ''          | ''            | ''        
 '16K'        | '1%'      | '1/16W'  | '0402LF'  | 'CHIP'   | 'TMP_QCS31602FB00'(!)   = 'End of Design' | 'Comp-Approve'     | 'CS31602FB00'           |'R0402'| '(R0402-0201)'                 | '16K'     | '1%'    | '1/16W'  | 'DISCRETE' | '16Kohm 0402'                                      | 'CHIP0402'     | ''          | ''            | ''        
 '16K'        | '1%'      | '1/16W'  | '0402LF'  | 'EMPTY'  | 'TMP_QCS31602FB00'(!)   = 'End of Design' | 'Comp-Approve'     | 'CS31602FB00'           |'R0402'| '(R0402-0201)'                 | '16K'     | '1%'    | '1/16W'  | 'IO'       | '16Kohm 0402'                                      | 'CHIP0402'     | ''          | ''            | ''        
 '150'        | '1%'      | '1/16W'  | '0402LF'  | 'CHIP'   | 'TMP_QCS11502FB21'(!)   = 'End of Design' | 'Comp-Approve'     | 'CS11502FB21'           |'R0402'| '(R0402-0201)'                 | '150'     | '1%'    | '1/16W'  | 'DISCRETE' | '150ohm 0402'                                      | 'CHIP0402'     | ''          | ''            | ''        
 '150'        | '1%'      | '1/16W'  | '0402LF'  | 'EMPTY'  | 'TMP_QCS11502FB21'(!)   = 'End of Design' | 'Comp-Approve'     | 'CS11502FB21'           |'R0402'| '(R0402-0201)'                 | '150'     | '1%'    | '1/16W'  | 'IO'       | '150ohm 0402'                                      | 'CHIP0402'     | ''          | ''            | ''        
 '2.37K'      | '1%'      | '1/16W'  | '0402LF'  | 'CHIP'   | 'TMP_QCS22372FB11'(!)   = 'End of Design' | 'Comp-Approve'     | 'CS22372FB11'           |'R0402'| '(R0402-0201)'                 | '2.37K'   | '1%'    | '1/16W'  | 'DISCRETE' | '2.37Kohm 0402'                                    | 'CHIP0402'     | ''          | ''            | ''        
 '2.37K'      | '1%'      | '1/16W'  | '0402LF'  | 'EMPTY'  | 'TMP_QCS22372FB11'(!)   = 'End of Design' | 'Comp-Approve'     | 'CS22372FB11'           |'R0402'| '(R0402-0201)'                 | '2.37K'   | '1%'    | '1/16W'  | 'IO'       | '2.37Kohm 0402'                                    | 'CHIP0402'     | ''          | ''            | ''        
 '3.16K'      | '1%'      | '1/16W'  | '0402LF'  | 'CHIP'   | 'TMP_QCS23162FB04'(!)   = 'End of Design' | 'Comp-Approve'     | 'CS23162FB04'           |'R0402'| '(R0402-0201)'                 | '3.16K'   | '1%'    | '1/16W'  | 'DISCRETE' | '3.16Kohm 0402'                                    | 'CHIP0402'     | ''          | ''            | ''        
 '3.16K'      | '1%'      | '1/16W'  | '0402LF'  | 'EMPTY'  | 'TMP_QCS23162FB04'(!)   = 'End of Design' | 'Comp-Approve'     | 'CS23162FB04'           |'R0402'| '(R0402-0201)'                 | '3.16K'   | '1%'    | '1/16W'  | 'IO'       | '3.16Kohm 0402'                                    | 'CHIP0402'     | ''          | ''            | ''        
 '42.2K'      | '1%'      | '1/16W'  | '0402LF'  | 'CHIP'   | 'TMP_QCS34222FB00'(!)   = 'End of Design' | 'Comp-Approve'     | 'CS34222FB00'           |'R0402'| '(R0402-0201)'                 | '42.2K'   | '1%'    | '1/16W'  | 'DISCRETE' | '42.2Kohm 0402'                                    | 'CHIP0402'     | ''          | ''            | ''        
 '42.2K'      | '1%'      | '1/16W'  | '0402LF'  | 'EMPTY'  | 'TMP_QCS34222FB00'(!)   = 'End of Design' | 'Comp-Approve'     | 'CS34222FB00'           |'R0402'| '(R0402-0201)'                 | '42.2K'   | '1%'    | '1/16W'  | 'IO'       | '42.2Kohm 0402'                                    | 'CHIP0402'     | ''          | ''            | ''        
 '56K'        | '1%'      | '1/16W'  | '0402LF'  | 'CHIP'   | 'TMP_QCS35602FB11'(!)   = 'End of Design' | 'Comp-Approve'     | 'CS35602FB11'           |'R0402'| '(R0402-0201)'                 | '56K'     | '1%'    | '1/16W'  | 'DISCRETE' | '56Kohm 0402'                                      | 'CHIP0402'     | ''          | ''            | ''        
 '56K'        | '1%'      | '1/16W'  | '0402LF'  | 'EMPTY'  | 'TMP_QCS35602FB11'(!)   = 'End of Design' | 'Comp-Approve'     | 'CS35602FB11'           |'R0402'| '(R0402-0201)'                 | '56K'     | '1%'    | '1/16W'  | 'IO'       | '56Kohm 0402'                                      | 'CHIP0402'     | ''          | ''            | ''        
 '80.6K'      | '1%'      | '1/16W ' | '0402LF ' | 'CHIP'   | 'TMP_QCS38062FB14'(!)   = 'End of Design' | 'Comp-Approve'     | 'CS38062FB14'           |'R0402'| '(R0402-0201)'                 | '80.6K'   | '1%'    | '1/16W ' | 'DISCRETE' | 'RES CHIP 80.6K 1/16W +-1% (0402)'                 | 'CHIP0402 '    | ''          | ''            | ''        
 '80.6K'      | '1%'      | '1/16W ' | '0402LF ' | 'EMPTY'  | 'TMP_QCS38062FB14'(!)   = 'End of Design' | 'Comp-Approve'     | 'CS38062FB14'           |'R0402'| '(R0402-0201)'                 | '80.6K'   | '1%'    | '1/16W ' | 'IO'       | 'RES CHIP 80.6K 1/16W +-1% (0402)'                 | 'CHIP0402 '    | ''          | ''            | ''        
 '22K'        | '1%'      | '1/16W'  | '0402LF'  | 'CHIP'   | 'TMP_QCS32202FB18'(!)   = 'End of Design' | 'Comp-Approve'     | 'CS32202FB18'           |'R0402'| '(R0402-0201)'                 | '22K'     | '1%'    | '1/16W'  | 'DISCRETE' | 'RES CHIP 22K 1/16W+-1%(0402)'                     | 'CHIP0402'     | ''          | ''            | ''        
 '22K'        | '1%'      | '1/16W'  | '0402LF'  | 'EMPTY'  | 'TMP_QCS32202FB18'(!)   = 'End of Design' | 'Comp-Approve'     | 'CS32202FB18'           |'R0402'| '(R0402-0201)'                 | '22K'     | '1%'    | '1/16W'  | 'IO'       | 'RES CHIP 22K 1/16W+-1%(0402)'                     | 'CHIP0402'     | ''          | ''            | ''        
 '12.1K'      | '1%'      | '1/16W'  | '0402LF'  | 'CHIP'   | 'TMP_QCS31212FB28'(!)   = 'End of Design' | 'Comp-Approve'     | 'CS31212FB28'           |'R0402'| '(R0402-0201)'                 | '12.1K'   | '1%'    | '1/16W'  | 'DISCRETE' | 'RES CHIP 12.1K 1/16W +-1%(0402)'                  | 'CHIP0402'     | ''          | ''            | ''        
 '12.1K'      | '1%'      | '1/16W'  | '0402LF'  | 'EMPTY'  | 'TMP_QCS31212FB28'(!)   = 'End of Design' | 'Comp-Approve'     | 'CS31212FB28'           |'R0402'| '(R0402-0201)'                 | '12.1K'   | '1%'    | '1/16W'  | 'IO'       | 'RES CHIP 12.1K 1/16W +-1%(0402)'                  | 'CHIP0402'     | ''          | ''            | ''        
 '37.4K'      | '1%'      | '1/16W'  | '0402LF'  | 'CHIP'   | 'TMP_QCS33742FB17'(!)   = 'End of Design' | 'Comp-Approve'     | 'CS33742FB17'           |'R0402'| '(R0402-0201)'                 | '37.4K'   | '1%'    | '1/16W ' | 'DISCRETE' | 'RES CHIP 37.4K 1/16W +-1% (0402)'                 | 'CHIP0402'     | ''          | ''            | ''        
 '37.4K'      | '1%'      | '1/16W'  | '0402LF'  | 'EMPTY'  | 'TMP_QCS33742FB17'(!)   = 'End of Design' | 'Comp-Approve'     | 'CS33742FB17'           |'R0402'| '(R0402-0201)'                 | '37.4K'   | '1%'    | '1/16W ' | 'IO'       | 'RES CHIP 37.4K 1/16W +-1% (0402)'                 | 'CHIP0402'     | ''          | ''            | ''        
 '680'        | '5%'      | '1/16W ' | '0402LF ' | 'CHIP'   | 'TMP_QCS16802JB27'(!)   = 'End of Design' | 'Comp-Approve'     | 'CS16802JB27'           |'R0402'| '(R0402-0201)'                 | '680'     | '5%'    | '1/16W ' | 'DISCRETE' | 'RES CHIP 680 1/16W +-5%(0402)'                    | 'CHIP0402 '    | ''          | ''            | ''        
 '680'        | '5%'      | '1/16W ' | '0402LF ' | 'EMPTY'  | 'TMP_QCS16802JB27'(!)   = 'End of Design' | 'Comp-Approve'     | 'CS16802JB27'           |'R0402'| '(R0402-0201)'                 | '680'     | '5%'    | '1/16W ' | 'IO'       | 'RES CHIP 680 1/16W +-5%(0402)'                    | 'CHIP0402 '    | ''          | ''            | ''        
 '5.1'        | '1%'      | '1/10W'  | '0603LF'  | 'CHIP'   | 'TMP_QCS-5103F916'(!)   = ''              | ''                 | 'CS-5103F916'           |'R0603'| '(SMR0603AW)'                  | '5.1'     | '1%'    | '1/10W'  | 'DISCRETE' | 'RES CHIP 5.1 1/10W +-1%(0603)'                    | 'CHIP0603'     | ''          | ''            | ''        
 '5.1'        | '1%'      | '1/10W'  | '0603LF'  | 'EMPTY'  | 'TMP_QCS-5103F916'(!)   = ''              | ''                 | 'CS-5103F916'           |'R0603'| '(SMR0603AW)'                  | '5.1'     | '1%'    | '1/10W'  | 'IO'       | 'RES CHIP 5.1 1/10W +-1%(0603)'                    | 'CHIP0603'     | ''          | ''            | ''        
 '2M'         | '1%'      | '1/16W'  | '0402LF'  | 'CHIP'   | 'TMP_QCS52002FB06'(!)   = 'End of Design' | 'Comp-Approve'     | 'CS52002FB06'           |'R0402'| '(R0402-0201)'                 | '2M'      | '1%'    | '1/16W ' | 'DISCRETE' | 'RES CHIP 2M 1/16W +-1%(0402)'                     | 'CHIP0402 '    | ''          | ''            | ''        
 '2M'         | '1%'      | '1/16W'  | '0402LF'  | 'EMPTY'  | 'TMP_QCS52002FB06'(!)   = 'End of Design' | 'Comp-Approve'     | 'CS52002FB06'           |'R0402'| '(R0402-0201)'                 | '2M'      | '1%'    | '1/16W ' | 'IO'       | 'RES CHIP 2M 1/16W +-1%(0402)'                     | 'CHIP0402 '    | ''          | ''            | ''        
 '165'        | '1%'      | '1/16W'  | '0402LF'  | 'CHIP'   | 'TMP_QCS11652FB19'(!)   = 'End of Design' | 'Comp-Approve'     | 'CS11652FB19'           |'R0402'| '(R0402-0201)'                 | '165'     | '1%'    | '1/16W ' | 'DISCRETE' | 'RES CHIP 165 1/16W +-1%(0402)'                    | 'CHIP0402 '    | ''          | ''            | ''        
 '165'        | '1%'      | '1/16W'  | '0402LF'  | 'EMPTY'  | 'TMP_QCS11652FB19'(!)   = 'End of Design' | 'Comp-Approve'     | 'CS11652FB19'           |'R0402'| '(R0402-0201)'                 | '165'     | '1%'    | '1/16W ' | 'IO'       | 'RES CHIP 165 1/16W +-1%(0402)'                    | 'CHIP0402 '    | ''          | ''            | ''        
 '49.9K'      | '1%'      | '1/16W ' | '0402LF ' | 'CHIP'   | 'TMP_QCS34992FB10'(!)   = 'End of Design' | 'Comp-Approve'     | 'CS34992FB10'           |'R0402'| '(R0402-0201)'                 | '49.9K'   | '1%'    | '1/16W ' | 'DISCRETE' | 'RES CHIP 49.9K 1/16W +-1%(0402)'                  | 'CHIP0402 '    | ''          | ''            | ''        
 '49.9K'      | '1%'      | '1/16W ' | '0402LF ' | 'EMPTY'  | 'TMP_QCS34992FB10'(!)   = 'End of Design' | 'Comp-Approve'     | 'CS34992FB10'           |'R0402'| '(R0402-0201)'                 | '49.9K'   | '1%'    | '1/16W ' | 'IO'       | 'RES CHIP 49.9K 1/16W +-1%(0402)'                  | 'CHIP0402 '    | ''          | ''            | ''        
 '15K'        | '1%'      | '1/16W'  | '0402LF'  | 'CHIP'   | 'TMP_QCS31502FB24'(!)   = 'End of Design' | 'Comp-Approve'     | 'CS31502FB24'           |'R0402'| '(R0402-0201)'                 | '15K'     | '1%'    | '1/16W ' | 'DISCRETE' | 'RES CHIP 15K 1/16W +-1% (0402)'                   | 'CHIP0402'     | ''          | ''            | ''        
 '15K'        | '1%'      | '1/16W'  | '0402LF'  | 'EMPTY'  | 'TMP_QCS31502FB24'(!)   = 'End of Design' | 'Comp-Approve'     | 'CS31502FB24'           |'R0402'| '(R0402-0201)'                 | '15K'     | '1%'    | '1/16W ' | 'IO'       | 'RES CHIP 15K 1/16W +-1% (0402)'                   | 'CHIP0402'     | ''          | ''            | ''        
 '10K'        | '1%'      | '1/16W'  | '0402LF'  | 'CHIP'   | 'TMP_QCS31002FB26'(!)   = 'End of Design' | 'Comp-Approve'     | 'CS31002FB26'           |'R0402'| '(R0402-0201)'                 | '10K'     | '1%'    | '1/16W'  | 'DISCRETE' | 'RES CHIP 10K 1/16W +-1% (0402)'                   | 'CHIP0402'     | ''          | ''            | ''        
 '10K'        | '1%'      | '1/16W'  | '0402LF'  | 'EMPTY'  | 'TMP_QCS31002FB26'(!)   = 'End of Design' | 'Comp-Approve'     | 'CS31002FB26'           |'R0402'| '(R0402-0201)'                 | '10K'     | '1%'    | '1/16W'  | 'IO'       | 'RES CHIP 10K 1/16W +-1% (0402)'                   | 'CHIP0402'     | ''          | ''            | ''        
 '2.7K'       | '1%'      | '1/16W'  | '0402LF'  | 'CHIP'   | 'TMP_QCS22702FB14'(!)   = 'End of Design' | 'Comp-Approve'     | 'CS22702FB14'           |'R0402'| '(R0402-0201)'                 | '2.7K'    | '1%'    | '1/16W ' | 'DISCRETE' | 'RES CHIP 2.7K 1/16W +-1%(0402)'                   | 'CHIP0402 '    | ''          | ''            | ''        
 '2.7K'       | '1%'      | '1/16W'  | '0402LF'  | 'EMPTY'  | 'TMP_QCS22702FB14'(!)   = 'End of Design' | 'Comp-Approve'     | 'CS22702FB14'           |'R0402'| '(R0402-0201)'                 | '2.7K'    | '1%'    | '1/16W ' | 'IO'       | 'RES CHIP 2.7K 1/16W +-1%(0402)'                   | 'CHIP0402 '    | ''          | ''            | ''        
 '402K'       | '1%'      | '1/16W'  | '0402LF'  | 'CHIP'   | 'TMP_QCS44022FB25'(!)   = 'End of Design' | 'Comp-Approve'     | 'CS44022FB25'           |'R0402'| '(R0402-0201)'                 | '402K'    | '1%'    | '1/16W ' | 'DISCRETE' | 'RES CHIP 402K 1/16W +-1% (0402)'                  | 'CHIP0402 '    | ''          | ''            | ''        
 '402K'       | '1%'      | '1/16W'  | '0402LF'  | 'EMPTY'  | 'TMP_QCS44022FB25'(!)   = 'End of Design' | 'Comp-Approve'     | 'CS44022FB25'           |'R0402'| '(R0402-0201)'                 | '402K'    | '1%'    | '1/16W ' | 'IO'       | 'RES CHIP 402K 1/16W +-1% (0402)'                  | 'CHIP0402 '    | ''          | ''            | ''        
 '511K'       | '1%'      | '1/10W'  | '0603LF ' | 'CHIP'   | 'TMP_QCS45113F900'(!)   = 'End of Design' | 'Comp-Approve'     | 'CS45113F900'           |'R0603'| '(SMR0603AW)'                  | '511K'    | '1%'    | '1/10W ' | 'DISCRETE' | 'RES CHIP 511K 1/10W +-1%(0603)'                   | 'CHIP0603 '    | ''          | ''            | ''        
 '511K'       | '1%'      | '1/10W'  | '0603LF ' | 'EMPTY'  | 'TMP_QCS45113F900'(!)   = 'End of Design' | 'Comp-Approve'     | 'CS45113F900'           |'R0603'| '(SMR0603AW)'                  | '511K'    | '1%'    | '1/10W ' | 'IO'       | 'RES CHIP 511K 1/10W +-1%(0603)'                   | 'CHIP0603 '    | ''          | ''            | ''        
 '220'        | '5%'      | '1/2W'   | '1210LF ' | 'CHIP'   | 'TMP_QCS12207J300'(!)   = ''              | ''                 | 'CS12207J300'           |'R1210'| '(SMR1210AW)'                  | '220'     | '5%'    | '1/2W'   | 'DISCRETE' | 'RES CHIP 220 1/2W +-5%(1210)'                     | 'CHIP1210 '    | ''          | ''            | ''        
 '220'        | '5%'      | '1/2W'   | '1210LF ' | 'EMPTY'  | 'TMP_QCS12207J300'(!)   = ''              | ''                 | 'CS12207J300'           |'R1210'| '(SMR1210AW)'                  | '220'     | '5%'    | '1/2W'   | 'IO'       | 'RES CHIP 220 1/2W +-5%(1210)'                     | 'CHIP1210 '    | ''          | ''            | ''        
 '56'         | '5%'      | '1/10W'  | '0603LF ' | 'CHIP'   | 'TMP_QCS05603J930'(!)   = ''              | ''                 | 'CS05603J930'           |'R0603'| '(SMR0603AW)'                  | '56'      | '5%'    | '1/10W ' | 'DISCRETE' | 'RESISTOR CHIP 56 1/10W,+-5%(1608)'                | 'CHIP0603 '    | ''          | ''            | ''        
 '56'         | '5%'      | '1/10W'  | '0603LF ' | 'EMPTY'  | 'TMP_QCS05603J930'(!)   = ''              | ''                 | 'CS05603J930'           |'R0603'| '(SMR0603AW)'                  | '56'      | '5%'    | '1/10W ' | 'IO'       | 'RESISTOR CHIP 56 1/10W,+-5%(1608)'                | 'CHIP0603 '    | ''          | ''            | ''        
 '2.55K'      | '1%'      | '1/16W ' | '0402LF ' | 'CHIP'   | 'TMP_QCS22552FB01'(!)   = 'End of Design' | 'Comp-Approve'     | 'CS22552FB01'           |'R0402'| '(R0402-0201)'                 | '2.55K'   | '1%'    | '1/16W ' | 'DISCRETE' | 'RES CHIP 2.55K 1/16W +-1%(0402)'                  | 'CHIP0402 '    | ''          | ''            | ''        
 '2.55K'      | '1%'      | '1/16W ' | '0402LF ' | 'EMPTY'  | 'TMP_QCS22552FB01'(!)   = 'End of Design' | 'Comp-Approve'     | 'CS22552FB01'           |'R0402'| '(R0402-0201)'                 | '2.55K'   | '1%'    | '1/16W ' | 'IO'       | 'RES CHIP 2.55K 1/16W +-1%(0402)'                  | 'CHIP0402 '    | ''          | ''            | ''        
 '9.53K'      | '1%'      | '1/16W ' | '0402LF ' | 'CHIP'   | 'TMP_QCS29532FB10'(!)   = 'End of Design' | 'Comp-Approve'     | 'CS29532FB10'           |'R0402'| '(R0402-0201)'                 | '9.53K'   | '1%'    | '1/16W ' | 'DISCRETE' | 'RES CHIP 9.53K 1/16W +-1%(0402)'                  | 'CHIP0402 '    | ''          | ''            | ''        
 '9.53K'      | '1%'      | '1/16W ' | '0402LF ' | 'EMPTY'  | 'TMP_QCS29532FB10'(!)   = 'End of Design' | 'Comp-Approve'     | 'CS29532FB10'           |'R0402'| '(R0402-0201)'                 | '9.53K'   | '1%'    | '1/16W ' | 'IO'       | 'RES CHIP 9.53K 1/16W +-1%(0402)'                  | 'CHIP0402 '    | ''          | ''            | ''        
 '909'        | '1%'      | '1/16W'  | '0402LF'  | 'CHIP'   | 'TMP_QCS19092FB17'(!)   = 'End of Design' | 'Comp-Approve'     | 'CS19092FB17'           |'R0402'| '(R0402-0201)'                 | '909'     | '1%'    | '1/16W'  | 'DISCRETE' | 'RES CHIP 909(1/16W,1%,0402)'                      | 'CHIP0402'     | ''          | ''            | ''        
 '909'        | '1%'      | '1/16W'  | '0402LF'  | 'EMPTY'  | 'TMP_QCS19092FB17'(!)   = 'End of Design' | 'Comp-Approve'     | 'CS19092FB17'           |'R0402'| '(R0402-0201)'                 | '909'     | '1%'    | '1/16W'  | 'IO'       | 'RES CHIP 909(1/16W,1%,0402)'                      | 'CHIP0402'     | ''          | ''            | ''        
 '51'         | '1%'      | '1/16W ' | '0402LF ' | 'CHIP'   | 'TMP_QCS05102FB09'(!)   = 'End of Design' | 'Comp-Approve'     | 'CS05102FB09'           |'R0402'| '(R0402-0201)'                 | '51'      | '1%'    | '1/16W ' | 'DISCRETE' | 'RES CHIP 51 1/16W +-1% (0402)'                    | 'CHIP0402 '    | ''          | ''            | ''        
 '51'         | '1%'      | '1/16W ' | '0402LF ' | 'EMPTY'  | 'TMP_QCS05102FB09'(!)   = 'End of Design' | 'Comp-Approve'     | 'CS05102FB09'           |'R0402'| '(R0402-0201)'                 | '51'      | '1%'    | '1/16W ' | 'IO'       | 'RES CHIP 51 1/16W +-1% (0402)'                    | 'CHIP0402 '    | ''          | ''            | ''        
 '59K'        | '1%'      | '1/16W ' | '0402LF ' | 'CHIP'   | 'TMP_QCS35902FB03'(!)   = ''              | ''                 | 'CS35902FB03'           |'R0402'| '(R0402-0201)'                 | '59K'     | '1%'    | '1/16W ' | 'DISCRETE' | 'RESISTOR CHIP 59K 1/16W +-1%(0402)'               | 'CHIP0402 '    | ''          | ''            | ''        
 '59K'        | '1%'      | '1/16W ' | '0402LF ' | 'EMPTY'  | 'TMP_QCS35902FB03'(!)   = ''              | ''                 | 'CS35902FB03'           |'R0402'| '(R0402-0201)'                 | '59K'     | '1%'    | '1/16W ' | 'IO'       | 'RESISTOR CHIP 59K 1/16W +-1%(0402)'               | 'CHIP0402 '    | ''          | ''            | ''        
 '0.39'       | '1%'      | '1/10W'  | '0603LF ' | 'CHIP'   | 'TMP_QCS+3903F900'(!)   = ''              | ''                 | 'CS+3903F900'           |'R0603'| '(SMR0603AW)'                  | '0.39'    | '1%'    | '1/10W ' | 'DISCRETE' | 'RES CHIP 0.39 1/10W +-1%(0603)'                   | 'CHIP0603'     | ''          | ''            | ''        
 '0.39'       | '1%'      | '1/10W'  | '0603LF ' | 'EMPTY'  | 'TMP_QCS+3903F900'(!)   = ''              | ''                 | 'CS+3903F900'           |'R0603'| '(SMR0603AW)'                  | '0.39'    | '1%'    | '1/10W ' | 'IO'       | 'RES CHIP 0.39 1/10W +-1%(0603)'                   | 'CHIP0603'     | ''          | ''            | ''        
 '2.61K'      | '1%'      | '1/16W ' | '0402LF ' | 'CHIP'   | 'TMP_QCS22612FB15'(!)   = 'End of Design' | 'Comp-Approve'     | 'CS22612FB15'           |'R0402'| '(R0402-0201)'                 | '2.61K'   | '1%'    | '1/16W ' | 'DISCRETE' | 'RES CHIP 2.61K 1/16W +-1%(0402)'                  | 'CHIP0402 '    | ''          | ''            | ''        
 '2.61K'      | '1%'      | '1/16W ' | '0402LF ' | 'EMPTY'  | 'TMP_QCS22612FB15'(!)   = 'End of Design' | 'Comp-Approve'     | 'CS22612FB15'           |'R0402'| '(R0402-0201)'                 | '2.61K'   | '1%'    | '1/16W ' | 'IO'       | 'RES CHIP 2.61K 1/16W +-1%(0402)'                  | 'CHIP0402 '    | ''          | ''            | ''        
 '52.3K'      | '1%'      | '1/10W'  | '0603LF ' | 'CHIP'   | 'TMP_QCS35233F916'(!)   = ''              | ''                 | 'CS35233F916'           |'R0603'| '(SMR0603AW)'                  | '52.3K'   | '1%'    | '1/10W ' | 'DISCRETE' | 'RES CHIP 52.3K 1/10W +-1% (0603)'                 | 'CHIP0603'     | ''          | ''            | ''        
 '52.3K'      | '1%'      | '1/10W'  | '0603LF ' | 'EMPTY'  | 'TMP_QCS35233F916'(!)   = ''              | ''                 | 'CS35233F916'           |'R0603'| '(SMR0603AW)'                  | '52.3K'   | '1%'    | '1/10W ' | 'IO'       | 'RES CHIP 52.3K 1/10W +-1% (0603)'                 | 'CHIP0603'     | ''          | ''            | ''        
 '6.49K'      | '1%'      | '1/16W ' | '0402LF ' | 'CHIP'   | 'TMP_QCS26492FB23'(!)   = 'End of Design' | 'Comp-Approve'     | 'CS26492FB23'           |'R0402'| '(R0402-0201)'                 | '6.49K'   | '1%'    | '1/16W ' | 'DISCRETE' | 'RES CHIP 6.49K 1/16W +-1%(0402)'                  | 'CHIP0402 '    | ''          | ''            | ''        
 '6.49K'      | '1%'      | '1/16W ' | '0402LF ' | 'EMPTY'  | 'TMP_QCS26492FB23'(!)   = 'End of Design' | 'Comp-Approve'     | 'CS26492FB23'           |'R0402'| '(R0402-0201)'                 | '6.49K'   | '1%'    | '1/16W ' | 'IO'       | 'RES CHIP 6.49K 1/16W +-1%(0402)'                  | 'CHIP0402 '    | ''          | ''            | ''        
 '1.47K'      | '1%'      | '1/16W ' | '0402LF ' | 'CHIP'   | 'TMP_QCS21472FB21'(!)   = 'End of Design' | 'Comp-Approve'     | 'CS21472FB21'           |'R0402'| '(R0402-0201)'                 | '1.47K'   | '1%'    | '1/16W ' | 'DISCRETE' | 'RES CHIP 1.47K 1/16W +-1% (0402)'                 | 'CHIP0402 '    | ''          | ''            | ''        
 '1.47K'      | '1%'      | '1/16W ' | '0402LF ' | 'EMPTY'  | 'TMP_QCS21472FB21'(!)   = 'End of Design' | 'Comp-Approve'     | 'CS21472FB21'           |'R0402'| '(R0402-0201)'                 | '1.47K'   | '1%'    | '1/16W ' | 'IO'       | 'RES CHIP 1.47K 1/16W +-1% (0402)'                 | 'CHIP0402 '    | ''          | ''            | ''        
 '9.1K'       | '0.5%'    | '1/10W'  | '0603LF ' | 'CHIP'   | 'TMP_QCS29103D915'(!)   = ''              | ''                 | 'CS29103D915'           |'R0603'| '(SMR0603AW)'                  | '9.1K'    | '0.5%'  | '1/10W ' | 'DISCRETE' | 'RES CHIP 9.1K 1/10W +-0.5%(0603)'                 | 'CHIP0603'     | ''          | ''            | ''        
 '9.1K'       | '0.5%'    | '1/10W'  | '0603LF ' | 'EMPTY'  | 'TMP_QCS29103D915'(!)   = ''              | ''                 | 'CS29103D915'           |'R0603'| '(SMR0603AW)'                  | '9.1K'    | '0.5%'  | '1/10W ' | 'IO'       | 'RES CHIP 9.1K 1/10W +-0.5%(0603)'                 | 'CHIP0603'     | ''          | ''            | ''        
 '4.32K'      | '1%'      | '1/16W'  | '0402LF'  | 'CHIP'   | 'TMP_QCS24322FB14'(!)   = 'End of Design' | 'Comp-Approve'     | 'CS24322FB14'           |'R0402'| '(R0402-0201)'                 | '4.32K'   | '1%'    | '1/16W'  | 'DISCRETE' | 'RES CHIP 4.32K 1/16W +-1%(0402)'                  | 'CHIP0402'     | ''          | ''            | ''        
 '4.32K'      | '1%'      | '1/16W'  | '0402LF'  | 'EMPTY'  | 'TMP_QCS24322FB14'(!)   = 'End of Design' | 'Comp-Approve'     | 'CS24322FB14'           |'R0402'| '(R0402-0201)'                 | '4.32K'   | '1%'    | '1/16W'  | 'IO'       | 'RES CHIP 4.32K 1/16W +-1%(0402)'                  | 'CHIP0402'     | ''          | ''            | ''        
 '7.5K'       | '1%'      | '1/16W'  | '0402LF'  | 'CHIP'   | 'TMP_QCS27502FB11'(!)   = 'End of Design' | 'Comp-Approve'     | 'CS27502FB11'           |'R0402'| '(R0402-0201)'                 | '7.5K'    | '1%'    | '1/16W'  | 'DISCRETE' | 'RES CHIP 7.5K 1/16W +-1% (0402)'                  | 'CHIP0402'     | ''          | ''            | ''        
 '7.5K'       | '1%'      | '1/16W'  | '0402LF'  | 'EMPTY'  | 'TMP_QCS27502FB11'(!)   = 'End of Design' | 'Comp-Approve'     | 'CS27502FB11'           |'R0402'| '(R0402-0201)'                 | '7.5K'    | '1%'    | '1/16W'  | 'IO'       | 'RES CHIP 7.5K 1/16W +-1% (0402)'                  | 'CHIP0402'     | ''          | ''            | ''        
 '300'        | '1%'      | '1/16W ' | '0402LF ' | 'CHIP'   | 'TMP_QCS13002FB00'(!)   = 'End of Design' | 'Comp-Approve'     | 'CS13002FB00'           |'R0402'| '(R0402-0201)'                 | '300'     | '1%'    | '1/16W ' | 'DISCRETE' | 'RES CHIP 300 1/16W +-1%(0402)'                    | 'CHIP0402 '    | ''          | ''            | ''        
 '300'        | '1%'      | '1/16W ' | '0402LF ' | 'EMPTY'  | 'TMP_QCS13002FB00'(!)   = 'End of Design' | 'Comp-Approve'     | 'CS13002FB00'           |'R0402'| '(R0402-0201)'                 | '300'     | '1%'    | '1/16W ' | 'IO'       | 'RES CHIP 300 1/16W +-1%(0402)'                    | 'CHIP0402 '    | ''          | ''            | ''        
 '120'        | '5%'      | '1/10W'  | '0603LF ' | 'CHIP'   | 'TMP_QCS11203J936'(!)   = ''              | ''                 | 'CS11203J936'           |'R0603'| '(SMR0603AW)'                  | '120'     | '5%'    | '1/10W ' | 'DISCRETE' | 'RES CHIP 120 1/10W +-5%(0603)'                    | 'CHIP0603'     | ''          | ''            | ''        
 '120'        | '5%'      | '1/10W'  | '0603LF ' | 'EMPTY'  | 'TMP_QCS11203J936'(!)   = ''              | ''                 | 'CS11203J936'           |'R0603'| '(SMR0603AW)'                  | '120'     | '5%'    | '1/10W ' | 'IO'       | 'RES CHIP 120 1/10W +-5%(0603)'                    | 'CHIP0603'     | ''          | ''            | ''        
 '150'        | '5%'      | '1/10W'  | '0603LF ' | 'CHIP'   | 'TMP_QCS11503J937'(!)   = ''              | ''                 | 'CS11503J937'           |'R0603'| '(SMR0603AW)'                  | '150'     | '5%'    | '1/10W ' | 'DISCRETE' | 'RES CHIP 150 1/10W +-5%(0603)'                    | 'CHIP0603'     | ''          | ''            | ''        
 '150'        | '5%'      | '1/10W'  | '0603LF ' | 'EMPTY'  | 'TMP_QCS11503J937'(!)   = ''              | ''                 | 'CS11503J937'           |'R0603'| '(SMR0603AW)'                  | '150'     | '5%'    | '1/10W ' | 'IO'       | 'RES CHIP 150 1/10W +-5%(0603)'                    | 'CHIP0603'     | ''          | ''            | ''        
 '93.1K'      | '1%'      | '1/16W ' | '0402LF ' | 'CHIP'   | 'TMP_QCS39312FB15'(!)   = 'End of Design' | 'Comp-Approve'     | 'CS39312FB15'           |'R0402'| '(R0402-0201)'                 | '93.1K'   | '1%'    | '1/16W ' | 'DISCRETE' | 'RES CHIP 93.1K 1/16W +-1%(0402)'                  | 'CHIP0402 '    | ''          | ''            | ''        
 '93.1K'      | '1%'      | '1/16W ' | '0402LF ' | 'EMPTY'  | 'TMP_QCS39312FB15'(!)   = 'End of Design' | 'Comp-Approve'     | 'CS39312FB15'           |'R0402'| '(R0402-0201)'                 | '93.1K'   | '1%'    | '1/16W ' | 'IO'       | 'RES CHIP 93.1K 1/16W +-1%(0402)'                  | 'CHIP0402 '    | ''          | ''            | ''        
 '10.2K'      | '1%'      | '1/16W ' | '0402LF ' | 'CHIP'   | 'TMP_QCS31022FB17'(!)   = 'End of Design' | 'Comp-Approve'     | 'CS31022FB17'           |'R0402'| '(R0402-0201)'                 | '10.2K'   | '1%'    | '1/16W ' | 'DISCRETE' | 'RES CHIP 10.2K 1/16W +-1%(0402)'                  | 'CHIP0402 '    | ''          | ''            | ''        
 '10.2K'      | '1%'      | '1/16W ' | '0402LF ' | 'EMPTY'  | 'TMP_QCS31022FB17'(!)   = 'End of Design' | 'Comp-Approve'     | 'CS31022FB17'           |'R0402'| '(R0402-0201)'                 | '10.2K'   | '1%'    | '1/16W ' | 'IO'       | 'RES CHIP 10.2K 1/16W +-1%(0402)'                  | 'CHIP0402 '    | ''          | ''            | ''        
 '1.37K'      | '1%'      | '1/16W ' | '0402LF ' | 'CHIP'   | 'TMP_QCS21372FB19'(!)   = 'End of Design' | 'Comp-Approve'     | 'CS21372FB19'           |'R0402'| '(R0402-0201)'                 | '1.37K'   | '1%'    | '1/16W ' | 'DISCRETE' | 'RES CHIP 1.37K 1/16W +-1%(0402)'                  | 'CHIP0402 '    | ''          | ''            | ''        
 '1.37K'      | '1%'      | '1/16W ' | '0402LF ' | 'EMPTY'  | 'TMP_QCS21372FB19'(!)   = 'End of Design' | 'Comp-Approve'     | 'CS21372FB19'           |'R0402'| '(R0402-0201)'                 | '1.37K'   | '1%'    | '1/16W ' | 'IO'       | 'RES CHIP 1.37K 1/16W +-1%(0402)'                  | 'CHIP0402 '    | ''          | ''            | ''        
 '90.9K'      | '1%'      | '1/16W ' | '0402LF ' | 'CHIP'   | 'TMP_QCS39092FB11'(!)   = 'End of Design' | 'Comp-Approve'     | 'CS39092FB11'           |'R0402'| '(R0402-0201)'                 | '90.9K'   | '1%'    | '1/16W ' | 'DISCRETE' | 'RES CHIP 90.9K 1/16W +-1% (0402)'                 | 'CHIP0402 '    | ''          | ''            | ''        
 '90.9K'      | '1%'      | '1/16W ' | '0402LF ' | 'EMPTY'  | 'TMP_QCS39092FB11'(!)   = 'End of Design' | 'Comp-Approve'     | 'CS39092FB11'           |'R0402'| '(R0402-0201)'                 | '90.9K'   | '1%'    | '1/16W ' | 'IO'       | 'RES CHIP 90.9K 1/16W +-1% (0402)'                 | 'CHIP0402 '    | ''          | ''            | ''        
 '45.3K'      | '1%'      | '1/16W ' | '0402LF ' | 'CHIP'   | 'TMP_QCS34532FB18'(!)   = 'End of Design' | 'Comp-Approve'     | 'CS34532FB18'           |'R0402'| '(R0402-0201)'                 | '45.3K'   | '1%'    | '1/16W ' | 'DISCRETE' | 'RES CHIP 45.3K 1/16W +-1% (0402)'                 | 'CHIP0402 '    | ''          | ''            | ''        
 '45.3K'      | '1%'      | '1/16W ' | '0402LF ' | 'EMPTY'  | 'TMP_QCS34532FB18'(!)   = 'End of Design' | 'Comp-Approve'     | 'CS34532FB18'           |'R0402'| '(R0402-0201)'                 | '45.3K'   | '1%'    | '1/16W ' | 'IO'       | 'RES CHIP 45.3K 1/16W +-1% (0402)'                 | 'CHIP0402 '    | ''          | ''            | ''        
 '5.49K'      | '1%'      | '1/16W ' | '0402LF ' | 'CHIP'   | 'TMP_QCS25492FB12'(!)   = 'End of Design' | 'Comp-Approve'     | 'CS25492FB12'           |'R0402'| '(R0402-0201)'                 | '5.49K'   | '1%'    | '1/16W ' | 'DISCRETE' | 'RES CHIP 5.49K 1/16W +-1%(0402)'                  | 'CHIP0402 '    | ''          | ''            | ''        
 '5.49K'      | '1%'      | '1/16W ' | '0402LF ' | 'EMPTY'  | 'TMP_QCS25492FB12'(!)   = 'End of Design' | 'Comp-Approve'     | 'CS25492FB12'           |'R0402'| '(R0402-0201)'                 | '5.49K'   | '1%'    | '1/16W ' | 'IO'       | 'RES CHIP 5.49K 1/16W +-1%(0402)'                  | 'CHIP0402 '    | ''          | ''            | ''        
 '5.1K'       | '1%'      | '1/10W'  | '0603LF ' | 'CHIP'   | 'TMP_QCS25103F917'(!)   = 'End of Design' | 'Comp-Release Qty' | 'CS25103F917'           |'R0603'| '(SMR0603AW)'                  | '5.1K'    | '1%'    | '1/10W ' | 'DISCRETE' | 'RES CHIP 5.1K 1/10W +-1% (0603)'                  | 'CHIP0603'     | ''          | ''            | ''        
 '5.1K'       | '1%'      | '1/10W'  | '0603LF ' | 'EMPTY'  | 'TMP_QCS25103F917'(!)   = 'End of Design' | 'Comp-Release Qty' | 'CS25103F917'           |'R0603'| '(SMR0603AW)'                  | '5.1K'    | '1%'    | '1/10W ' | 'IO'       | 'RES CHIP 5.1K 1/10W +-1% (0603)'                  | 'CHIP0603'     | ''          | ''            | ''        
 '10'         | '1%'      | '1/16W'  | '0402LF'  | 'CHIP'   | 'TMP_QCS01002FB21'(!)   = 'End of Design' | 'Comp-Approve'     | 'CS01002FB21'           |'R0402'| '(R0402-0201)'                 | '10'      | '1%'    | '1/16W'  | 'DISCRETE' | 'RES CHIP 10 1/16W +-1%(0402)'                     | 'CHIP0402'     | ''          | ''            | ''        
 '10'         | '1%'      | '1/16W'  | '0402LF'  | 'EMPTY'  | 'TMP_QCS01002FB21'(!)   = 'End of Design' | 'Comp-Approve'     | 'CS01002FB21'           |'R0402'| '(R0402-0201)'                 | '10'      | '1%'    | '1/16W'  | 'IO'       | 'RES CHIP 10 1/16W +-1%(0402)'                     | 'CHIP0402'     | ''          | ''            | ''        
 '56'         | '1%'      | '1/16W'  | '0402LF'  | 'CHIP'   | 'TMP_QCS05602FB15'(!)   = 'End of Design' | 'Comp-Approve'     | 'CS05602FB15'           |'R0402'| '(R0402-0201)'                 | '56'      | '1%'    | '1/16W'  | 'DISCRETE' | 'RESISTOR CHIP 56 1/16W +-1% (0402)'               | 'CHIP0402'     | ''          | ''            | ''        
 '56'         | '1%'      | '1/16W'  | '0402LF'  | 'EMPTY'  | 'TMP_QCS05602FB15'(!)   = 'End of Design' | 'Comp-Approve'     | 'CS05602FB15'           |'R0402'| '(R0402-0201)'                 | '56'      | '1%'    | '1/16W'  | 'IO'       | 'RESISTOR CHIP 56 1/16W +-1% (0402)'               | 'CHIP0402'     | ''          | ''            | ''        
 '82.5'       | '1%'      | '1/16W'  | '0402LF'  | 'CHIP'   | 'TMP_QCS08252FB11'(!)   = 'End of Design' | 'Comp-Approve'     | 'CS08252FB11'           |'R0402'| '(R0402-0201)'                 | '82.5'    | '1%'    | '1/16W'  | 'DISCRETE' | 'RES CHIP 82.5 1/16W +-1%(0402)'                   | 'CHIP0402'     | ''          | ''            | ''        
 '82.5'       | '1%'      | '1/16W'  | '0402LF'  | 'EMPTY'  | 'TMP_QCS08252FB11'(!)   = 'End of Design' | 'Comp-Approve'     | 'CS08252FB11'           |'R0402'| '(R0402-0201)'                 | '82.5'    | '1%'    | '1/16W'  | 'IO'       | 'RES CHIP 82.5 1/16W +-1%(0402)'                   | 'CHIP0402'     | ''          | ''            | ''        
 '100'        | '1%'      | '1/16W'  | '0402LF'  | 'CHIP'   | 'TMP_QCS11002FB22'(!)   = 'End of Design' | 'Comp-Approve'     | 'CS11002FB22'           |'R0402'| '(R0402-0201)'                 | '100'     | '1%'    | '1/16W'  | 'DISCRETE' | 'RES CHIP 100 1/16W +-1%(0402)'                    | 'CHIP0402'     | ''          | ''            | ''        
 '100'        | '1%'      | '1/16W'  | '0402LF'  | 'EMPTY'  | 'TMP_QCS11002FB22'(!)   = 'End of Design' | 'Comp-Approve'     | 'CS11002FB22'           |'R0402'| '(R0402-0201)'                 | '100'     | '1%'    | '1/16W'  | 'IO'       | 'RES CHIP 100 1/16W +-1%(0402)'                    | 'CHIP0402'     | ''          | ''            | ''        
 '100'        | '5%'      | '1/16W'  | '0402LF'  | 'CHIP'   | 'TMP_QCS11002JB32'(!)   = 'End of Design' | 'Comp-Approve'     | 'CS11002JB32'           |'R0402'| '(R0402-0201)'                 | '100'     | '5%'    | '1/16W'  | 'DISCRETE' | 'RES CHIP 100 1/16W +-5% (0402)'                   | 'CHIP0402'     | ''          | ''            | ''        
 '100'        | '5%'      | '1/16W'  | '0402LF'  | 'EMPTY'  | 'TMP_QCS11002JB32'(!)   = 'End of Design' | 'Comp-Approve'     | 'CS11002JB32'           |'R0402'| '(R0402-0201)'                 | '100'     | '5%'    | '1/16W'  | 'IO'       | 'RES CHIP 100 1/16W +-5% (0402)'                   | 'CHIP0402'     | ''          | ''            | ''        
 '178'        | '1%'      | '1/10W'  | '0603LF'  | 'CHIP'   | 'TMP_QCS11783F912'(!)   = ''              | ''                 | 'CS11783F912'           |'R0603'| '(SMR0603AW)'                  | '178'     | '1%'    | '1/10W'  | 'DISCRETE' | 'RES CHIP 178 1/10W +-1%(0603)'                    | 'CHIP0603'     | ''          | ''            | ''        
 '178'        | '1%'      | '1/10W'  | '0603LF'  | 'EMPTY'  | 'TMP_QCS11783F912'(!)   = ''              | ''                 | 'CS11783F912'           |'R0603'| '(SMR0603AW)'                  | '178'     | '1%'    | '1/10W'  | 'IO'       | 'RES CHIP 178 1/10W +-1%(0603)'                    | 'CHIP0603'     | ''          | ''            | ''        
 '301'        | '1%'      | '1/16W'  | '0402LF'  | 'CHIP'   | 'TMP_QCS13012FB14'(!)   = 'End of Design' | 'Comp-Approve'     | 'CS13012FB14'           |'R0402'| '(R0402-0201)'                 | '301'     | '1%'    | '1/16W'  | 'DISCRETE' | 'RES CHIP 301 1/16W +-1%(0402)'                    | 'CHIP0402'     | ''          | ''            | ''        
 '301'        | '1%'      | '1/16W'  | '0402LF'  | 'EMPTY'  | 'TMP_QCS13012FB14'(!)   = 'End of Design' | 'Comp-Approve'     | 'CS13012FB14'           |'R0402'| '(R0402-0201)'                 | '301'     | '1%'    | '1/16W'  | 'IO'       | 'RES CHIP 301 1/16W +-1%(0402)'                    | 'CHIP0402'     | ''          | ''            | ''        
 '340'        | '1%'      | '1/10W'  | '0603LF'  | 'CHIP'   | 'TMP_QCS13403F902'(!)   = ''              | ''                 | 'CS13403F902'           |'R0603'| '(SMR0603AW)'                  | '340'     | '1%'    | '1/10W'  | 'DISCRETE' | 'RES CHIP 340 1/10W +-1%(0603)'                    | 'CHIP0402'     | ''          | ''            | ''        
 '340'        | '1%'      | '1/10W'  | '0603LF'  | 'EMPTY'  | 'TMP_QCS13403F902'(!)   = ''              | ''                 | 'CS13403F902'           |'R0603'| '(SMR0603AW)'                  | '340'     | '1%'    | '1/10W'  | 'IO'       | 'RES CHIP 340 1/10W +-1%(0603)'                    | 'CHIP0402'     | ''          | ''            | ''        
 '953'        | '1%'      | '1/16W'  | '0402LF'  | 'CHIP'   | 'TMP_QCS19532FB00'(!)   = 'End of Design' | 'Comp-Approve'     | 'CS19532FB00'           |'R0402'| '(R0402-0201)'                 | '953'     | '1%'    | '1/16W'  | 'DISCRETE' | 'RES CHIP 953 1/16W +-1% (0402)'                   | 'CHIP0402'     | ''          | ''            | ''        
 '953'        | '1%'      | '1/16W'  | '0402LF'  | 'EMPTY'  | 'TMP_QCS19532FB00'(!)   = 'End of Design' | 'Comp-Approve'     | 'CS19532FB00'           |'R0402'| '(R0402-0201)'                 | '953'     | '1%'    | '1/16W'  | 'IO'       | 'RES CHIP 953 1/16W +-1% (0402)'                   | 'CHIP0402'     | ''          | ''            | ''        
 '1K'         | '5%'      | '1/16W'  | '0402LF'  | 'CHIP'   | 'TMP_QCS21002JB34'(!)   = 'End of Design' | 'Comp-Approve'     | 'CS21002JB34'           |'R0402'| '(R0402-0201)'                 | '1K'      | '5%'    | '1/16W'  | 'DISCRETE' | 'RES CHIP 1K 1/16W 5%(0402)'                       | 'CHIP0402'     | ''          | ''            | ''        
 '1K'         | '5%'      | '1/16W'  | '0402LF'  | 'EMPTY'  | 'TMP_QCS21002JB34'(!)   = 'End of Design' | 'Comp-Approve'     | 'CS21002JB34'           |'R0402'| '(R0402-0201)'                 | '1K'      | '5%'    | '1/16W'  | 'IO'       | 'RES CHIP 1K 1/16W 5%(0402)'                       | 'CHIP0402'     | ''          | ''            | ''        
 '1.21K'      | '1%'      | '1/16W'  | '0402LF'  | 'CHIP'   | 'TMP_QCS21212FB18'(!)   = 'End of Design' | 'Comp-Approve'     | 'CS21212FB18'           |'R0402'| '(R0402-0201)'                 | '1.21K'   | '1%'    | '1/16W'  | 'DISCRETE' | 'RES CHIP 1.21K 1/16W +-1%(0402)'                  | 'CHIP0402'     | ''          | ''            | ''        
 '1.21K'      | '1%'      | '1/16W'  | '0402LF'  | 'EMPTY'  | 'TMP_QCS21212FB18'(!)   = 'End of Design' | 'Comp-Approve'     | 'CS21212FB18'           |'R0402'| '(R0402-0201)'                 | '1.21K'   | '1%'    | '1/16W'  | 'IO'       | 'RES CHIP 1.21K 1/16W +-1%(0402)'                  | 'CHIP0402'     | ''          | ''            | ''        
 '2K'         | '1%'      | '1/16W'  | '0402LF'  | 'CHIP'   | 'TMP_QCS22002FB19'(!)   = 'End of Design' | 'Comp-Approve'     | 'CS22002FB19'           |'R0402'| '(R0402-0201)'                 | '2K'      | '1%'    | '1/16W'  | 'DISCRETE' | 'RES CHIP 2K 1/16W +-1%(0402)'                     | 'CHIP0402'     | ''          | ''            | ''        
 '2K'         | '1%'      | '1/16W'  | '0402LF'  | 'EMPTY'  | 'TMP_QCS22002FB19'(!)   = 'End of Design' | 'Comp-Approve'     | 'CS22002FB19'           |'R0402'| '(R0402-0201)'                 | '2K'      | '1%'    | '1/16W'  | 'IO'       | 'RES CHIP 2K 1/16W +-1%(0402)'                     | 'CHIP0402'     | ''          | ''            | ''        
 '2.2'        | '5%'      | '1/16W'  | '0402LF'  | 'CHIP'   | 'TMP_QCS-2202JB25'(!)   = 'End of Design' | 'Comp-Approve'     | 'CS-2202JB25'           |'R0402'| '(R0402-0201)'                 | '2.2'     | '5%'    | '1/16W'  | 'DISCRETE' | 'RES CHIP 2.2 1/16W +-5%  (0402)'                  | 'CHIP0402'     | ''          | ''            | ''        
 '2.2'        | '5%'      | '1/16W'  | '0402LF'  | 'EMPTY'  | 'TMP_QCS-2202JB25'(!)   = 'End of Design' | 'Comp-Approve'     | 'CS-2202JB25'           |'R0402'| '(R0402-0201)'                 | '2.2'     | '5%'    | '1/16W'  | 'IO'       | 'RES CHIP 2.2 1/16W +-5%  (0402)'                  | 'CHIP0402'     | ''          | ''            | ''        
 '2.2K'       | '1%'      | '1/16W'  | '0402LF'  | 'CHIP'   | 'TMP_QCS22202FB08'(!)   = 'End of Design' | 'Comp-Approve'     | 'CS22202FB08'           |'R0402'| '(R0402-0201)'                 | '2.2K'    | '1%'    | '1/16W'  | 'DISCRETE' | 'RES CHIP 2.2K 1/16W +-1%(0402)'                   | 'CHIP0402'     | ''          | ''            | ''        
 '2.2K'       | '1%'      | '1/16W'  | '0402LF'  | 'EMPTY'  | 'TMP_QCS22202FB08'(!)   = 'End of Design' | 'Comp-Approve'     | 'CS22202FB08'           |'R0402'| '(R0402-0201)'                 | '2.2K'    | '1%'    | '1/16W'  | 'IO'       | 'RES CHIP 2.2K 1/16W +-1%(0402)'                   | 'CHIP0402'     | ''          | ''            | ''        
 '2.26K'      | '1%'      | '1/16W'  | '0402LF'  | 'CHIP'   | 'TMP_QCS22262FB05'(!)   = 'End of Design' | 'Comp-Approve'     | 'CS22262FB05'           |'R0402'| '(R0402-0201)'                 | '2.26K'   | '1%'    | '1/16W'  | 'DISCRETE' | 'RES CHIP 2.26K 1/16W +-1%(0402)'                  | 'CHIP0402'     | ''          | ''            | ''        
 '2.26K'      | '1%'      | '1/16W'  | '0402LF'  | 'EMPTY'  | 'TMP_QCS22262FB05'(!)   = 'End of Design' | 'Comp-Approve'     | 'CS22262FB05'           |'R0402'| '(R0402-0201)'                 | '2.26K'   | '1%'    | '1/16W'  | 'IO'       | 'RES CHIP 2.26K 1/16W +-1%(0402)'                  | 'CHIP0402'     | ''          | ''            | ''        
 '2.8K'       | '1%'      | '1/16W'  | '0402LF'  | 'CHIP'   | 'TMP_QCS22802FB00'(!)   = ''              | ''                 | 'CS22802FB00'           |'R0402'| '(R0402-0201)'                 | '2.8K'    | '1%'    | '1/16W'  | 'DISCRETE' | 'RES CHIP 2.8K 1/16W +-1%(0402)'                   | 'CHIP0402'     | ''          | ''            | ''        
 '2.8K'       | '1%'      | '1/16W'  | '0402LF'  | 'EMPTY'  | 'TMP_QCS22802FB00'(!)   = ''              | ''                 | 'CS22802FB00'           |'R0402'| '(R0402-0201)'                 | '2.8K'    | '1%'    | '1/16W'  | 'IO'       | 'RES CHIP 2.8K 1/16W +-1%(0402)'                   | 'CHIP0402'     | ''          | ''            | ''        
 '3.3K'       | '1%'      | '1/16W'  | '0402LF'  | 'CHIP'   | 'TMP_QCS23302FB12'(!)   = 'End of Design' | 'Comp-Approve'     | 'CS23302FB12'           |'R0402'| '(R0402-0201)'                 | '3.3K'    | '1%'    | '1/16W'  | 'DISCRETE' | 'RES CHIP 3.3K 1/16W +-1%(0402)'                   | 'CHIP0402'     | ''          | ''            | ''        
 '3.3K'       | '1%'      | '1/16W'  | '0402LF'  | 'EMPTY'  | 'TMP_QCS23302FB12'(!)   = 'End of Design' | 'Comp-Approve'     | 'CS23302FB12'           |'R0402'| '(R0402-0201)'                 | '3.3K'    | '1%'    | '1/16W'  | 'IO'       | 'RES CHIP 3.3K 1/16W +-1%(0402)'                   | 'CHIP0402'     | ''          | ''            | ''        
 '5.1K'       | '1%'      | '1/16W'  | '0402LF'  | 'CHIP'   | 'TMP_QCS25102FB02'(!)   = 'End of Design' | 'Comp-Approve'     | 'CS25102FB02'           |'R0402'| '(R0402-0201)'                 | '5.1K'    | '1%'    | '1/16W'  | 'DISCRETE' | 'RES CHIP 5.1K 1/16W +-1%(0402)'                   | 'CHIP0402'     | ''          | ''            | ''        
 '5.1K'       | '1%'      | '1/16W'  | '0402LF'  | 'EMPTY'  | 'TMP_QCS25102FB02'(!)   = 'End of Design' | 'Comp-Approve'     | 'CS25102FB02'           |'R0402'| '(R0402-0201)'                 | '5.1K'    | '1%'    | '1/16W'  | 'IO'       | 'RES CHIP 5.1K 1/16W +-1%(0402)'                   | 'CHIP0402'     | ''          | ''            | ''        
 '5.11K'      | '1%'      | '1/16W'  | '0402LF'  | 'CHIP'   | 'TMP_QCS25112FB15'(!)   = 'End of Design' | 'Comp-Approve'     | 'CS25112FB15'           |'R0402'| '(R0402-0201)'                 | '5.11K'   | '1%'    | '1/16W'  | 'DISCRETE' | 'RES CHIP 5.11K 1/16W +-1%(0402)'                  | 'CHIP0402'     | ''          | ''            | ''        
 '5.11K'      | '1%'      | '1/16W'  | '0402LF'  | 'EMPTY'  | 'TMP_QCS25112FB15'(!)   = 'End of Design' | 'Comp-Approve'     | 'CS25112FB15'           |'R0402'| '(R0402-0201)'                 | '5.11K'   | '1%'    | '1/16W'  | 'IO'       | 'RES CHIP 5.11K 1/16W +-1%(0402)'                  | 'CHIP0402'     | ''          | ''            | ''        
 '7.15K'      | '1%'      | '1/16W'  | '0402LF'  | 'CHIP'   | 'TMP_QCS27152FB19'(!)   = ''              | ''                 | 'CS27152FB19'           |'R0402'| '(R0402-0201)'                 | '7.15K'   | '1%'    | '1/16W'  | 'DISCRETE' | 'RES CHIP 7.15K 1/16W +-1% (0402)'                 | 'CHIP0402'     | ''          | ''            | ''        
 '7.15K'      | '1%'      | '1/16W'  | '0402LF'  | 'EMPTY'  | 'TMP_QCS27152FB19'(!)   = ''              | ''                 | 'CS27152FB19'           |'R0402'| '(R0402-0201)'                 | '7.15K'   | '1%'    | '1/16W'  | 'IO'       | 'RES CHIP 7.15K 1/16W +-1% (0402)'                 | 'CHIP0402'     | ''          | ''            | ''        
 '11.3K'      | '1%'      | '1/16W'  | '0402LF'  | 'CHIP'   | 'TMP_QCS31132FB07'(!)   = 'End of Design' | 'Comp-Approve'     | 'CS31132FB07'           |'R0402'| '(R0402-0201)'                 | '11.3K'   | '1%'    | '1/16W'  | 'DISCRETE' | 'RES CHIP 11.3K 1/16W +-1%(0402)'                  | 'CHIP0402'     | ''          | ''            | ''        
 '11.3K'      | '1%'      | '1/16W'  | '0402LF'  | 'EMPTY'  | 'TMP_QCS31132FB07'(!)   = 'End of Design' | 'Comp-Approve'     | 'CS31132FB07'           |'R0402'| '(R0402-0201)'                 | '11.3K'   | '1%'    | '1/16W'  | 'IO'       | 'RES CHIP 11.3K 1/16W +-1%(0402)'                  | 'CHIP0402'     | ''          | ''            | ''        
 '13K'        | '1%'      | '1/16W'  | '0402LF'  | 'CHIP'   | 'TMP_QCS31302FB19'(!)   = 'End of Design' | 'Comp-Approve'     | 'CS31302FB19'           |'R0402'| '(R0402-0201)'                 | '13K'     | '1%'    | '1/16W'  | 'DISCRETE' | 'RES CHIP 13K 1/16W +-1%( 0402)'                   | 'CHIP0402'     | ''          | ''            | ''        
 '13K'        | '1%'      | '1/16W'  | '0402LF'  | 'EMPTY'  | 'TMP_QCS31302FB19'(!)   = 'End of Design' | 'Comp-Approve'     | 'CS31302FB19'           |'R0402'| '(R0402-0201)'                 | '13K'     | '1%'    | '1/16W'  | 'IO'       | 'RES CHIP 13K 1/16W +-1%( 0402)'                   | 'CHIP0402'     | ''          | ''            | ''        
 '18.2K'      | '1%'      | '1/16W'  | '0402LF'  | 'CHIP'   | 'TMP_QCS31822FB16'(!)   = 'End of Design' | 'Comp-Approve'     | 'CS31822FB16'           |'R0402'| '(R0402-0201)'                 | '18.2K'   | '1%'    | '1/16W'  | 'DISCRETE' | 'RES CHIP 18.2K 1/16W +-1%( 0402)'                 | 'CHIP0402'     | ''          | ''            | ''        
 '18.2K'      | '1%'      | '1/16W'  | '0402LF'  | 'EMPTY'  | 'TMP_QCS31822FB16'(!)   = 'End of Design' | 'Comp-Approve'     | 'CS31822FB16'           |'R0402'| '(R0402-0201)'                 | '18.2K'   | '1%'    | '1/16W'  | 'IO'       | 'RES CHIP 18.2K 1/16W +-1%( 0402)'                 | 'CHIP0402'     | ''          | ''            | ''        
 '20K'        | '5%'      | '1/16W'  | '0402LF'  | 'CHIP'   | 'TMP_QCS32002JB12'(!)   = 'End of Design' | 'Comp-Approve'     | 'CS32002JB12'           |'R0402'| '(R0402-0201)'                 | '20K'     | '5%'    | '1/16W'  | 'DISCRETE' | 'RES CHIP 20K 1/16W +-5% (0402)'                   | 'CHIP0402'     | ''          | ''            | ''        
 '20K'        | '5%'      | '1/16W'  | '0402LF'  | 'EMPTY'  | 'TMP_QCS32002JB12'(!)   = 'End of Design' | 'Comp-Approve'     | 'CS32002JB12'           |'R0402'| '(R0402-0201)'                 | '20K'     | '5%'    | '1/16W'  | 'IO'       | 'RES CHIP 20K 1/16W +-5% (0402)'                   | 'CHIP0402'     | ''          | ''            | ''        
 '61.9K'      | '1%'      | '1/16W'  | '0402LF'  | 'CHIP'   | 'TMP_QCS36192FB16'(!)   = 'End of Design' | 'Comp-Approve'     | 'CS36192FB16'           |'R0402'| '(R0402-0201)'                 | '61.9K'   | '1%'    | '1/16W'  | 'DISCRETE' | 'RES CHIP 61.9K 1/16W +-1%(0402)'                  | 'CHIP0402'     | ''          | ''            | ''        
 '61.9K'      | '1%'      | '1/16W'  | '0402LF'  | 'EMPTY'  | 'TMP_QCS36192FB16'(!)   = 'End of Design' | 'Comp-Approve'     | 'CS36192FB16'           |'R0402'| '(R0402-0201)'                 | '61.9K'   | '1%'    | '1/16W'  | 'IO'       | 'RES CHIP 61.9K 1/16W +-1%(0402)'                  | 'CHIP0402'     | ''          | ''            | ''        
 '68.1K'      | '1%'      | '1/16W'  | '0402LF'  | 'CHIP'   | 'TMP_QCS36812FB15'(!)   = 'End of Design' | 'Comp-Approve'     | 'CS36812FB15'           |'R0402'| '(R0402-0201)'                 | '68.1K'   | '1%'    | '1/16W'  | 'DISCRETE' | 'RES CHIP 68.1K 1/16W +-1%(0402)'                  | 'CHIP0402'     | ''          | ''            | ''        
 '68.1K'      | '1%'      | '1/16W'  | '0402LF'  | 'EMPTY'  | 'TMP_QCS36812FB15'(!)   = 'End of Design' | 'Comp-Approve'     | 'CS36812FB15'           |'R0402'| '(R0402-0201)'                 | '68.1K'   | '1%'    | '1/16W'  | 'IO'       | 'RES CHIP 68.1K 1/16W +-1%(0402)'                  | 'CHIP0402'     | ''          | ''            | ''        
 '150K'       | '1%'      | '1/16W'  | '0402LF'  | 'CHIP'   | 'TMP_QCS41502FB18'(!)   = 'End of Design' | 'Comp-Approve'     | 'CS41502FB18'           |'R0402'| '(R0402-0201)'                 | '150K'    | '1%'    | '1/16W'  | 'DISCRETE' | 'RES CHIP 150K 1/16W +-1%(0402)'                   | 'CHIP0402'     | ''          | ''            | ''        
 '150K'       | '1%'      | '1/16W'  | '0402LF'  | 'EMPTY'  | 'TMP_QCS41502FB18'(!)   = 'End of Design' | 'Comp-Approve'     | 'CS41502FB18'           |'R0402'| '(R0402-0201)'                 | '150K'    | '1%'    | '1/16W'  | 'IO'       | 'RES CHIP 150K 1/16W +-1%(0402)'                   | 'CHIP0402'     | ''          | ''            | ''        
 '147K'       | '0.1%'    | '1/16W'  | '0402LF'  | 'CHIP'   | 'TMP_QCS41472BB00'(!)   = ''              | ''                 | 'CS41472BB00'           |'R0402'| '(R0402-0201)'                 | '147K'    | '0.1%'  | '1/16W'  | 'DISCRETE' | 'RES CHIP 147K 1/16W +-0.1% (0402)'                | 'CHIP0402'     | ''          | ''            | ''        
 '147K'       | '0.1%'    | '1/16W'  | '0402LF'  | 'EMPTY'  | 'TMP_QCS41472BB00'(!)   = ''              | ''                 | 'CS41472BB00'           |'R0402'| '(R0402-0201)'                 | '147K'    | '0.1%'  | '1/16W'  | 'IO'       | 'RES CHIP 147K 1/16W +-0.1% (0402)'                | 'CHIP0402'     | ''          | ''            | ''        
 '7.15K'      | '0.1%'    | '1/16W'  | '0402LF'  | 'CHIP'   | 'TMP_QCS27152BB00'(!)   = ''              | ''                 | 'CS27152BB00'           |'R0402'| '(R0402-0201)'                 | '7.15K'   | '0.1%'  | '1/16W'  | 'DISCRETE' | 'RES CHIP 7.15K 1/16W +-0.1% (0402)'               | 'CHIP0402'     | ''          | ''            | ''        
 '7.15K'      | '0.1%'    | '1/16W'  | '0402LF'  | 'EMPTY'  | 'TMP_QCS27152BB00'(!)   = ''              | ''                 | 'CS27152BB00'           |'R0402'| '(R0402-0201)'                 | '7.15K'   | '0.1%'  | '1/16W'  | 'IO'       | 'RES CHIP 7.15K 1/16W +-0.1% (0402)'               | 'CHIP0402'     | ''          | ''            | ''        
 '140K'       | '0.1%'    | '1/16W'  | '0402LF'  | 'CHIP'   | 'TMP_QCS41402BB00'(!)   = ''              | ''                 | 'CS41402BB00'           |'R0402'| '(R0402-0201)'                 | '140K'    | '0.1%'  | '1/16W'  | 'DISCRETE' | 'RES CHIP 140K 1/16W +-0.1% (0402)'                | 'CHIP0402'     | ''          | ''            | ''        
 '140K'       | '0.1%'    | '1/16W'  | '0402LF'  | 'EMPTY'  | 'TMP_QCS41402BB00'(!)   = ''              | ''                 | 'CS41402BB00'           |'R0402'| '(R0402-0201)'                 | '140K'    | '0.1%'  | '1/16W'  | 'IO'       | 'RES CHIP 140K 1/16W +-0.1% (0402)'                | 'CHIP0402'     | ''          | ''            | ''        
 '330'        | '1%'      | '1/16W'  | '0402LF'  | 'CHIP'   | 'TMP_QCS13302FB11'(!)   = 'End of Design' | 'Comp-Approve'     | 'CS13302FB11'           |'R0402'| '(R0402-0201)'                 | '330'     | '1%'    | '1/16W'  | 'DISCRETE' | 'RES CHIP 330 1/16W +-1%(0402)'                    | 'CHIP0402'     | ''          | ''            | ''        
 '330'        | '1%'      | '1/16W'  | '0402LF'  | 'EMPTY'  | 'TMP_QCS13302FB11'(!)   = 'End of Design' | 'Comp-Approve'     | 'CS13302FB11'           |'R0402'| '(R0402-0201)'                 | '330'     | '1%'    | '1/16W'  | 'IO'       | 'RES CHIP 330 1/16W +-1%(0402)'                    | 'CHIP0402'     | ''          | ''            | ''        
 '220'        | '1%'      | '1/16W'  | '0402LF'  | 'CHIP'   | 'TMP_QCS12202FB14'(!)   = 'End of Design' | 'Comp-Approve'     | 'CS12202FB14'           |'R0402'| '(R0402-0201)'                 | '220'     | '1%'    | '1/16W'  | 'DISCRETE' | 'RES CHIP 220 1/16W +-1%(0402)'                    | 'CHIP0402'     | ''          | ''            | ''        
 '220'        | '1%'      | '1/16W'  | '0402LF'  | 'EMPTY'  | 'TMP_QCS12202FB14'(!)   = 'End of Design' | 'Comp-Approve'     | 'CS12202FB14'           |'R0402'| '(R0402-0201)'                 | '220'     | '1%'    | '1/16W'  | 'IO'       | 'RES CHIP 220 1/16W +-1%(0402)'                    | 'CHIP0402'     | ''          | ''            | ''        
 '5.76K'      | '1%'      | '1/16W'  | '0402LF'  | 'CHIP'   | 'TMP_QCS25762FB01'(!)   = 'End of Design' | 'Comp-Approve'     | 'CS25762FB01'           |'R0402'| '(R0402-0201)'                 | '5.76K'   | '1%'    | '1/16W'  | 'DISCRETE' | 'RES CHIP 5.76K 1/16W +-1%(0402)'                  | 'CHIP0402'     | ''          | ''            | ''        
 '5.76K'      | '1%'      | '1/16W'  | '0402LF'  | 'EMPTY'  | 'TMP_QCS25762FB01'(!)   = 'End of Design' | 'Comp-Approve'     | 'CS25762FB01'           |'R0402'| '(R0402-0201)'                 | '5.76K'   | '1%'    | '1/16W'  | 'IO'       | 'RES CHIP 5.76K 1/16W +-1%(0402)'                  | 'CHIP0402'     | ''          | ''            | ''        
 '3.74K'      | '1%'      | '1/16W'  | '0402LF'  | 'CHIP'   | 'TMP_QCS23742FB00'(!)   = 'End of Design' | 'Comp-Approve'     | 'CS23742FB00'           |'R0402'| '(R0402-0201)'                 | '3.74K'   | '1%'    | '1/16W'  | 'DISCRETE' | 'RES CHIP 3.74K 1/16W +-1%(0402)'                  | 'CHIP0402'     | ''          | ''            | ''        
 '3.74K'      | '1%'      | '1/16W'  | '0402LF'  | 'EMPTY'  | 'TMP_QCS23742FB00'(!)   = 'End of Design' | 'Comp-Approve'     | 'CS23742FB00'           |'R0402'| '(R0402-0201)'                 | '3.74K'   | '1%'    | '1/16W'  | 'IO'       | 'RES CHIP 3.74K 1/16W +-1%(0402)'                  | 'CHIP0402'     | ''          | ''            | ''        
 '12.7K'      | '1%'      | '1/16W'  | '0402LF'  | 'CHIP'   | 'TMP_QCS31272FB17'(!)   = 'End of Design' | 'Comp-Approve'     | 'CS31272FB17'           |'R0402'| '(R0402-0201)'                 | '12.7K'   | '1%'    | '1/16W'  | 'DISCRETE' | 'RES CHIP 12.7K 1/16W +-1% (0402)'                 | 'CHIP0402'     | ''          | ''            | ''        
 '12.7K'      | '1%'      | '1/16W'  | '0402LF'  | 'EMPTY'  | 'TMP_QCS31272FB17'(!)   = 'End of Design' | 'Comp-Approve'     | 'CS31272FB17'           |'R0402'| '(R0402-0201)'                 | '12.7K'   | '1%'    | '1/16W'  | 'IO'       | 'RES CHIP 12.7K 1/16W +-1% (0402)'                 | 'CHIP0402'     | ''          | ''            | ''        
 '31.6K'      | '1%'      | '1/16W'  | '0402LF'  | 'CHIP'   | 'TMP_QCS33162FB14'(!)   = 'End of Design' | 'Comp-Approve'     | 'CS33162FB14'           |'R0402'| '(R0402-0201)'                 | '31.6K'   | '1%'    | '1/16W'  | 'DISCRETE' | 'RES CHIP 31.6K 1/16W +-1%(0402)'                  | 'CHIP0402'     | ''          | ''            | ''        
 '31.6K'      | '1%'      | '1/16W'  | '0402LF'  | 'EMPTY'  | 'TMP_QCS33162FB14'(!)   = 'End of Design' | 'Comp-Approve'     | 'CS33162FB14'           |'R0402'| '(R0402-0201)'                 | '31.6K'   | '1%'    | '1/16W'  | 'IO'       | 'RES CHIP 31.6K 1/16W +-1%(0402)'                  | 'CHIP0402'     | ''          | ''            | ''        
 '54.9K'      | '1%'      | '1/16W'  | '0402LF'  | 'CHIP'   | 'TMP_QCS35492FB14'(!)   = 'End of Design' | 'Comp-Approve'     | 'CS35492FB14'           |'R0402'| '(R0402-0201)'                 | '54.9K'   | '1%'    | '1/16W'  | 'DISCRETE' | 'RES CHIP 54.9K 1/16W +-1%(0402)'                  | 'CHIP0402'     | ''          | ''            | ''        
 '54.9K'      | '1%'      | '1/16W'  | '0402LF'  | 'EMPTY'  | 'TMP_QCS35492FB14'(!)   = 'End of Design' | 'Comp-Approve'     | 'CS35492FB14'           |'R0402'| '(R0402-0201)'                 | '54.9K'   | '1%'    | '1/16W'  | 'IO'       | 'RES CHIP 54.9K 1/16W +-1%(0402)'                  | 'CHIP0402'     | ''          | ''            | ''        
 '8.87K'      | '1%'      | '1/16W'  | '0402LF'  | 'CHIP'   | 'TMP_QCS28872FB08'(!)   = 'End of Design' | 'Comp-Approve'     | 'CS28872FB08'           |'R0402'| '(R0402-0201)'                 | '8.87K'   | '1%'    | '1/16W'  | 'DISCRETE' | 'RES CHIP 8.87K 1/16W +-1%(0402)'                  | 'CHIP0402'     | ''          | ''            | ''        
 '8.87K'      | '1%'      | '1/16W'  | '0402LF'  | 'EMPTY'  | 'TMP_QCS28872FB08'(!)   = 'End of Design' | 'Comp-Approve'     | 'CS28872FB08'           |'R0402'| '(R0402-0201)'                 | '8.87K'   | '1%'    | '1/16W'  | 'IO'       | 'RES CHIP 8.87K 1/16W +-1%(0402)'                  | 'CHIP0402'     | ''          | ''            | ''        
 '2.67K'      | '1%'      | '1/16W'  | '0402LF'  | 'CHIP'   | 'TMP_QCS22672FB12'(!)   = 'End of Design' | 'Comp-Approve'     | 'CS22672FB12'           |'R0402'| '(R0402-0201)'                 | '2.67K'   | '1%'    | '1/16W'  | 'DISCRETE' | 'RES CHIP 2.67K 1/16W +-1%(0402) '                 | 'CHIP0402'     | ''          | ''            | ''        
 '2.67K'      | '1%'      | '1/16W'  | '0402LF'  | 'EMPTY'  | 'TMP_QCS22672FB12'(!)   = 'End of Design' | 'Comp-Approve'     | 'CS22672FB12'           |'R0402'| '(R0402-0201)'                 | '2.67K'   | '1%'    | '1/16W'  | 'IO'       | 'RES CHIP 2.67K 1/16W +-1%(0402) '                 | 'CHIP0402'     | ''          | ''            | ''        
 '5.36K'      | '1%'      | '1/16W'  | '0402LF'  | 'CHIP'   | 'TMP_QCS25362FB15'(!)   = 'End of Design' | 'Comp-Approve'     | 'CS25362FB15'           |'R0402'| '(R0402-0201)'                 | '5.36K'   | '1%'    | '1/16W'  | 'DISCRETE' | 'RES CHIP 5.36K 1/16W +-1%(0402) '                 | 'CHIP0402'     | ''          | ''            | ''        
 '5.36K'      | '1%'      | '1/16W'  | '0402LF'  | 'EMPTY'  | 'TMP_QCS25362FB15'(!)   = 'End of Design' | 'Comp-Approve'     | 'CS25362FB15'           |'R0402'| '(R0402-0201)'                 | '5.36K'   | '1%'    | '1/16W'  | 'IO'       | 'RES CHIP 5.36K 1/16W +-1%(0402) '                 | 'CHIP0402'     | ''          | ''            | ''        
 '390K'       | '1%'      | '1/16W'  | '0402LF'  | 'CHIP'   | 'TMP_QCS43902FB00'(!)   = 'End of Design' | 'Comp-Approve'     | 'CS43902FB00'           |'R0402'| '(R0402-0201)'                 | '390K'    | '1%'    | '1/16W'  | 'DISCRETE' | 'RES CHIP 390K 1/16W +-1%(0402)'                   | 'CHIP0402'     | ''          | ''            | ''        
 '390K'       | '1%'      | '1/16W'  | '0402LF'  | 'EMPTY'  | 'TMP_QCS43902FB00'(!)   = 'End of Design' | 'Comp-Approve'     | 'CS43902FB00'           |'R0402'| '(R0402-0201)'                 | '390K'    | '1%'    | '1/16W'  | 'IO'       | 'RES CHIP 390K 1/16W +-1%(0402)'                   | 'CHIP0402'     | ''          | ''            | ''        
 '100K'       | '1%'      | '1/16W'  | '0402LF'  | 'CHIP'   | 'TMP_QCS41002FB28'(!)   = 'End of Design' | 'Comp-Approve'     | 'CS41002FB28'           |'R0402'| '(R0402-0201)'                 | '100K'    | '1%'    | '1/16W'  | 'DISCRETE' | 'RES CHIP 100K 1/16W +-1% (0402)'                  | 'CHIP0402'     | ''          | ''            | ''        
 '100K'       | '1%'      | '1/16W'  | '0402LF'  | 'EMPTY'  | 'TMP_QCS41002FB28'(!)   = 'End of Design' | 'Comp-Approve'     | 'CS41002FB28'           |'R0402'| '(R0402-0201)'                 | '100K'    | '1%'    | '1/16W'  | 'IO'       | 'RES CHIP 100K 1/16W +-1% (0402)'                  | 'CHIP0402'     | ''          | ''            | ''        
 '110K'       | '1%'      | '1/16W'  | '0402LF'  | 'CHIP'   | 'TMP_QCS41102FB13'(!)   = 'End of Design' | 'Comp-Approve'     | 'CS41102FB13'           |'R0402'| '(R0402-0201)'                 | '110K'    | '1%'    | '1/16W'  | 'DISCRETE' | 'RES CHIP 110K 1/16W +-1%(0402)'                   | 'CHIP0402'     | ''          | ''            | ''        
 '110K'       | '1%'      | '1/16W'  | '0402LF'  | 'EMPTY'  | 'TMP_QCS41102FB13'(!)   = 'End of Design' | 'Comp-Approve'     | 'CS41102FB13'           |'R0402'| '(R0402-0201)'                 | '110K'    | '1%'    | '1/16W'  | 'IO'       | 'RES CHIP 110K 1/16W +-1%(0402)'                   | 'CHIP0402'     | ''          | ''            | ''        
 '10'         | '5%'      | '1/16W'  | '0402LF'  | 'CHIP'   | 'TMP_QCS01002JB22'(!)   = 'End of Design' | 'Comp-Approve'     | 'CS01002JB22'           |'R0402'| '(R0402-0201)'                 | '10'      | '5%'    | '1/16W'  | 'DISCRETE' | 'RES CHIP 10 1/16W +-5%(0402)'                     | 'CHIP0402'     | ''          | ''            | ''        
 '10'         | '5%'      | '1/16W'  | '0402LF'  | 'EMPTY'  | 'TMP_QCS01002JB22'(!)   = 'End of Design' | 'Comp-Approve'     | 'CS01002JB22'           |'R0402'| '(R0402-0201)'                 | '10'      | '5%'    | '1/16W'  | 'IO'       | 'RES CHIP 10 1/16W +-5%(0402)'                     | 'CHIP0402'     | ''          | ''            | ''        
 '20K'        | '5%'      | '1/16W'  | '0402LF'  | 'CHIP'   | 'TMP_QCS32002JB04'(!)   = ''              | ''                 | 'CS32002JB04'           |'R0402'| '(R0402-0201)'                 | '20K'     | '5%'    | '1/16W'  | 'DISCRETE' | 'RES CHIP 20K 1/16W +-5% (0402)'                   | 'CHIP0402'     | ''          | ''            | ''        
 '20K'        | '5%'      | '1/16W'  | '0402LF'  | 'EMPTY'  | 'TMP_QCS32002JB04'(!)   = ''              | ''                 | 'CS32002JB04'           |'R0402'| '(R0402-0201)'                 | '20K'     | '5%'    | '1/16W'  | 'IO'       | 'RES CHIP 20K 1/16W +-5% (0402)'                   | 'CHIP0402'     | ''          | ''            | ''        
 '56'         | '5%'      | '1/16W'  | '0402LF'  | 'CHIP'   | 'TMP_QCS05602JB17'(!)   = 'End of Design' | 'Comp-Approve'     | 'CS05602JB17'           |'R0402'| '(R0402-0201)'                 | '56'      | '5%'    | '1/16W'  | 'DISCRETE' | 'RES CHIP 56 1/16W +-5% (0402)'                    | 'CHIP0402'     | ''          | ''            | '20100527'
 '56'         | '5%'      | '1/16W'  | '0402LF'  | 'EMPTY'  | 'TMP_QCS05602JB17'(!)   = 'End of Design' | 'Comp-Approve'     | 'CS05602JB17'           |'R0402'| '(R0402-0201)'                 | '56'      | '5%'    | '1/16W'  | 'IO'       | 'RES CHIP 56 1/16W +-5% (0402)'                    | 'CHIP0402'     | ''          | ''            | '20100527'
 '20'         | '1%'      | '1/16W'  | '0402LF'  | 'CHIP'   | 'TMP_QCS02002FB23'(!)   = 'End of Design' | 'Comp-Approve'     | 'CS02002FB23'           |'R0402'| '(R0402-0201)'                 | '20'      | '1%'    | '1/16W'  | 'DISCRETE' | 'RES CHIP 20 1/16W +-1% (0402)'                    | 'CHIP0402'     | ''          | ''            | '20100601'
 '20'         | '1%'      | '1/16W'  | '0402LF'  | 'EMPTY'  | 'TMP_QCS02002FB23'(!)   = 'End of Design' | 'Comp-Approve'     | 'CS02002FB23'           |'R0402'| '(R0402-0201)'                 | '20'      | '1%'    | '1/16W'  | 'IO'       | 'RES CHIP 20 1/16W +-1% (0402)'                    | 'CHIP0402'     | ''          | ''            | '20100601'
 '4.02K'      | '1%'      | '1/16W'  | '0402LF'  | 'CHIP'   | 'TMP_QCS24022FB05'(!)   = ''              | ''                 | 'CS24022FB05'           |'R0402'| '(R0402-0201)'                 | '4.02K'   | '1%'    | '1/16W'  | 'DISCRETE' | 'RES CHIP 4.02K 1/16W +-1%(0402)'                  | 'CHIP0402'     | ''          | ''            | '20100601'
 '4.02K'      | '1%'      | '1/16W'  | '0402LF'  | 'EMPTY'  | 'TMP_QCS24022FB05'(!)   = ''              | ''                 | 'CS24022FB05'           |'R0402'| '(R0402-0201)'                 | '4.02K'   | '1%'    | '1/16W'  | 'IO'       | 'RES CHIP 4.02K 1/16W +-1%(0402)'                  | 'CHIP0402'     | ''          | ''            | '20100601'
 '21.5K'      | '1%'      | '1/16W'  | '0402LF'  | 'CHIP'   | 'TMP_QCS32152FB17'(!)   = 'End of Design' | 'Comp-Approve'     | 'CS32152FB17'           |'R0402'| '(R0402-0201)'                 | '21.5K'   | '1%'    | '1/16W'  | 'DISCRETE' | 'RES CHIP 21.5K 1/16W +-1%(0402)'                  | 'CHIP0402'     | ''          | ''            | '20100601'
 '21.5K'      | '1%'      | '1/16W'  | '0402LF'  | 'EMPTY'  | 'TMP_QCS32152FB17'(!)   = 'End of Design' | 'Comp-Approve'     | 'CS32152FB17'           |'R0402'| '(R0402-0201)'                 | '21.5K'   | '1%'    | '1/16W'  | 'IO'       | 'RES CHIP 21.5K 1/16W +-1%(0402)'                  | 'CHIP0402'     | ''          | ''            | '20100601'
 '1'          | '1%'      | '1/4W'   | '1206LF'  | 'CHIP'   | 'TMP_QCS-1006F209'(!)   = 'End of Design' | 'Comp-Approve'     | 'CS-1006F209'           |'R1206'| '(SMR1206AW)'                  | '1'       | '1%'    | '1/4W'   | 'DISCRETE' | 'RES CHIP 1 1/4W +-1%(1206)'                       | 'CHIP1206'     | ''          | ''            | '20100603'
 '1'          | '1%'      | '1/4W'   | '1206LF'  | 'EMPTY'  | 'TMP_QCS-1006F209'(!)   = 'End of Design' | 'Comp-Approve'     | 'CS-1006F209'           |'R1206'| '(SMR1206AW)'                  | '1'       | '1%'    | '1/4W'   | 'IO'       | 'RES CHIP 1 1/4W +-1%(1206)'                       | 'CHIP1206'     | ''          | ''            | '20100603'
 '2K'         | '5%'      | '1/16W'  | '0402LF'  | 'CHIP'   | 'TMP_QCS22002JB29'(!)   = 'End of Design' | 'Comp-Approve'     | 'CS22002JB29'           |'R0402'| '(R0402-0201)'                 | '2K'      | '5%'    | '1/16W'  | 'DISCRETE' | 'RES CHIP 2K(1/16W +-5% 0402)'                     | 'CHIP0402'     | ''          | ''            | '20100603'
 '2K'         | '5%'      | '1/16W'  | '0402LF'  | 'EMPTY'  | 'TMP_QCS22002JB29'(!)   = 'End of Design' | 'Comp-Approve'     | 'CS22002JB29'           |'R0402'| '(R0402-0201)'                 | '2K'      | '5%'    | '1/16W'  | 'IO'       | 'RES CHIP 2K(1/16W +-5% 0402)'                     | 'CHIP0402'     | ''          | ''            | '20100603'
 '430'        | '1%'      | '1/16W'  | '0402LF'  | 'CHIP'   | 'CS14302FB05'(!)        = 'End of Design' | 'Comp-Approve'     | 'CS14302FB05'           |'R0402'| '(R0402-0201)'                 | '430'     | '1%'    | '1/16W'  | 'DISCRETE' | 'RES CHIP 430 1/16W +-1%(0402)'                    | 'CHIP0402'     | ''          | ''            | '20100609'
 '430'        | '1%'      | '1/16W'  | '0402LF'  | 'EMPTY'  | 'CS14302FB05'(!)        = 'End of Design' | 'Comp-Approve'     | 'CS14302FB05'           |'R0402'| '(R0402-0201)'                 | '430'     | '1%'    | '1/16W'  | 'IO'       | 'RES CHIP 430 1/16W +-1%(0402)'                    | 'CHIP0402'     | ''          | ''            | '20100609'
 '422'        | '1%'      | '1/16W'  | '0402LF'  | 'CHIP'   | 'CS14222FB19'(!)        = 'End of Design' | 'Comp-Approve'     | 'CS14222FB19'           |'R0402'| '(R0402-0201)'                 | '422'     | '1%'    | '1/16W'  | 'DISCRETE' | 'RES CHIP 422 1/16W +-1% (0402)'                   | 'CHIP0402'     | ''          | ''            | '20100609'
 '422'        | '1%'      | '1/16W'  | '0402LF'  | 'EMPTY'  | 'CS14222FB19'(!)        = 'End of Design' | 'Comp-Approve'     | 'CS14222FB19'           |'R0402'| '(R0402-0201)'                 | '422'     | '1%'    | '1/16W'  | 'IO'       | 'RES CHIP 422 1/16W +-1% (0402)'                   | 'CHIP0402'     | ''          | ''            | '20100609'
 '120'        | '1%'      | '1/16W'  | '0402LF'  | 'CHIP'   | 'CS11202FB11'(!)        = 'End of Design' | 'Comp-Approve'     | 'CS11202FB11'           |'R0402'| '(R0402-0201)'                 | '120'     | '1%'    | '1/16W'  | 'DISCRETE' | 'RES CHIP 120 1/16W +-1%(0402)'                    | 'CHIP0402'     | ''          | ''            | '20100609'
 '120'        | '1%'      | '1/16W'  | '0402LF'  | 'EMPTY'  | 'CS11202FB11'(!)        = 'End of Design' | 'Comp-Approve'     | 'CS11202FB11'           |'R0402'| '(R0402-0201)'                 | '120'     | '1%'    | '1/16W'  | 'IO'       | 'RES CHIP 120 1/16W +-1%(0402)'                    | 'CHIP0402'     | ''          | ''            | '20100609'
 '866'        | '1%'      | '1/10W'  | '0603LF ' | 'CHIP'   | 'CS18663F919'(!)        = ''              | ''                 | 'CS18663F919'           |'R0603'| '(SMR0603AW)'                  | '866'     | '1%'    | '1/10W ' | 'DISCRETE' | 'RESISTER CHIP 866 1/10W +-1%(0603)'               | 'CHIP0603'     | ''          | ''            | '20100609'
 '866'        | '1%'      | '1/10W'  | '0603LF ' | 'EMPTY'  | 'CS18663F919'(!)        = ''              | ''                 | 'CS18663F919'           |'R0603'| '(SMR0603AW)'                  | '866'     | '1%'    | '1/10W ' | 'IO'       | 'RESISTER CHIP 866 1/10W +-1%(0603)'               | 'CHIP0603'     | ''          | ''            | '20100609'
 '1.74K'      | '1%'      | '1/16W'  | '0402LF'  | 'CHIP'   | 'CS21742FB00'(!)        = 'End of Design' | 'Comp-Approve'     | 'CS21742FB00'           |'R0402'| '(R0402-0201)'                 | '1.74K'   | '1%'    | '1/16W'  | 'DISCRETE' | 'RES CHIP 1.74K 1/16W +-1%(0402)'                  | 'CHIP0402'     | ''          | ''            | '20100610'
 '1.74K'      | '1%'      | '1/16W'  | '0402LF'  | 'EMPTY'  | 'CS21742FB00'(!)        = 'End of Design' | 'Comp-Approve'     | 'CS21742FB00'           |'R0402'| '(R0402-0201)'                 | '1.74K'   | '1%'    | '1/16W'  | 'IO'       | 'RES CHIP 1.74K 1/16W +-1%(0402)'                  | 'CHIP0402'     | ''          | ''            | '20100610'
 '3.48K'      | '1%'      | '1/16W'  | '0402LF'  | 'CHIP'   | 'CS23482FB12'(!)        = 'End of Design' | 'Comp-Approve'     | 'CS23482FB12'           |'R0402'| '(R0402-0201)'                 | '3.48K'   | '1%'    | '1/16W'  | 'DISCRETE' | 'RES CHIP 3.48K 1/16W +-1%( 0402)'                 | 'CHIP0402'     | ''          | ''            | '20100611'
 '3.48K'      | '1%'      | '1/16W'  | '0402LF'  | 'EMPTY'  | 'CS23482FB12'(!)        = 'End of Design' | 'Comp-Approve'     | 'CS23482FB12'           |'R0402'| '(R0402-0201)'                 | '3.48K'   | '1%'    | '1/16W'  | 'IO'       | 'RES CHIP 3.48K 1/16W +-1%( 0402)'                 | 'CHIP0402'     | ''          | ''            | '20100611'
 '154'        | '1%'      | '1/16W'  | '0402LF'  | 'CHIP'   | 'CS11542FB00'(!)        = 'End of Design' | 'Comp-Approve'     | 'CS11542FB00'           |'R0402'| '(R0402-0201)'                 | '154'     | '1%'    | '1/16W'  | 'DISCRETE' | 'RES CHIP 154 1/16W +-1%(0402)'                    | 'CHIP0402'     | ''          | ''            | '20100614'
 '154'        | '1%'      | '1/16W'  | '0402LF'  | 'EMPTY'  | 'CS11542FB00'(!)        = 'End of Design' | 'Comp-Approve'     | 'CS11542FB00'           |'R0402'| '(R0402-0201)'                 | '154'     | '1%'    | '1/16W'  | 'IO'       | 'RES CHIP 154 1/16W +-1%(0402)'                    | 'CHIP0402'     | ''          | ''            | '20100614'
 '402'        | '1%'      | '1/16W'  | '0402LF'  | 'CHIP'   | 'CS14022FB03'(!)        = ''              | ''                 | 'CS14022FB03'           |'R0402'| '(R0402-0201)'                 | '402'     | '1%'    | '1/16W'  | 'DISCRETE' | 'RES CHIP 402 1/16W +-1%(0402)'                    | 'CHIP0402'     | ''          | ''            | '20100614'
 '402'        | '1%'      | '1/16W'  | '0402LF'  | 'EMPTY'  | 'CS14022FB03'(!)        = ''              | ''                 | 'CS14022FB03'           |'R0402'| '(R0402-0201)'                 | '402'     | '1%'    | '1/16W'  | 'IO'       | 'RES CHIP 402 1/16W +-1%(0402)'                    | 'CHIP0402'     | ''          | ''            | '20100614'
 '2.15K'      | '1%'      | '1/16W'  | '0402LF'  | 'CHIP'   | 'CS22152FB07'(!)        = 'End of Design' | 'Comp-Approve'     | 'CS22152FB07'           |'R0402'| '(R0402-0201)'                 | '2.15K'   | '1%'    | '1/16W'  | 'DISCRETE' | 'RES CHIP 2.15K 1/16W +-1%(0402)'                  | 'CHIP0402'     | ''          | ''            | '20100614'
 '2.15K'      | '1%'      | '1/16W'  | '0402LF'  | 'EMPTY'  | 'CS22152FB07'(!)        = 'End of Design' | 'Comp-Approve'     | 'CS22152FB07'           |'R0402'| '(R0402-0201)'                 | '2.15K'   | '1%'    | '1/16W'  | 'IO'       | 'RES CHIP 2.15K 1/16W +-1%(0402)'                  | 'CHIP0402'     | ''          | ''            | '20100614'
 '3.57K'      | '1%'      | '1/16W'  | '0402LF'  | 'CHIP'   | 'CS23572FB11'(!)        = 'End of Design' | 'Comp-Approve'     | 'CS23572FB11'           |'R0402'| '(R0402-0201)'                 | '3.57K'   | '1%'    | '1/16W'  | 'DISCRETE' | 'RES CHIP 3.57K 1/16W +-1%(0402)'                  | 'CHIP0402'     | ''          | ''            | '20100614'
 '3.57K'      | '1%'      | '1/16W'  | '0402LF'  | 'EMPTY'  | 'CS23572FB11'(!)        = 'End of Design' | 'Comp-Approve'     | 'CS23572FB11'           |'R0402'| '(R0402-0201)'                 | '3.57K'   | '1%'    | '1/16W'  | 'IO'       | 'RES CHIP 3.57K 1/16W +-1%(0402)'                  | 'CHIP0402'     | ''          | ''            | '20100614'
 '3.92K'      | '1%'      | '1/16W'  | '0402LF'  | 'CHIP'   | 'CS23922FB13'(!)        = 'End of Design' | 'Comp-Approve'     | 'CS23922FB13'           |'R0402'| '(R0402-0201)'                 | '3.92K'   | '1%'    | '1/16W'  | 'DISCRETE' | 'RES CHIP 3.92K 1/16W +-1% (0402)'                 | 'CHIP0402'     | ''          | ''            | '20100614'
 '3.92K'      | '1%'      | '1/16W'  | '0402LF'  | 'EMPTY'  | 'CS23922FB13'(!)        = 'End of Design' | 'Comp-Approve'     | 'CS23922FB13'           |'R0402'| '(R0402-0201)'                 | '3.92K'   | '1%'    | '1/16W'  | 'IO'       | 'RES CHIP 3.92K 1/16W +-1% (0402)'                 | 'CHIP0402'     | ''          | ''            | '20100614'
 '1.5K'       | '1%'      | '1/16W'  | '0402LF'  | 'CHIP'   | 'CS21502FB14'(!)        = 'End of Design' | 'Comp-Release Qty' | 'CS21502FB14'           |'R0402'| '(R0402-0201)'                 | '1.5K'    | '1%'    | '1/16W'  | 'DISCRETE' | 'RES CHIP 1.5K 1/16W +-1% (0402)'                  | 'CHIP0402'     | ''          | ''            | '20100614'
 '1.5K'       | '1%'      | '1/16W'  | '0402LF'  | 'EMPTY'  | 'CS21502FB14'(!)        = 'End of Design' | 'Comp-Release Qty' | 'CS21502FB14'           |'R0402'| '(R0402-0201)'                 | '1.5K'    | '1%'    | '1/16W'  | 'IO'       | 'RES CHIP 1.5K 1/16W +-1% (0402)'                  | 'CHIP0402'     | ''          | ''            | '20100614'
 '261'        | '1%'      | '1/16W'  | '0402LF'  | 'CHIP'   | 'CS12612FB05'(!)        = ''              | ''                 | 'CS12612FB05'           |'R0402'| '(R0402-0201)'                 | '261'     | '1%'    | '1/16W'  | 'DISCRETE' | 'RES CHIP 261 1/16W +-1%(0402)'                    | 'CHIP0402'     | ''          | ''            | '20100614'
 '261'        | '1%'      | '1/16W'  | '0402LF'  | 'EMPTY'  | 'CS12612FB05'(!)        = ''              | ''                 | 'CS12612FB05'           |'R0402'| '(R0402-0201)'                 | '261'     | '1%'    | '1/16W'  | 'IO'       | 'RES CHIP 261 1/16W +-1%(0402)'                    | 'CHIP0402'     | ''          | ''            | '20100614'
 '20.5K'      | '1%'      | '1/16W'  | '0402LF'  | 'CHIP'   | 'CS32052FB21'(!)        = 'End of Design' | 'Comp-Approve'     | 'CS32052FB21'           |'R0402'| '(R0402-0201)'                 | '20.5K'   | '1%'    | '1/16W'  | 'DISCRETE' | 'RES CHIP 20.5K 1/16W +-1%(0402)'                  | 'CHIP0402'     | ''          | ''            | '20100615'
 '20.5K'      | '1%'      | '1/16W'  | '0402LF'  | 'EMPTY'  | 'CS32052FB21'(!)        = 'End of Design' | 'Comp-Approve'     | 'CS32052FB21'           |'R0402'| '(R0402-0201)'                 | '20.5K'   | '1%'    | '1/16W'  | 'IO'       | 'RES CHIP 20.5K 1/16W +-1%(0402)'                  | 'CHIP0402'     | ''          | ''            | '20100615'
 '34K'        | '1%'      | '1/16W'  | '0402LF'  | 'CHIP'   | 'CS33402FB18'(!)        = 'End of Design' | 'Comp-Approve'     | 'CS33402FB18'           |'R0402'| '(R0402-0201)'                 | '34K'     | '1%'    | '1/16W'  | 'DISCRETE' | 'RES CHIP 34K 1/16W +-1% (0402)'                   | 'CHIP0402'     | ''          | ''            | '20100615'
 '34K'        | '1%'      | '1/16W'  | '0402LF'  | 'EMPTY'  | 'CS33402FB18'(!)        = 'End of Design' | 'Comp-Approve'     | 'CS33402FB18'           |'R0402'| '(R0402-0201)'                 | '34K'     | '1%'    | '1/16W'  | 'IO'       | 'RES CHIP 34K 1/16W +-1% (0402)'                   | 'CHIP0402'     | ''          | ''            | '20100615'
 '8.66K'      | '1%'      | '1/16W'  | '0402LF'  | 'CHIP'   | 'CS28662FB14'(!)        = 'End of Design' | 'Comp-Approve'     | 'CS28662FB14'           |'R0402'| '(R0402-0201)'                 | '8.66K'   | '1%'    | '1/16W'  | 'DISCRETE' | 'RES CHIP 8.66K 1/16W +-1%(0402)'                  | 'CHIP0402'     | ''          | ''            | '20100615'
 '8.66K'      | '1%'      | '1/16W'  | '0402LF'  | 'EMPTY'  | 'CS28662FB14'(!)        = 'End of Design' | 'Comp-Approve'     | 'CS28662FB14'           |'R0402'| '(R0402-0201)'                 | '8.66K'   | '1%'    | '1/16W'  | 'IO'       | 'RES CHIP 8.66K 1/16W +-1%(0402)'                  | 'CHIP0402'     | ''          | ''            | '20100615'
 '54.9'       | '1%'      | '1/16W'  | '0402LF'  | 'CHIP'   | 'CS05492FB19'(!)        = 'End of Design' | 'Comp-Approve'     | 'CS05492FB19'           |'R0402'| '(R0402-0201)'                 | '54.9'    | '1%'    | '1/16W'  | 'DISCRETE' | 'RES CHIP 54.9 1/16W +-1%(0402)'                   | 'CHIP0402'     | ''          | ''            | '20100617'
 '54.9'       | '1%'      | '1/16W'  | '0402LF'  | 'EMPTY'  | 'CS05492FB19'(!)        = 'End of Design' | 'Comp-Approve'     | 'CS05492FB19'           |'R0402'| '(R0402-0201)'                 | '54.9'    | '1%'    | '1/16W'  | 'IO'       | 'RES CHIP 54.9 1/16W +-1%(0402)'                   | 'CHIP0402'     | ''          | ''            | '20100617'
 '4.02K'      | '1%'      | '1/16W'  | '0402LF'  | 'CHIP'   | 'CS24022FB05'(!)        = ''              | ''                 | 'CS24022FB05'           |'R0402'| '(R0402-0201)'                 | '4.02K'   | '1%'    | '1/16W'  | 'DISCRETE' | 'RES CHIP 4.02K 1/16W +-1%(0402)'                  | 'CHIP0402'     | ''          | ''            | '20100617'
 '4.02K'      | '1%'      | '1/16W'  | '0402LF'  | 'EMPTY'  | 'CS24022FB05'(!)        = ''              | ''                 | 'CS24022FB05'           |'R0402'| '(R0402-0201)'                 | '4.02K'   | '1%'    | '1/16W'  | 'IO'       | 'RES CHIP 4.02K 1/16W +-1%(0402)'                  | 'CHIP0402'     | ''          | ''            | '20100617'
 '3.4K'       | '1%'      | '1/16W'  | '0402LF'  | 'CHIP'   | 'CS23402FB08'(!)        = 'End of Design' | 'Comp-Approve'     | 'CS23402FB08'           |'R0402'| '(R0402-0201)'                 | '3.4K'    | '1%'    | '1/16W'  | 'DISCRETE' | 'RES CHIP 3.4K 1/16W +-1%(0402)'                   | 'CHIP0402'     | ''          | ''            | '20100617'
 '3.4K'       | '1%'      | '1/16W'  | '0402LF'  | 'EMPTY'  | 'CS23402FB08'(!)        = 'End of Design' | 'Comp-Approve'     | 'CS23402FB08'           |'R0402'| '(R0402-0201)'                 | '3.4K'    | '1%'    | '1/16W'  | 'IO'       | 'RES CHIP 3.4K 1/16W +-1%(0402)'                   | 'CHIP0402'     | ''          | ''            | '20100617'
 '187K'       | '1%'      | '1/16W'  | '0402LF'  | 'CHIP'   | 'CS41872FB10'(!)        = 'End of Design' | 'Comp-Approve'     | 'CS41872FB10'           |'R0402'| '(R0402-0201)'                 | '187K'    | '1%'    | '1/16W'  | 'DISCRETE' | 'RES CHIP 187K 1/16W +-1%(0402)'                   | 'CHIP0402'     | ''          | ''            | '20100617'
 '187K'       | '1%'      | '1/16W'  | '0402LF'  | 'EMPTY'  | 'CS41872FB10'(!)        = 'End of Design' | 'Comp-Approve'     | 'CS41872FB10'           |'R0402'| '(R0402-0201)'                 | '187K'    | '1%'    | '1/16W'  | 'IO'       | 'RES CHIP 187K 1/16W +-1%(0402)'                   | 'CHIP0402'     | ''          | ''            | '20100617'
 '1M'         | '1%'      | '1/16W'  | '0402LF'  | 'CHIP'   | 'CS51002FB11'(!)        = 'End of Design' | 'Comp-Approve'     | 'CS51002FB11'           |'R0402'| '(R0402-0201)'                 | '1M'      | '1%'    | '1/16W'  | 'DISCRETE' | 'RES CHIP 1M 1/16W +-1% (0402)'                    | 'CHIP0402'     | ''          | ''            | '20100617'
 '1M'         | '1%'      | '1/16W'  | '0402LF'  | 'EMPTY'  | 'CS51002FB11'(!)        = 'End of Design' | 'Comp-Approve'     | 'CS51002FB11'           |'R0402'| '(R0402-0201)'                 | '1M'      | '1%'    | '1/16W'  | 'IO'       | 'RES CHIP 1M 1/16W +-1% (0402)'                    | 'CHIP0402'     | ''          | ''            | '20100617'
 '562'        | '1%'      | '1/16W'  | '0402LF'  | 'CHIP'   | 'CS15622FB08'(!)        = ''              | ''                 | 'CS15622FB08'           |'R0402'| '(R0402-0201)'                 | '562'     | '1%'    | '1/16W'  | 'DISCRETE' | 'RES CIHP 562 1/16W +-1% (0402)'                   | 'CHIP0402'     | ''          | ''            | '20100617'
 '562'        | '1%'      | '1/16W'  | '0402LF'  | 'EMPTY'  | 'CS15622FB08'(!)        = ''              | ''                 | 'CS15622FB08'           |'R0402'| '(R0402-0201)'                 | '562'     | '1%'    | '1/16W'  | 'IO'       | 'RES CIHP 562 1/16W +-1% (0402)'                   | 'CHIP0402'     | ''          | ''            | '20100617'
 '0'          | '5%'      | '1/16W'  | '0402LF'  | 'CHIP'   | 'CS00002JB38'(!)        = 'End of Design' | 'Comp-Approve'     | 'CS00002JB38'           |'R0402'| '(R0402-0201)'                 | '0'       | '5%'    | '1/16W'  | 'DISCRETE' | 'RESISTOR CHIP 0 1/16W +-5%(0402)'                 | 'CHIP0402'     | ''          | ''            | '20100618'
 '0'          | '5%'      | '1/16W'  | '0402LF'  | 'EMPTY'  | 'CS00002JB38'(!)        = 'End of Design' | 'Comp-Approve'     | 'CS00002JB38'           |'R0402'| '(R0402-0201)'                 | '0'       | '5%'    | '1/16W'  | 'IO'       | 'RESISTOR CHIP 0 1/16W +-5%(0402)'                 | 'CHIP0402'     | ''          | ''            | '20100618'
 '4.99K'      | '0.5%'    | '1/16W'  | '0402LF'  | 'CHIP'   | 'CS24992DB00'(!)        = ''              | ''                 | 'CS24992DB00'           |'R0402'| '(R0402-0201)'                 | '4.99K'   | '0.5%'  | '1/16W'  | 'DISCRETE' | 'RES CHIP 4.99K 1/16W +-0.5%(0402)'                | 'CHIP0402'     | ''          | ''            | '20100618'
 '4.99K'      | '0.5%'    | '1/16W'  | '0402LF'  | 'EMPTY'  | 'CS24992DB00'(!)        = ''              | ''                 | 'CS24992DB00'           |'R0402'| '(R0402-0201)'                 | '4.99K'   | '0.5%'  | '1/16W'  | 'IO'       | 'RES CHIP 4.99K 1/16W +-0.5%(0402)'                | 'CHIP0402'     | ''          | ''            | '20100618'
 '210K'       | '1%'      | '1/16W'  | '0402LF'  | 'CHIP'   | 'CS42102FB00'(!)        = 'End of Design' | 'Comp-Approve'     | 'CS42102FB00'           |'R0402'| '(R0402-0201)'                 | '210K'    | '1%'    | '1/16W'  | 'DISCRETE' | 'RES CHIP 210K 1/16W +-1%(0402)'                   | 'CHIP0402'     | ''          | ''            | '20100618'
 '210K'       | '1%'      | '1/16W'  | '0402LF'  | 'EMPTY'  | 'CS42102FB00'(!)        = 'End of Design' | 'Comp-Approve'     | 'CS42102FB00'           |'R0402'| '(R0402-0201)'                 | '210K'    | '1%'    | '1/16W'  | 'IO'       | 'RES CHIP 210K 1/16W +-1%(0402)'                   | 'CHIP0402'     | ''          | ''            | '20100618'
 '84.5K'      | '1%'      | '1/16W'  | '0402LF'  | 'CHIP'   | 'CS38452FB14'(!)        = 'End of Design' | 'Comp-Approve'     | 'CS38452FB14'           |'R0402'| '(R0402-0201)'                 | '84.5K'   | '1%'    | '1/16W'  | 'DISCRETE' | 'RES CHIP 84.5K 1/16W +-1%(0402)'                  | 'CHIP0402'     | ''          | ''            | '20100618'
 '84.5K'      | '1%'      | '1/16W'  | '0402LF'  | 'EMPTY'  | 'CS38452FB14'(!)        = 'End of Design' | 'Comp-Approve'     | 'CS38452FB14'           |'R0402'| '(R0402-0201)'                 | '84.5K'   | '1%'    | '1/16W'  | 'IO'       | 'RES CHIP 84.5K 1/16W +-1%(0402)'                  | 'CHIP0402'     | ''          | ''            | '20100618'
 '133K'       | '1%'      | '1/16W'  | '0402LF'  | 'CHIP'   | 'CS41332FB06'(!)        = 'End of Design' | 'Comp-Approve'     | 'CS41332FB06'           |'R0402'| '(R0402-0201)'                 | '133K'    | '1%'    | '1/16W'  | 'DISCRETE' | 'RES CHIP 133K 1/16W +-1%(0402)'                   | 'CHIP0402'     | ''          | ''            | '20100618'
 '133K'       | '1%'      | '1/16W'  | '0402LF'  | 'EMPTY'  | 'CS41332FB06'(!)        = 'End of Design' | 'Comp-Approve'     | 'CS41332FB06'           |'R0402'| '(R0402-0201)'                 | '133K'    | '1%'    | '1/16W'  | 'IO'       | 'RES CHIP 133K 1/16W +-1%(0402)'                   | 'CHIP0402'     | ''          | ''            | '20100618'
 '205K'       | '1%'      | '1/16W'  | '0402LF'  | 'CHIP'   | 'CS42052FB10'(!)        = 'End of Design' | 'Comp-Approve'     | 'CS42052FB10'           |'R0402'| '(R0402-0201)'                 | '205K'    | '1%'    | '1/16W'  | 'DISCRETE' | 'RES CHIP 205K 1/16W +-1%(0402)'                   | 'CHIP0402'     | ''          | ''            | '20100618'
 '205K'       | '1%'      | '1/16W'  | '0402LF'  | 'EMPTY'  | 'CS42052FB10'(!)        = 'End of Design' | 'Comp-Approve'     | 'CS42052FB10'           |'R0402'| '(R0402-0201)'                 | '205K'    | '1%'    | '1/16W'  | 'IO'       | 'RES CHIP 205K 1/16W +-1%(0402)'                   | 'CHIP0402'     | ''          | ''            | '20100618'
 '6.34K'      | '0.5%'    | '1/10W'  | '0603LF'  | 'CHIP'   | 'CS26343D900'(!)        = 'End of Design' | 'Comp-Approve'     | 'CS26343D900'           |'R0603'| '(SMR0603AW)'                  | '6.34K'   | '0.5%'  | '1/10W'  | 'DISCRETE' | 'RES CHIP 6.34K 1/10W +-0.5%(0603)'                | 'CHIP0603'     | ''          | ''            | '20100618'
 '6.34K'      | '0.5%'    | '1/10W'  | '0603LF'  | 'EMPTY'  | 'CS26343D900'(!)        = 'End of Design' | 'Comp-Approve'     | 'CS26343D900'           |'R0603'| '(SMR0603AW)'                  | '6.34K'   | '0.5%'  | '1/10W'  | 'IO'       | 'RES CHIP 6.34K 1/10W +-0.5%(0603)'                | 'CHIP0603'     | ''          | ''            | '20100618'
 '10K'        | '0.5%'    | '1/10W'  | '0603LF'  | 'CHIP'   | 'CS31003D911'(!)        = ''              | ''                 | 'CS31003D911'           |'R0603'| '(SMR0603AW)'                  | '10K'     | '0.5%'  | '1/10W ' | 'DISCRETE' | 'RESISTOR CHIP 10K 1/10W+-0.5%(0603)'              | 'CHIP0603'     | ''          | ''            | '20100618'
 '10K'        | '0.5%'    | '1/10W'  | '0603LF'  | 'EMPTY'  | 'CS31003D911'(!)        = ''              | ''                 | 'CS31003D911'           |'R0603'| '(SMR0603AW)'                  | '10K'     | '0.5%'  | '1/10W ' | 'IO'       | 'RESISTOR CHIP 10K 1/10W+-0.5%(0603)'              | 'CHIP0603'     | ''          | ''            | '20100618'
 '3.6K'       | '0.5%'    | '1/10W'  | '0603LF'  | 'CHIP'   | 'CS23603D900'(!)        = 'End of Design' | 'Comp-Approve'     | 'CS23603D900'           |'R0603'| '(SMR0603AW)'                  | '3.6K'    | '0.5%'  | '1/10W ' | 'DISCRETE' | 'RES CHIP 3.6K 1/10W +-0.5%(0603)'                 | 'CHIP0603'     | ''          | ''            | '20100621'
 '3.6K'       | '0.5%'    | '1/10W'  | '0603LF'  | 'EMPTY'  | 'CS23603D900'(!)        = 'End of Design' | 'Comp-Approve'     | 'CS23603D900'           |'R0603'| '(SMR0603AW)'                  | '3.6K'    | '0.5%'  | '1/10W ' | 'IO'       | 'RES CHIP 3.6K 1/10W +-0.5%(0603)'                 | 'CHIP0603'     | ''          | ''            | '20100621'
 '24.9K'      | '1%'      | '1/16W'  | '0402LF'  | 'CHIP'   | 'CS32492FB16'(!)        = 'End of Design' | 'Comp-Approve'     | 'CS32492FB16'           |'R0402'| '(R0402-0201)'                 | '24.9K'   | '1%'    | '1/16W'  | 'DISCRETE' | 'RES CHIP 24.9K 1/16W +-1%(0402)'                  | 'CHIP0402'     | ''          | ''            | '20100621'
 '24.9K'      | '1%'      | '1/16W'  | '0402LF'  | 'EMPTY'  | 'CS32492FB16'(!)        = 'End of Design' | 'Comp-Approve'     | 'CS32492FB16'           |'R0402'| '(R0402-0201)'                 | '24.9K'   | '1%'    | '1/16W'  | 'IO'       | 'RES CHIP 24.9K 1/16W +-1%(0402)'                  | 'CHIP0402'     | ''          | ''            | '20100621'
 '330'        | '1%'      | '1/10W'  | '0603LF'  | 'CHIP'   | 'CS13303F917'(!)        = ''              | ''                 | 'CS13303F917'           |'R0603'| '(SMR0603AW)'                  | '330'     | '1%'    | '1/10W'  | 'DISCRETE' | 'RES CHIP 330 1/10W +-1%(0603)'                    | 'CHIP0603'     | ''          | ''            | '20100621'
 '330'        | '1%'      | '1/10W'  | '0603LF'  | 'EMPTY'  | 'CS13303F917'(!)        = ''              | ''                 | 'CS13303F917'           |'R0603'| '(SMR0603AW)'                  | '330'     | '1%'    | '1/10W'  | 'IO'       | 'RES CHIP 330 1/10W +-1%(0603)'                    | 'CHIP0603'     | ''          | ''            | '20100621'
 '47.5K'      | '1%'      | '1/10W'  | '0603LF'  | 'CHIP'   | 'CS34753F911'(!)        = ''              | ''                 | 'CS34753F911'           |'R0603'| '(SMR0603AW)'                  | '47.5K'   | '1%'    | '1/10W ' | 'DISCRETE' | 'RES CHIP 47.5K 1/10W +-1%(0603)'                  | 'CHIP0603'     | ''          | ''            | '20100621'
 '47.5K'      | '1%'      | '1/10W'  | '0603LF'  | 'EMPTY'  | 'CS34753F911'(!)        = ''              | ''                 | 'CS34753F911'           |'R0603'| '(SMR0603AW)'                  | '47.5K'   | '1%'    | '1/10W ' | 'IO'       | 'RES CHIP 47.5K 1/10W +-1%(0603)'                  | 'CHIP0603'     | ''          | ''            | '20100621'
 '47.5K'      | '1%'      | '1/16W'  | '0402LF'  | 'CHIP'   | 'CS34752FB14'(!)        = 'End of Design' | 'Comp-Approve'     | 'CS34752FB14'           |'R0402'| '(R0402-0201)'                 | '47.5K'   | '1%'    | '1/16W'  | 'DISCRETE' | 'RES CHIP 47.5K 1/16W +-1% (0402)'                 | 'CHIP0402'     | ''          | ''            | '20100621'
 '47.5K'      | '1%'      | '1/16W'  | '0402LF'  | 'EMPTY'  | 'CS34752FB14'(!)        = 'End of Design' | 'Comp-Approve'     | 'CS34752FB14'           |'R0402'| '(R0402-0201)'                 | '47.5K'   | '1%'    | '1/16W'  | 'IO'       | 'RES CHIP 47.5K 1/16W +-1% (0402)'                 | 'CHIP0402'     | ''          | ''            | '20100621'
 '130'        | '1%'      | '1/16W'  | '0402LF'  | 'CHIP'   | 'CS11302FB15'(!)        = 'End of Design' | 'Comp-Approve'     | 'CS11302FB15'           |'R0402'| '(R0402-0201)'                 | '130'     | '1%'    | '1/16W'  | 'DISCRETE' | 'RES CHIP 130 1/16W +-1%(0402)'                    | 'CHIP0402'     | ''          | ''            | '20100621'
 '130'        | '1%'      | '1/16W'  | '0402LF'  | 'EMPTY'  | 'CS11302FB15'(!)        = 'End of Design' | 'Comp-Approve'     | 'CS11302FB15'           |'R0402'| '(R0402-0201)'                 | '130'     | '1%'    | '1/16W'  | 'IO'       | 'RES CHIP 130 1/16W +-1%(0402)'                    | 'CHIP0402'     | ''          | ''            | '20100621'
 '23.7K'      | '1%'      | '1/16W'  | '0402LF'  | 'CHIP'   | 'CS32372FB05'(!)        = 'End of Design' | 'Comp-Approve'     | 'CS32372FB05'           |'R0402'| '(R0402-0201)'                 | '23.7K'   | '1%'    | '1/16W'  | 'DISCRETE' | 'RES CHIP 23.7K 1/16W +-1%(0402)'                  | 'CHIP0402'     | ''          | ''            | '20100621'
 '23.7K'      | '1%'      | '1/16W'  | '0402LF'  | 'EMPTY'  | 'CS32372FB05'(!)        = 'End of Design' | 'Comp-Approve'     | 'CS32372FB05'           |'R0402'| '(R0402-0201)'                 | '23.7K'   | '1%'    | '1/16W'  | 'IO'       | 'RES CHIP 23.7K 1/16W +-1%(0402)'                  | 'CHIP0402'     | ''          | ''            | '20100621'
 '6.98K'      | '1%'      | '1/16W'  | '0402LF'  | 'CHIP'   | 'CS26982FB01'(!)        = 'End of Design' | 'Comp-Approve'     | 'CS26982FB01'           |'R0402'| '(R0402-0201)'                 | '6.98K'   | '1%'    | '1/16W'  | 'DISCRETE' | 'RES CHIP 6.98K 1/16W +-1% (0402)'                 | 'CHIP0402'     | ''          | ''            | '20100622'
 '6.98K'      | '1%'      | '1/16W'  | '0402LF'  | 'EMPTY'  | 'CS26982FB01'(!)        = 'End of Design' | 'Comp-Approve'     | 'CS26982FB01'           |'R0402'| '(R0402-0201)'                 | '6.98K'   | '1%'    | '1/16W'  | 'IO'       | 'RES CHIP 6.98K 1/16W +-1% (0402)'                 | 'CHIP0402'     | ''          | ''            | '20100622'
 '845'        | '1%'      | '1/16W'  | '0402LF'  | 'CHIP'   | 'CS18452FB11'(!)        = 'End of Design' | 'Comp-Approve'     | 'CS18452FB11'           |'R0402'| '(R0402-0201)'                 | '845'     | '1%'    | '1/16W'  | 'DISCRETE' | 'RES CHIP 845 1/16W +-1%(0402) '                   | 'CHIP0402'     | ''          | ''            | '20100622'
 '845'        | '1%'      | '1/16W'  | '0402LF'  | 'EMPTY'  | 'CS18452FB11'(!)        = 'End of Design' | 'Comp-Approve'     | 'CS18452FB11'           |'R0402'| '(R0402-0201)'                 | '845'     | '1%'    | '1/16W'  | 'IO'       | 'RES CHIP 845 1/16W +-1%(0402) '                   | 'CHIP0402'     | ''          | ''            | '20100622'
 '1.05K'      | '1%'      | '1/16W'  | '0402LF'  | 'CHIP'   | 'CS21052FB00'(!)        = 'End of Design' | 'Comp-Approve'     | 'CS21052FB00'           |'R0402'| '(R0402-0201)'                 | '1.05K'   | '1%'    | '1/16W'  | 'DISCRETE' | 'RES CHIP 1.05K 1/16W +-1%(0402)'                  | 'CHIP0402'     | ''          | ''            | '20100723'
 '1.05K'      | '1%'      | '1/16W'  | '0402LF'  | 'EMPTY'  | 'CS21052FB00'(!)        = 'End of Design' | 'Comp-Approve'     | 'CS21052FB00'           |'R0402'| '(R0402-0201)'                 | '1.05K'   | '1%'    | '1/16W'  | 'IO'       | 'RES CHIP 1.05K 1/16W +-1%(0402)'                  | 'CHIP0402'     | ''          | ''            | '20100723'
 '1.02K'      | '1%'      | '1/16W'  | '0402LF'  | 'CHIP'   | 'CS21022FB15'(!)        = 'End of Design' | 'Comp-Approve'     | 'CS21022FB15'           |'R0402'| '(R0402-0201)'                 | '1.02K'   | '1%'    | '1/16W'  | 'DISCRETE' | 'RES CHIP 1.02K 1/16W +-1%(0402)'                  | 'CHIP0402'     | ''          | ''            | '20100622'
 '1.02K'      | '1%'      | '1/16W'  | '0402LF'  | 'EMPTY'  | 'CS21022FB15'(!)        = 'End of Design' | 'Comp-Approve'     | 'CS21022FB15'           |'R0402'| '(R0402-0201)'                 | '1.02K'   | '1%'    | '1/16W'  | 'IO'       | 'RES CHIP 1.02K 1/16W +-1%(0402)'                  | 'CHIP0402'     | ''          | ''            | '20100622'
 '115K'       | '1%'      | '1/16W'  | '0402LF'  | 'CHIP'   | 'CS41152FB08'(!)        = 'End of Design' | 'Comp-Approve'     | 'CS41152FB08'           |'R0402'| '(R0402-0201)'                 | '115K'    | '1%'    | '1/16W'  | 'DISCRETE' | 'RES CHIP 115K 1/16W +-1%(0402)'                   | 'CHIP0402'     | ''          | ''            | '20100623'
 '115K'       | '1%'      | '1/16W'  | '0402LF'  | 'EMPTY'  | 'CS41152FB08'(!)        = 'End of Design' | 'Comp-Approve'     | 'CS41152FB08'           |'R0402'| '(R0402-0201)'                 | '115K'    | '1%'    | '1/16W'  | 'IO'       | 'RES CHIP 115K 1/16W +-1%(0402)'                   | 'CHIP0402'     | ''          | ''            | '20100623'
 '28.7K'      | '1%'      | '1/16W'  | '0402LF'  | 'CHIP'   | 'CS32872FB11'(!)        = 'End of Design' | 'Comp-Approve'     | 'CS32872FB11'           |'R0402'| '(R0402-0201)'                 | '28.7K'   | '1%'    | '1/16W'  | 'DISCRETE' | 'RES CHIP 28.7K 1/16W +-1%(0402)'                  | 'CHIP0402'     | ''          | ''            | '20100623'
 '28.7K'      | '1%'      | '1/16W'  | '0402LF'  | 'EMPTY'  | 'CS32872FB11'(!)        = 'End of Design' | 'Comp-Approve'     | 'CS32872FB11'           |'R0402'| '(R0402-0201)'                 | '28.7K'   | '1%'    | '1/16W'  | 'IO'       | 'RES CHIP 28.7K 1/16W +-1%(0402)'                  | 'CHIP0402'     | ''          | ''            | '20100623'
 '6.04K'      | '1%'      | '1/16W'  | '0402LF'  | 'CHIP'   | 'CS26042FB00'(!)        = 'End of Design' | 'Comp-Approve'     | 'CS26042FB00'           |'R0402'| '(R0402-0201)'                 | '6.04K'   | '1%'    | '1/16W'  | 'DISCRETE' | 'RES CHIP 6.04K 1/16W +-1%(0402)'                  | 'CHIP0402'     | ''          | ''            | '20100630'
 '6.04K'      | '1%'      | '1/16W'  | '0402LF'  | 'EMPTY'  | 'CS26042FB00'(!)        = 'End of Design' | 'Comp-Approve'     | 'CS26042FB00'           |'R0402'| '(R0402-0201)'                 | '6.04K'   | '1%'    | '1/16W'  | 'IO'       | 'RES CHIP 6.04K 1/16W +-1%(0402)'                  | 'CHIP0402'     | ''          | ''            | '20100630'
 '45'         | '1%'      | '1/16W'  | '0402LF'  | 'CHIP'   | 'CS04502FB01'(!)        = ''              | ''                 | 'CS04502FB01'           |'R0402'| '(R0402-0201)'                 | '45'      | '1%'    | '1/16W'  | 'DISCRETE' | 'RES CHIP 45 1/16W +-1%(0402)'                     | 'CHIP0402'     | ''          | ''            | '20100630'
 '45'         | '1%'      | '1/16W'  | '0402LF'  | 'EMPTY'  | 'CS04502FB01'(!)        = ''              | ''                 | 'CS04502FB01'           |'R0402'| '(R0402-0201)'                 | '45'      | '1%'    | '1/16W'  | 'IO'       | 'RES CHIP 45 1/16W +-1%(0402)'                     | 'CHIP0402'     | ''          | ''            | '20100630'
 '196K'       | '1%'      | '1/16W'  | '0402LF'  | 'CHIP'   | 'CS41962FB01'(!)        = 'End of Design' | 'Comp-Approve'     | 'CS41962FB01'           |'R0402'| '(R0402-0201)'                 | '196K'    | '1%'    | '1/16W'  | 'DISCRETE' | 'RES CHIP 196K 1/16W +-1% (0402)'                  | 'CHIP0402'     | ''          | ''            | '20100702'
 '196K'       | '1%'      | '1/16W'  | '0402LF'  | 'EMPTY'  | 'CS41962FB01'(!)        = 'End of Design' | 'Comp-Approve'     | 'CS41962FB01'           |'R0402'| '(R0402-0201)'                 | '196K'    | '1%'    | '1/16W'  | 'IO'       | 'RES CHIP 196K 1/16W +-1% (0402)'                  | 'CHIP0402'     | ''          | ''            | '20100702'
 '158K'       | '1%'      | '1/16W'  | '0402LF'  | 'CHIP'   | 'CS41582FB06'(!)        = ''              | ''                 | 'CS41582FB06'           |'R0402'| '(R0402-0201)'                 | '158K'    | '1%'    | '1/16W'  | 'DISCRETE' | 'RES CHIP 158K 1/16W +-1% (0402)'                  | 'CHIP0402'     | ''          | ''            | '20100702'
 '158K'       | '1%'      | '1/16W'  | '0402LF'  | 'EMPTY'  | 'CS41582FB06'(!)        = ''              | ''                 | 'CS41582FB06'           |'R0402'| '(R0402-0201)'                 | '158K'    | '1%'    | '1/16W'  | 'IO'       | 'RES CHIP 158K 1/16W +-1% (0402)'                  | 'CHIP0402'     | ''          | ''            | '20100702'
 '300'        | '1%'      | '1/8W'   | '0805LF'  | 'CHIP'   | 'CS13004FA00'(!)        = ''              | ''                 | 'CS13004FA00'           |'R0805'| '(SMR0805AW)'                  | '300'     | '1%'    | '1/8W'   | 'DISCRETE' | 'RES CHIP 300 1/8W +-1%(0805)'                     | 'CHIP0805'     | ''          | ''            | '20100706'
 '300'        | '1%'      | '1/8W'   | '0805LF'  | 'EMPTY'  | 'CS13004FA00'(!)        = ''              | ''                 | 'CS13004FA00'           |'R0805'| '(SMR0805AW)'                  | '300'     | '1%'    | '1/8W'   | 'IO'       | 'RES CHIP 300 1/8W +-1%(0805)'                     | 'CHIP0805'     | ''          | ''            | '20100706'
 '0.5'        | '5%'      | '1/2W'   | '1210LF'  | 'CHIP'   | 'CS+5007J300'(!)        = ''              | ''                 | 'CS+5007J300'           |'R1210'| '(SMR1210AW)'                  | '0.5'     | '5%'    | '1/2W'   | 'DISCRETE' | 'RES CHIP 0.5 1/2W +-5% (1210)'                    | 'CHIP1210'     | ''          | ''            | '20100706'
 '0.5'        | '5%'      | '1/2W'   | '1210LF'  | 'EMPTY'  | 'CS+5007J300'(!)        = ''              | ''                 | 'CS+5007J300'           |'R1210'| '(SMR1210AW)'                  | '0.5'     | '5%'    | '1/2W'   | 'IO'       | 'RES CHIP 0.5 1/2W +-5% (1210)'                    | 'CHIP1210'     | ''          | ''            | '20100706'
 '499K'       | '1%'      | '1/10W'  | '0603LF'  | 'CHIP'   | 'CS44993F918'(!)        = ''              | ''                 | 'CS44993F918'           |'R0603'| '(SMR0603AW)'                  | '499K'    | '1%'    | '1/10W ' | 'DISCRETE' | 'RES CHIP 499K 1/10W +-1%(0603)'                   | 'CHIP0603'     | ''          | ''            | '20100708'
 '499K'       | '1%'      | '1/10W'  | '0603LF'  | 'EMPTY'  | 'CS44993F918'(!)        = ''              | ''                 | 'CS44993F918'           |'R0603'| '(SMR0603AW)'                  | '499K'    | '1%'    | '1/10W ' | 'IO'       | 'RES CHIP 499K 1/10W +-1%(0603)'                   | 'CHIP0603'     | ''          | ''            | '20100708'
 '33'         | '5%'      | '1/16W'  | '0402LF'  | 'CHIP'   | 'CS03302JB29'(!)        = 'End of Design' | 'Comp-Approve'     | 'CS03302JB29'           |'R0402'| '(R0402-0201)'                 | '33'      | '5%'    | '1/16W'  | 'DISCRETE' | 'RES CHIP 33 1/16W +-5% (0402)'                    | 'CHIP0402'     | ''          | ''            | '20100708'
 '33'         | '5%'      | '1/16W'  | '0402LF'  | 'EMPTY'  | 'CS03302JB29'(!)        = 'End of Design' | 'Comp-Approve'     | 'CS03302JB29'           |'R0402'| '(R0402-0201)'                 | '33'      | '5%'    | '1/16W'  | 'IO'       | 'RES CHIP 33 1/16W +-5% (0402)'                    | 'CHIP0402'     | ''          | ''            | '20100708'
 '330'        | '5%'      | '1/10W'  | '0603LF'  | 'CHIP'   | 'CS13303J943'(!)        = ''              | ''                 | 'CS13303J943'           |'R0603'| '(SMR0603AW)'                  | '330'     | '5%'    | '1/10W ' | 'DISCRETE' | 'RES CHIP 330 1/10W +-5%(0603)'                    | 'CHIP0603'     | ''          | ''            | '20100708'
 '330'        | '5%'      | '1/10W'  | '0603LF'  | 'EMPTY'  | 'CS13303J943'(!)        = ''              | ''                 | 'CS13303J943'           |'R0603'| '(SMR0603AW)'                  | '330'     | '5%'    | '1/10W ' | 'IO'       | 'RES CHIP 330 1/10W +-5%(0603)'                    | 'CHIP0603'     | ''          | ''            | '20100708'
 '4.7K'       | '5%'      | '1/10W'  | '0603LF'  | 'CHIP'   | 'CS24703J942'(!)        = ''              | ''                 | 'CS24703J942'           |'R0603'| '(SMR0603AW)'                  | '4.7K'    | '5%'    | '1/10W ' | 'DISCRETE' | 'RES CHIP 4.7K 1/10W +-5%(0603)'                   | 'CHIP0603'     | ''          | ''            | '20100708'
 '4.7K'       | '5%'      | '1/10W'  | '0603LF'  | 'EMPTY'  | 'CS24703J942'(!)        = ''              | ''                 | 'CS24703J942'           |'R0603'| '(SMR0603AW)'                  | '4.7K'    | '5%'    | '1/10W ' | 'IO'       | 'RES CHIP 4.7K 1/10W +-5%(0603)'                   | 'CHIP0603'     | ''          | ''            | '20100708'
 '100'        | '1%'      | '1/10W'  | '0603LF'  | 'CHIP'   | 'CS11003F953'(!)        = ''              | ''                 | 'CS11003F953'           |'R0603'| '(SMR0603AW)'                  | '100'     | '1%'    | '1/10W ' | 'DISCRETE' | 'RESISTOR CHIP 100 1/10W+-1%(0603)'                | 'CHIP0603'     | ''          | ''            | '20100708'
 '100'        | '1%'      | '1/10W'  | '0603LF'  | 'EMPTY'  | 'CS11003F953'(!)        = ''              | ''                 | 'CS11003F953'           |'R0603'| '(SMR0603AW)'                  | '100'     | '1%'    | '1/10W ' | 'IO'       | 'RESISTOR CHIP 100 1/10W+-1%(0603)'                | 'CHIP0603'     | ''          | ''            | '20100708'
 '1K'         | '1%'      | '1/10W'  | '0603LF'  | 'CHIP'   | 'CS21003F947'(!)        = ''              | ''                 | 'CS21003F947'           |'R0603'| '(SMR0603AW)'                  | '1K'      | '1%'    | '1/10W ' | 'DISCRETE' | 'RESISTOR CHIP 1K,1/10W,+-1%(0603)'                | 'CHIP0603'     | ''          | ''            | '20100708'
 '1K'         | '1%'      | '1/10W'  | '0603LF'  | 'EMPTY'  | 'CS21003F947'(!)        = ''              | ''                 | 'CS21003F947'           |'R0603'| '(SMR0603AW)'                  | '1K'      | '1%'    | '1/10W ' | 'IO'       | 'RESISTOR CHIP 1K,1/10W,+-1%(0603)'                | 'CHIP0603'     | ''          | ''            | '20100708'
 '20K'        | '1%'      | '1/16W'  | '0402LF'  | 'CHIP'   | 'CS32002FB29'(!)        = 'End of Design' | 'Comp-Approve'     | 'CS32002FB29'           |'R0402'| '(R0402-0201)'                 | '20K'     | '1%'    | '1/16W'  | 'DISCRETE' | 'RES CHIP 20K 1/16W +-1%(0402)'                    | 'CHIP0402'     | ''          | ''            | '20100708'
 '20K'        | '1%'      | '1/16W'  | '0402LF'  | 'EMPTY'  | 'CS32002FB29'(!)        = 'End of Design' | 'Comp-Approve'     | 'CS32002FB29'           |'R0402'| '(R0402-0201)'                 | '20K'     | '1%'    | '1/16W'  | 'IO'       | 'RES CHIP 20K 1/16W +-1%(0402)'                    | 'CHIP0402'     | ''          | ''            | '20100708'
 '130'        | '5%'      | '1/16W'  | '0402LF'  | 'CHIP'   | 'CS11302JB17'(!)        = 'End of Design' | 'Comp-Approve'     | 'CS11302JB17'           |'R0402'| '(R0402-0201)'                 | '130'     | '5%'    | '1/16W'  | 'DISCRETE' | 'RES CHIP 130(1/16W,+-5%,0402)'                    | 'CHIP0402'     | ''          | ''            | '20100708'
 '130'        | '5%'      | '1/16W'  | '0402LF'  | 'EMPTY'  | 'CS11302JB17'(!)        = 'End of Design' | 'Comp-Approve'     | 'CS11302JB17'           |'R0402'| '(R0402-0201)'                 | '130'     | '5%'    | '1/16W'  | 'IO'       | 'RES CHIP 130(1/16W,+-5%,0402)'                    | 'CHIP0402'     | ''          | ''            | '20100708'
 '4.7K'       | '1%'      | '1/16W'  | '0402LF'  | 'CHIP'   | 'CS24702FB10'(!)        = 'End of Design' | 'Comp-Approve'     | 'CS24702FB10'           |'R0402'| '(R0402-0201)'                 | '4.7K'    | '1%'    | '1/16W'  | 'DISCRETE' | 'RES CHIP 4.7K 1/16W +-1%(0402)'                   | 'CHIP0402'     | ''          | ''            | '20100708'
 '4.7K'       | '1%'      | '1/16W'  | '0402LF'  | 'EMPTY'  | 'CS24702FB10'(!)        = 'End of Design' | 'Comp-Approve'     | 'CS24702FB10'           |'R0402'| '(R0402-0201)'                 | '4.7K'    | '1%'    | '1/16W'  | 'IO'       | 'RES CHIP 4.7K 1/16W +-1%(0402)'                   | 'CHIP0402'     | ''          | ''            | '20100708'
 '100K'       | '5%'      | '1/16W'  | '0402LF'  | 'CHIP'   | 'CS41002JB20'(!)        = 'End of Design' | 'Comp-Approve'     | 'CS41002JB20'           |'R0402'| '(R0402-0201)'                 | '100K'    | '5%'    | '1/16W'  | 'DISCRETE' | 'RES CHIP 100K 1/16W 5%(0402)'                     | 'CHIP0402'     | ''          | ''            | '20100708'
 '100K'       | '5%'      | '1/16W'  | '0402LF'  | 'EMPTY'  | 'CS41002JB20'(!)        = 'End of Design' | 'Comp-Approve'     | 'CS41002JB20'           |'R0402'| '(R0402-0201)'                 | '100K'    | '5%'    | '1/16W'  | 'IO'       | 'RES CHIP 100K 1/16W 5%(0402)'                     | 'CHIP0402'     | ''          | ''            | '20100708'
 '220'        | '5%'      | '1/16W'  | '0402LF'  | 'CHIP'   | 'CS12202JB24'(!)        = 'End of Design' | 'Comp-Approve'     | 'CS12202JB24'           |'R0402'| '(R0402-0201)'                 | '220'     | '5%'    | '1/16W'  | 'DISCRETE' | 'RES CHIP 220 1/16W +-5%(0402)'                    | 'CHIP0402'     | ''          | ''            | '20100708'
 '220'        | '5%'      | '1/16W'  | '0402LF'  | 'EMPTY'  | 'CS12202JB24'(!)        = 'End of Design' | 'Comp-Approve'     | 'CS12202JB24'           |'R0402'| '(R0402-0201)'                 | '220'     | '5%'    | '1/16W'  | 'IO'       | 'RES CHIP 220 1/16W +-5%(0402)'                    | 'CHIP0402'     | ''          | ''            | '20100708'
 '487'        | '1%'      | '1/16W'  | '0402LF'  | 'CHIP'   | 'CS14872FB05'(!)        = 'End of Design' | 'Comp-Approve'     | 'CS14872FB05'           |'R0402'| '(R0402-0201)'                 | '487'     | '1%'    | '1/16W'  | 'DISCRETE' | 'RES CHIP 487 1/16W +-1%(0402)'                    | 'CHIP0402'     | ''          | ''            | '20100712'
 '487'        | '1%'      | '1/16W'  | '0402LF'  | 'EMPTY'  | 'CS14872FB05'(!)        = 'End of Design' | 'Comp-Approve'     | 'CS14872FB05'           |'R0402'| '(R0402-0201)'                 | '487'     | '1%'    | '1/16W'  | 'IO'       | 'RES CHIP 487 1/16W +-1%(0402)'                    | 'CHIP0402'     | ''          | ''            | '20100712'
 '1.1K'       | '1%'      | '1/16W'  | '0402LF'  | 'CHIP'   | 'CS21102FB10'(!)        = 'End of Design' | 'Comp-Approve'     | 'CS21102FB10'           |'R0402'| '(R0402-0201)'                 | '1.1K'    | '1%'    | '1/16W'  | 'DISCRETE' | 'RES CHIP 1.1K 1/16W +-1% (0402)'                  | 'CHIP0402'     | ''          | ''            | '20100712'
 '1.1K'       | '1%'      | '1/16W'  | '0402LF'  | 'EMPTY'  | 'CS21102FB10'(!)        = 'End of Design' | 'Comp-Approve'     | 'CS21102FB10'           |'R0402'| '(R0402-0201)'                 | '1.1K'    | '1%'    | '1/16W'  | 'IO'       | 'RES CHIP 1.1K 1/16W +-1% (0402)'                  | 'CHIP0402'     | ''          | ''            | '20100712'
 '68'         | '1%'      | '1/16W'  | '0402LF'  | 'CHIP'   | 'CS06802FB07'(!)        = 'End of Design' | 'Comp-Approve'     | 'CS06802FB07'           |'R0402'| '(R0402-0201)'                 | '68'      | '1%'    | '1/16W'  | 'DISCRETE' | 'RES CHIP 68 1/16W +-1%(0402)'                     | 'CHIP0402'     | ''          | ''            | '20100712'
 '68'         | '1%'      | '1/16W'  | '0402LF'  | 'EMPTY'  | 'CS06802FB07'(!)        = 'End of Design' | 'Comp-Approve'     | 'CS06802FB07'           |'R0402'| '(R0402-0201)'                 | '68'      | '1%'    | '1/16W'  | 'IO'       | 'RES CHIP 68 1/16W +-1%(0402)'                     | 'CHIP0402'     | ''          | ''            | '20100712'
 '21K'        | '1%'      | '1/16W'  | '0402LF'  | 'CHIP'   | 'CS32102FB14'(!)        = 'End of Design' | 'Comp-Approve'     | 'CS32102FB14'           |'R0402'| '(R0402-0201)'                 | '21K '    | '1%'    | '1/16W'  | 'DISCRETE' | 'RES CHIP 21K 1/16W +-1%(0402)'                    | 'CHIP0402'     | ''          | ''            | '20100712'
 '21K'        | '1%'      | '1/16W'  | '0402LF'  | 'EMPTY'  | 'CS32102FB14'(!)        = 'End of Design' | 'Comp-Approve'     | 'CS32102FB14'           |'R0402'| '(R0402-0201)'                 | '21K '    | '1%'    | '1/16W'  | 'IO'       | 'RES CHIP 21K 1/16W +-1%(0402)'                    | 'CHIP0402'     | ''          | ''            | '20100712'
 '453'        | '1%'      | '1/16W'  | '0402LF'  | 'CHIP'   | 'CS14532FB14'(!)        = 'End of Design' | 'Comp-Approve'     | 'CS14532FB14'           |'R0402'| '(R0402-0201)'                 | '453'     | '1%'    | '1/16W'  | 'DISCRETE' | 'RES CHIP 453 1/16W +-1% (0402) '                  | 'CHIP0402'     | ''          | ''            | '20100712'
 '453'        | '1%'      | '1/16W'  | '0402LF'  | 'EMPTY'  | 'CS14532FB14'(!)        = 'End of Design' | 'Comp-Approve'     | 'CS14532FB14'           |'R0402'| '(R0402-0201)'                 | '453'     | '1%'    | '1/16W'  | 'IO'       | 'RES CHIP 453 1/16W +-1% (0402) '                  | 'CHIP0402'     | ''          | ''            | '20100712'
 '0'          | '5%'      | '1/8W'   | '0805LF'  | 'CHIP'   | 'CS00004JA40'(!)        = ''              | ''                 | 'CS00004JA40'           |'R0805'| '(SMR0805AW)'                  | '0'       | '5%'    | '1/8W'   | 'DISCRETE' | 'RESISTOR CHIP 0 1/8W +-5%(0805)'                  | 'CHIP0805'     | ''          | ''            | '20100713'
 '0'          | '5%'      | '1/8W'   | '0805LF'  | 'EMPTY'  | 'CS00004JA40'(!)        = ''              | ''                 | 'CS00004JA40'           |'R0805'| '(SMR0805AW)'                  | '0'       | '5%'    | '1/8W'   | 'IO'       | 'RESISTOR CHIP 0 1/8W +-5%(0805)'                  | 'CHIP0805'     | ''          | ''            | '20100713'
 '2.21K'      | '1%'      | '1/16W'  | '0402LF'  | 'CHIP'   | 'CS22212FB02'(!)        = ''              | ''                 | 'CS22212FB02'           |'R0402'| '(R0402-0201)'                 | '2.21K'   | '1%'    | '1/16W'  | 'DISCRETE' | 'RES CHIP 2.21K 1/16W +-1% (0402)'                 | 'CHIP0402'     | ''          | ''            | '20100713'
 '2.21K'      | '1%'      | '1/16W'  | '0402LF'  | 'EMPTY'  | 'CS22212FB02'(!)        = ''              | ''                 | 'CS22212FB02'           |'R0402'| '(R0402-0201)'                 | '2.21K'   | '1%'    | '1/16W'  | 'IO'       | 'RES CHIP 2.21K 1/16W +-1% (0402)'                 | 'CHIP0402'     | ''          | ''            | '20100713'
 '8.25K'      | '1%'      | '1/16W'  | '0402LF'  | 'CHIP'   | 'CS28252FB07'(!)        = ''              | ''                 | 'CS28252FB07'           |'R0402'| '(R0402-0201)'                 | '8.25K'   | '1%'    | '1/16W'  | 'DISCRETE' | 'RES CHIP 8.25K 1/16W +-1% (0402)'                 | 'CHIP0402'     | ''          | ''            | '20100715'
 '8.25K'      | '1%'      | '1/16W'  | '0402LF'  | 'EMPTY'  | 'CS28252FB07'(!)        = ''              | ''                 | 'CS28252FB07'           |'R0402'| '(R0402-0201)'                 | '8.25K'   | '1%'    | '1/16W'  | 'IO'       | 'RES CHIP 8.25K 1/16W +-1% (0402)'                 | 'CHIP0402'     | ''          | ''            | '20100715'
 '680  '      | '1%'      | '1/16W'  | '0402LF'  | 'CHIP'   | 'CS16802FB09'(!)        = 'End of Design' | 'Comp-Approve'     | 'CS16802FB09'           |'R0402'| '(R0402-0201)'                 | '680'     | '1%'    | '1/16W'  | 'DISCRETE' | 'RES CHIP 680 1/16W +-1%(0402)'                    | 'CHIP0402'     | ''          | ''            | '20100715'
 '680  '      | '1%'      | '1/16W'  | '0402LF'  | 'EMPTY'  | 'CS16802FB09'(!)        = 'End of Design' | 'Comp-Approve'     | 'CS16802FB09'           |'R0402'| '(R0402-0201)'                 | '680'     | '1%'    | '1/16W'  | 'IO'       | 'RES CHIP 680 1/16W +-1%(0402)'                    | 'CHIP0402'     | ''          | ''            | '20100715'
 '750'        | '1%'      | '1/16W'  | '0402LF'  | 'CHIP'   | 'CS17502FB19'(!)        = 'End of Design' | 'Comp-Approve'     | 'CS17502FB19'           |'R0402'| '(R0402-0201)'                 | '750'     | '1%'    | '1/16W'  | 'DISCRETE' | 'RES CHIP 750 1/16W +-1%(0402)'                    | 'CHIP0402'     | ''          | ''            | '20100715'
 '750'        | '1%'      | '1/16W'  | '0402LF'  | 'EMPTY'  | 'CS17502FB19'(!)        = 'End of Design' | 'Comp-Approve'     | 'CS17502FB19'           |'R0402'| '(R0402-0201)'                 | '750'     | '1%'    | '1/16W'  | 'IO'       | 'RES CHIP 750 1/16W +-1%(0402)'                    | 'CHIP0402'     | ''          | ''            | '20100715'
 '15   '      | '1%'      | '1/16W'  | '0402LF'  | 'CHIP'   | 'CS01502FB11'(!)        = 'End of Design' | 'Comp-Approve'     | 'CS01502FB11'           |'R0402'| '(R0402-0201)'                 | '15'      | '1%'    | '1/16W'  | 'DISCRETE' | 'RES CHIP 15 1/16W +-1%(0402)'                     | 'CHIP0402'     | ''          | ''            | '20100715'
 '15   '      | '1%'      | '1/16W'  | '0402LF'  | 'EMPTY'  | 'CS01502FB11'(!)        = 'End of Design' | 'Comp-Approve'     | 'CS01502FB11'           |'R0402'| '(R0402-0201)'                 | '15'      | '1%'    | '1/16W'  | 'IO'       | 'RES CHIP 15 1/16W +-1%(0402)'                     | 'CHIP0402'     | ''          | ''            | '20100715'
 '1M'         | '5%'      | '1/16W'  | '0402LF'  | 'CHIP'   | 'CS51002JB21'(!)        = 'End of Design' | 'Comp-Approve'     | 'CS51002JB21'           |'R0402'| '(R0402-0201)'                 | '1M'      | '5%'    | '1/16W'  | 'DISCRETE' | 'RES CHIP 1M 1/16W +-5% (0402)'                    | 'CHIP0402'     | ''          | ''            | '20100715'
 '1M'         | '5%'      | '1/16W'  | '0402LF'  | 'EMPTY'  | 'CS51002JB21'(!)        = 'End of Design' | 'Comp-Approve'     | 'CS51002JB21'           |'R0402'| '(R0402-0201)'                 | '1M'      | '5%'    | '1/16W'  | 'IO'       | 'RES CHIP 1M 1/16W +-5% (0402)'                    | 'CHIP0402'     | ''          | ''            | '20100715'
 '47   '      | '5%'      | '1/16W'  | '0402LF'  | 'CHIP'   | 'CS04702JB18'(!)        = 'End of Design' | 'Comp-Approve'     | 'CS04702JB18'           |'R0402'| '(R0402-0201)'                 | '47'      | '5%'    | '1/16W'  | 'DISCRETE' | 'RES CHIP 47 1/16W +-5%(0402)'                     | 'CHIP0402'     | ''          | ''            | '20100715'
 '47   '      | '5%'      | '1/16W'  | '0402LF'  | 'EMPTY'  | 'CS04702JB18'(!)        = 'End of Design' | 'Comp-Approve'     | 'CS04702JB18'           |'R0402'| '(R0402-0201)'                 | '47'      | '5%'    | '1/16W'  | 'IO'       | 'RES CHIP 47 1/16W +-5%(0402)'                     | 'CHIP0402'     | ''          | ''            | '20100715'
 '330  '      | '5%'      | '1/16W'  | '0402LF'  | 'CHIP'   | 'CS13302JB21'(!)        = 'End of Design' | 'Comp-Approve'     | 'CS13302JB21'           |'R0402'| '(R0402-0201)'                 | '330'     | '5%'    | '1/16W'  | 'DISCRETE' | 'RES CHIP 330(1/16W +-5% 0402)'                    | 'CHIP0402'     | ''          | ''            | '20100715'
 '330  '      | '5%'      | '1/16W'  | '0402LF'  | 'EMPTY'  | 'CS13302JB21'(!)        = 'End of Design' | 'Comp-Approve'     | 'CS13302JB21'           |'R0402'| '(R0402-0201)'                 | '330'     | '5%'    | '1/16W'  | 'IO'       | 'RES CHIP 330(1/16W +-5% 0402)'                    | 'CHIP0402'     | ''          | ''            | '20100715'
 '470  '      | '5%'      | '1/16W'  | '0402LF'  | 'CHIP'   | 'CS14702JB28'(!)        = 'End of Design' | 'Comp-Approve'     | 'CS14702JB28'           |'R0402'| '(R0402-0201)'                 | '470'     | '5%'    | '1/16W'  | 'DISCRETE' | 'RES CHIP 470 1/16W +-5% (0402)'                   | 'CHIP0402'     | ''          | ''            | '20100715'
 '470  '      | '5%'      | '1/16W'  | '0402LF'  | 'EMPTY'  | 'CS14702JB28'(!)        = 'End of Design' | 'Comp-Approve'     | 'CS14702JB28'           |'R0402'| '(R0402-0201)'                 | '470'     | '5%'    | '1/16W'  | 'IO'       | 'RES CHIP 470 1/16W +-5% (0402)'                   | 'CHIP0402'     | ''          | ''            | '20100715'
 '2.2K'       | '5%'      | '1/16W'  | '0402LF'  | 'CHIP'   | 'CS22202JB18'(!)        = 'End of Design' | 'Comp-Approve'     | 'CS22202JB18'           |'R0402'| '(R0402-0201)'                 | '2.2K'    | '5%'    | '1/16W'  | 'DISCRETE' | 'RES CHIP 2.2K 1/16W +-5%(0402)'                   | 'CHIP0402'     | ''          | ''            | '20100715'
 '2.2K'       | '5%'      | '1/16W'  | '0402LF'  | 'EMPTY'  | 'CS22202JB18'(!)        = 'End of Design' | 'Comp-Approve'     | 'CS22202JB18'           |'R0402'| '(R0402-0201)'                 | '2.2K'    | '5%'    | '1/16W'  | 'IO'       | 'RES CHIP 2.2K 1/16W +-5%(0402)'                   | 'CHIP0402'     | ''          | ''            | '20100715'
 '4.7K '      | '5%'      | '1/16W'  | '0402LF'  | 'CHIP'   | 'CS24702JB03'(!)        = 'End of Design' | 'Comp-Approve'     | 'CS24702JB03'           |'R0402'| '(R0402-0201)'                 | '4.7K'    | '5%'    | '1/16W'  | 'DISCRETE' | 'RES CHIP 4.7K 1/16W +-5% (0402)'                  | 'CHIP0402'     | ''          | ''            | '20100715'
 '4.7K '      | '5%'      | '1/16W'  | '0402LF'  | 'EMPTY'  | 'CS24702JB03'(!)        = 'End of Design' | 'Comp-Approve'     | 'CS24702JB03'           |'R0402'| '(R0402-0201)'                 | '4.7K'    | '5%'    | '1/16W'  | 'IO'       | 'RES CHIP 4.7K 1/16W +-5% (0402)'                  | 'CHIP0402'     | ''          | ''            | '20100715'
 '4.7K '      | '5%'      | '1/16W'  | '0402LF'  | 'CHIP'   | 'CS24702JB11'(!)        = ''              | ''                 | 'CS24702JB11'           |'R0402'| '(R0402-0201)'                 | '4.7K'    | '5%'    | '1/16W'  | 'DISCRETE' | 'RES CHIP 4.7K 1/16W +-5% (0402)ES-PAL'            | 'CHIP0402'     | ''          | ''            | '20100715'
 '4.7K '      | '5%'      | '1/16W'  | '0402LF'  | 'EMPTY'  | 'CS24702JB11'(!)        = ''              | ''                 | 'CS24702JB11'           |'R0402'| '(R0402-0201)'                 | '4.7K'    | '5%'    | '1/16W'  | 'IO'       | 'RES CHIP 4.7K 1/16W +-5% (0402)ES-PAL'            | 'CHIP0402'     | ''          | ''            | '20100715'
 '220K '      | '5%'      | '1/10W'  | '0603LF'  | 'CHIP'   | 'CS42203J900'(!)        = 'End of Design' | 'Comp-Approve'     | 'CS42203J900'           |'R0603'| '(SMR0603AW)'                  | '220K'    | '5%'    | '1/10W ' | 'DISCRETE' | 'RESISTOR CHIP 220K 1/10W +-5%(1608)'              | 'CHIP0603'     | ''          | ''            | '20100715'
 '220K '      | '5%'      | '1/10W'  | '0603LF'  | 'EMPTY'  | 'CS42203J900'(!)        = 'End of Design' | 'Comp-Approve'     | 'CS42203J900'           |'R0603'| '(SMR0603AW)'                  | '220K'    | '5%'    | '1/10W ' | 'IO'       | 'RESISTOR CHIP 220K 1/10W +-5%(1608)'              | 'CHIP0603'     | ''          | ''            | '20100715'
 '0    '      | '1%'      | '1/10W'  | '0603LF'  | 'CHIP'   | 'CS00003F916'(!)        = 'End of Design' | 'Comp-Approve'     | 'CS00003F916'           |'R0603'| '(SMR0603AW)'                  | '0'       | '1%'    | '1/10W ' | 'DISCRETE' | 'RES CHIP 0 1/10W +-1% (0603)'                     | 'CHIP0603'     | ''          | ''            | '20100715'
 '0    '      | '1%'      | '1/10W'  | '0603LF'  | 'EMPTY'  | 'CS00003F916'(!)        = 'End of Design' | 'Comp-Approve'     | 'CS00003F916'           |'R0603'| '(SMR0603AW)'                  | '0'       | '1%'    | '1/10W ' | 'IO'       | 'RES CHIP 0 1/10W +-1% (0603)'                     | 'CHIP0603'     | ''          | ''            | '20100715'
 '0'          | '5%'      | '1/10W'  | '0603LF'  | 'CHIP'   | 'CS00003J900'(!)        = 'End of Design' | 'Comp-Approve'     | 'CS00003J900'           |'R0603'| '(SMR0603AW)'                  | '0'       | '5%'    | '1/10W ' | 'DISCRETE' | 'RESISTOR CHIP 0 1/10W+-5%(0603)'                  | 'CHIP0603'     | ''          | ''            | '20100715'
 '0'          | '5%'      | '1/10W'  | '0603LF'  | 'EMPTY'  | 'CS00003J900'(!)        = 'End of Design' | 'Comp-Approve'     | 'CS00003J900'           |'R0603'| '(SMR0603AW)'                  | '0'       | '5%'    | '1/10W ' | 'IO'       | 'RESISTOR CHIP 0 1/10W+-5%(0603)'                  | 'CHIP0603'     | ''          | ''            | '20100715'
 '0.001'      | '1%'      | '2W   '  | '2512LF'  | 'CHIP'   | 'CS+001AF104'(!)        = ''              | 'End of Life'      | 'CS+001AF104'           |'R2512A_EOL'| '(SMR2512AW)'                  | '0.001'   | '1%'    | '2W    ' | 'DISCRETE' | 'RES CHIP 0.001 2W(+-1%,2512) L-F'                 | 'CHIP2512'     | ''          | ''            | '20100715'
 '0.001'      | '1%'      | '2W   '  | '2512LF'  | 'EMPTY'  | 'CS+001AF104'(!)        = ''              | 'End of Life'      | 'CS+001AF104'           |'R2512A_EOL'| '(SMR2512AW)'                  | '0.001'   | '1%'    | '2W    ' | 'IO'       | 'RES CHIP 0.001 2W(+-1%,2512) L-F'                 | 'CHIP2512'     | ''          | ''            | '20100715'
 '49.9'       | '1%'      | '1/16W'  | '0402LF'  | 'CHIP'   | 'CS04992FB31'(!)        = 'End of Design' | 'Comp-Approve'     | 'CS04992FB31'           |'R0402'| '(R0402-0201)'                 | '49.9'    | '1%'    | '1/16W ' | 'DISCRETE' | 'RES CHIP 49.9 1/16W +-1% (0402)'                  | 'CHIP0402'     | ''          | ''            | '20100716'
 '49.9'       | '1%'      | '1/16W'  | '0402LF'  | 'EMPTY'  | 'CS04992FB31'(!)        = 'End of Design' | 'Comp-Approve'     | 'CS04992FB31'           |'R0402'| '(R0402-0201)'                 | '49.9'    | '1%'    | '1/16W ' | 'IO'       | 'RES CHIP 49.9 1/16W +-1% (0402)'                  | 'CHIP0402'     | ''          | ''            | '20100716'
 '226      '  | '0.1%'    | '1/16W'  | '0402LF'  | 'CHIP'   | 'CS12262BB00'(!)        = ''              | ''                 | 'CS12262BB00'           |'R0402'| '(R0402-0201)'                 | '226'     | '0.1%'  | '1/16W ' | 'DISCRETE' | 'RES CHIP 226 1/16W 0.1% (0402)'                   | 'CHIP0402'     | ''          | ''            | '20100716'
 '226      '  | '0.1%'    | '1/16W'  | '0402LF'  | 'EMPTY'  | 'CS12262BB00'(!)        = ''              | ''                 | 'CS12262BB00'           |'R0402'| '(R0402-0201)'                 | '226'     | '0.1%'  | '1/16W ' | 'IO'       | 'RES CHIP 226 1/16W 0.1% (0402)'                   | 'CHIP0402'     | ''          | ''            | '20100716'
 '2.21K    '  | '1%  '    | '1/16W'  | '0402LF'  | 'CHIP'   | 'CS22212FB11'(!)        = 'End of Design' | 'Comp-Approve'     | 'CS22212FB11'           |'R0402'| '(R0402-0201)'                 | '2.21K'   | '1%  '  | '1/16W ' | 'DISCRETE' | 'RES CHIP 2.21K 1/16W +-1% (0402)'                 | 'CHIP0402'     | ''          | ''            | '20100716'
 '2.21K    '  | '1%  '    | '1/16W'  | '0402LF'  | 'EMPTY'  | 'CS22212FB11'(!)        = 'End of Design' | 'Comp-Approve'     | 'CS22212FB11'           |'R0402'| '(R0402-0201)'                 | '2.21K'   | '1%  '  | '1/16W ' | 'IO'       | 'RES CHIP 2.21K 1/16W +-1% (0402)'                 | 'CHIP0402'     | ''          | ''            | '20100716'
 '3K       '  | '1%  '    | '1/16W'  | '0402LF'  | 'CHIP'   | 'CS23002FB11'(!)        = 'End of Design' | 'Comp-Approve'     | 'CS23002FB11'           |'R0402'| '(R0402-0201)'                 | '3K'      | '1%  '  | '1/16W ' | 'DISCRETE' | 'RES CHIP 3K 1/16W +-1%(0402)'                     | 'CHIP0402'     | ''          | ''            | '20100716'
 '3K       '  | '1%  '    | '1/16W'  | '0402LF'  | 'EMPTY'  | 'CS23002FB11'(!)        = 'End of Design' | 'Comp-Approve'     | 'CS23002FB11'           |'R0402'| '(R0402-0201)'                 | '3K'      | '1%  '  | '1/16W ' | 'IO'       | 'RES CHIP 3K 1/16W +-1%(0402)'                     | 'CHIP0402'     | ''          | ''            | '20100716'
 '6.2K'       | '1%'      | '1/16W'  | '0402LF'  | 'CHIP'   | 'CS26202FB17'(!)        = 'End of Design' | 'Comp-Approve'     | 'CS26202FB17'           |'R0402'| '(R0402-0201)'                 | '6.2K'    | '1%'    | '1/16W'  | 'DISCRETE' | 'RES CHIP 6.2K 1/16W +-1%(0402)'                   | 'CHIP0402'     | ''          | ''            | '20100716'
 '6.2K'       | '1%'      | '1/16W'  | '0402LF'  | 'EMPTY'  | 'CS26202FB17'(!)        = 'End of Design' | 'Comp-Approve'     | 'CS26202FB17'           |'R0402'| '(R0402-0201)'                 | '6.2K'    | '1%'    | '1/16W'  | 'IO'       | 'RES CHIP 6.2K 1/16W +-1%(0402)'                   | 'CHIP0402'     | ''          | ''            | '20100716'
 '10K      '  | '0.1%'    | '1/16W'  | '0402LF'  | 'CHIP'   | 'CS31002BB02'(!)        = ''              | ''                 | 'CS31002BB02'           |'R0402'| '(R0402-0201)'                 | '10K'     | '0.1%'  | '1/16W'  | 'DISCRETE' | 'RES CHIP 10K 1/16W+-0.1%(0402)JET ASSIGN'         | 'CHIP0402'     | ''          | ''            | '20100716'
 '10K      '  | '0.1%'    | '1/16W'  | '0402LF'  | 'EMPTY'  | 'CS31002BB02'(!)        = ''              | ''                 | 'CS31002BB02'           |'R0402'| '(R0402-0201)'                 | '10K'     | '0.1%'  | '1/16W'  | 'IO'       | 'RES CHIP 10K 1/16W+-0.1%(0402)JET ASSIGN'         | 'CHIP0402'     | ''          | ''            | '20100716'
 '22K      '  | '5%  '    | '1/16W'  | '0402LF'  | 'CHIP'   | 'CS32202JB28'(!)        = 'End of Design' | 'Comp-Approve'     | 'CS32202JB28'           |'R0402'| '(R0402-0201)'                 | '22K'     | '5%'    | '1/16W'  | 'DISCRETE' | 'RES CHIP 22K 1/16W +-5% (0402)'                   | 'CHIP0402'     | ''          | ''            | '20100716'
 '22K      '  | '5%  '    | '1/16W'  | '0402LF'  | 'EMPTY'  | 'CS32202JB28'(!)        = 'End of Design' | 'Comp-Approve'     | 'CS32202JB28'           |'R0402'| '(R0402-0201)'                 | '22K'     | '5%'    | '1/16W'  | 'IO'       | 'RES CHIP 22K 1/16W +-5% (0402)'                   | 'CHIP0402'     | ''          | ''            | '20100716'
 '30.1K    '  | '1%  '    | '1/16W'  | '0402LF'  | 'CHIP'   | 'CS33012FB18'(!)        = 'End of Design' | 'Comp-Approve'     | 'CS33012FB18'           |'R0402'| '(R0402-0201)'                 | '30.1K'   | '1%  '  | '1/16W'  | 'DISCRETE' | 'RES CHIP 30.1K 1/16W +-1%(0402)'                  | 'CHIP0402'     | ''          | ''            | '20100716'
 '30.1K    '  | '1%  '    | '1/16W'  | '0402LF'  | 'EMPTY'  | 'CS33012FB18'(!)        = 'End of Design' | 'Comp-Approve'     | 'CS33012FB18'           |'R0402'| '(R0402-0201)'                 | '30.1K'   | '1%  '  | '1/16W'  | 'IO'       | 'RES CHIP 30.1K 1/16W +-1%(0402)'                  | 'CHIP0402'     | ''          | ''            | '20100716'
 '33K'        | '0.1%'    | '1/16W'  | '0402LF'  | 'CHIP'   | 'CS33302BB00'(!)        = ''              | ''                 | 'CS33302BB00'           |'R0402'| '(R0402-0201)'                 | '33K'     | '0.1%'  | '1/16W'  | 'DISCRETE' | 'RES CHIP 33K 1/16W 0.1% (0402)'                   | 'CHIP0402'     | ''          | ''            | '20100716'
 '33K'        | '0.1%'    | '1/16W'  | '0402LF'  | 'EMPTY'  | 'CS33302BB00'(!)        = ''              | ''                 | 'CS33302BB00'           |'R0402'| '(R0402-0201)'                 | '33K'     | '0.1%'  | '1/16W'  | 'IO'       | 'RES CHIP 33K 1/16W 0.1% (0402)'                   | 'CHIP0402'     | ''          | ''            | '20100716'
 '100      '  | '5%  '    | '1/10W'  | '0603LF'  | 'CHIP'   | 'CS11003J947'(!)        = ''              | ''                 | 'CS11003J947'           |'R0603'| '(SMR0603AW)'                  | '100'     | '5%'    | '1/10W'  | 'DISCRETE' | 'RESISTOR CHIP 100 1/10W +-5%(0603)EP'             | 'CHIP0603'     | ''          | ''            | '20100716'
 '100      '  | '5%  '    | '1/10W'  | '0603LF'  | 'EMPTY'  | 'CS11003J947'(!)        = ''              | ''                 | 'CS11003J947'           |'R0603'| '(SMR0603AW)'                  | '100'     | '5%'    | '1/10W'  | 'IO'       | 'RESISTOR CHIP 100 1/10W +-5%(0603)EP'             | 'CHIP0603'     | ''          | ''            | '20100716'
 '180      '  | '1%  '    | '1/10W'  | '0603LF'  | 'CHIP'   | 'CS11803F910'(!)        = 'End of Design' | 'Comp-Approve'     | 'CS11803F910'           |'R0603'| '(SMR0603AW)'                  | '180'     | '1%'    | '1/10W'  | 'DISCRETE' | 'RES CHIP 180 1/10W +-1%(0603)EP'                  | 'CHIP0603'     | ''          | ''            | '20100716'
 '180      '  | '1%  '    | '1/10W'  | '0603LF'  | 'EMPTY'  | 'CS11803F910'(!)        = 'End of Design' | 'Comp-Approve'     | 'CS11803F910'           |'R0603'| '(SMR0603AW)'                  | '180'     | '1%'    | '1/10W'  | 'IO'       | 'RES CHIP 180 1/10W +-1%(0603)EP'                  | 'CHIP0603'     | ''          | ''            | '20100716'
 '200      '  | '1%  '    | '1/10W'  | '0603LF'  | 'CHIP'   | 'CS12003F930'(!)        = ''              | ''                 | 'CS12003F930'           |'R0603'| '(SMR0603AW)'                  | '200'     | '1%'    | '1/10W'  | 'DISCRETE' | 'RES CHIP 200 1/10W 1% (0603)EP'                   | 'CHIP0603'     | ''          | ''            | '20100716'
 '200      '  | '1%  '    | '1/10W'  | '0603LF'  | 'EMPTY'  | 'CS12003F930'(!)        = ''              | ''                 | 'CS12003F930'           |'R0603'| '(SMR0603AW)'                  | '200'     | '1%'    | '1/10W'  | 'IO'       | 'RES CHIP 200 1/10W 1% (0603)EP'                   | 'CHIP0603'     | ''          | ''            | '20100716'
 '1K       '  | '5%  '    | '1/10W'  | '0603LF'  | 'CHIP'   | 'CS21003J949'(!)        = ''              | ''                 | 'CS21003J949'           |'R0603'| '(SMR0603AW)'                  | '1K'      | '5%'    | '1/10W'  | 'DISCRETE' | 'RES CHIP 1K 1/10W +-5%(0603)'                     | 'CHIP0603'     | ''          | ''            | '20100716'
 '1K       '  | '5%  '    | '1/10W'  | '0603LF'  | 'EMPTY'  | 'CS21003J949'(!)        = ''              | ''                 | 'CS21003J949'           |'R0603'| '(SMR0603AW)'                  | '1K'      | '5%'    | '1/10W'  | 'IO'       | 'RES CHIP 1K 1/10W +-5%(0603)'                     | 'CHIP0603'     | ''          | ''            | '20100716'
 '54.9      ' | '1%  '    | '1/10W'  | '0603LF'  | 'CHIP'   | 'CS05493F931'(!)        = ''              | ''                 | 'CS05493F931'           |'R0603'| '(SMR0603AW)'                  | '54.9'    | '1%'    | '1/10W'  | 'DISCRETE' | 'RES CHIP 54.9 1/10W +-1%(0603)'                   | 'CHIP0603'     | ''          | ''            | '20100718'
 '54.9      ' | '1%  '    | '1/10W'  | '0603LF'  | 'EMPTY'  | 'CS05493F931'(!)        = ''              | ''                 | 'CS05493F931'           |'R0603'| '(SMR0603AW)'                  | '54.9'    | '1%'    | '1/10W'  | 'IO'       | 'RES CHIP 54.9 1/10W +-1%(0603)'                   | 'CHIP0603'     | ''          | ''            | '20100718'
 '2.15K     ' | '1%  '    | '1/10W'  | '0603LF'  | 'CHIP'   | 'CS22153F920'(!)        = ''              | ''                 | 'CS22153F920'           |'R0603'| '(SMR0603AW)'                  | '2.15K'   | '1%'    | '1/10W'  | 'DISCRETE' | 'RES CHIP 2.15K 1/10W +-1%(0603)'                  | 'CHIP0603'     | ''          | ''            | '20100718'
 '2.15K     ' | '1%  '    | '1/10W'  | '0603LF'  | 'EMPTY'  | 'CS22153F920'(!)        = ''              | ''                 | 'CS22153F920'           |'R0603'| '(SMR0603AW)'                  | '2.15K'   | '1%'    | '1/10W'  | 'IO'       | 'RES CHIP 2.15K 1/10W +-1%(0603)'                  | 'CHIP0603'     | ''          | ''            | '20100718'
 '3.4K      ' | '1%  '    | '1/10W'  | '0603LF'  | 'CHIP'   | 'CS23403F912'(!)        = ''              | ''                 | 'CS23403F912'           |'R0603'| '(SMR0603AW)'                  | '3.4K'    | '1%'    | '1/10W'  | 'DISCRETE' | 'RESISTOR CHIP 3.4K 1/10W+-1%(0603)'               | 'CHIP0603'     | ''          | ''            | '20100718'
 '3.4K      ' | '1%  '    | '1/10W'  | '0603LF'  | 'EMPTY'  | 'CS23403F912'(!)        = ''              | ''                 | 'CS23403F912'           |'R0603'| '(SMR0603AW)'                  | '3.4K'    | '1%'    | '1/10W'  | 'IO'       | 'RESISTOR CHIP 3.4K 1/10W+-1%(0603)'               | 'CHIP0603'     | ''          | ''            | '20100718'
 '10K       ' | '1%  '    | '1/10W'  | '0603LF'  | 'CHIP'   | 'CS31003F949'(!)        = ''              | ''                 | 'CS31003F949'           |'R0603'| '(SMR0603AW)'                  | '10K'     | '1%'    | '1/10W'  | 'DISCRETE' | 'RESISTOR CHIP 10K 1/10W+-1%(0603)'                | 'CHIP0603'     | ''          | ''            | '20100718'
 '10K       ' | '1%  '    | '1/10W'  | '0603LF'  | 'EMPTY'  | 'CS31003F949'(!)        = ''              | ''                 | 'CS31003F949'           |'R0603'| '(SMR0603AW)'                  | '10K'     | '1%'    | '1/10W'  | 'IO'       | 'RESISTOR CHIP 10K 1/10W+-1%(0603)'                | 'CHIP0603'     | ''          | ''            | '20100718'
 '511      '  | '1%  '    | '1/16W'  | '0402LF'  | 'CHIP'   | 'CS15112FB13'(!)        = 'End of Design' | 'Comp-Approve'     | 'CS15112FB13'           |'R0402'| '(R0402-0201)'                 | '511'     | '1%'    | '1/16W'  | 'DISCRETE' | 'RES CHIP 511 1/16W +-1%(0402)'                    | 'CHIP0402'     | ''          | ''            | '20100720'
 '511      '  | '1%  '    | '1/16W'  | '0402LF'  | 'EMPTY'  | 'CS15112FB13'(!)        = 'End of Design' | 'Comp-Approve'     | 'CS15112FB13'           |'R0402'| '(R0402-0201)'                 | '511'     | '1%'    | '1/16W'  | 'IO'       | 'RES CHIP 511 1/16W +-1%(0402)'                    | 'CHIP0402'     | ''          | ''            | '20100720'
 '604      '  | '1%  '    | '1/16W'  | '0402LF'  | 'CHIP'   | 'CS16042FB24'(!)        = 'End of Design' | 'Comp-Approve'     | 'CS16042FB24'           |'R0402'| '(R0402-0201)'                 | '604'     | '1%'    | '1/16W'  | 'DISCRETE' | 'RES CHIP 604 1/16W +-1%(0402)'                    | 'CHIP0402'     | ''          | ''            | '20100720'
 '604      '  | '1%  '    | '1/16W'  | '0402LF'  | 'EMPTY'  | 'CS16042FB24'(!)        = 'End of Design' | 'Comp-Approve'     | 'CS16042FB24'           |'R0402'| '(R0402-0201)'                 | '604'     | '1%'    | '1/16W'  | 'IO'       | 'RES CHIP 604 1/16W +-1%(0402)'                    | 'CHIP0402'     | ''          | ''            | '20100720'
 '13.7K    '  | '1%  '    | '1/16W'  | '0402LF'  | 'CHIP'   | 'CS31372FB11'(!)        = 'End of Design' | 'Comp-Approve'     | 'CS31372FB11'           |'R0402'| '(R0402-0201)'                 | '13.7K'   | '1%'    | '1/16W'  | 'DISCRETE' | 'RES CHIP 13.7K 1/16W +-1%(0402)'                  | 'CHIP0402'     | ''          | ''            | '20100720'
 '13.7K    '  | '1%  '    | '1/16W'  | '0402LF'  | 'EMPTY'  | 'CS31372FB11'(!)        = 'End of Design' | 'Comp-Approve'     | 'CS31372FB11'           |'R0402'| '(R0402-0201)'                 | '13.7K'   | '1%'    | '1/16W'  | 'IO'       | 'RES CHIP 13.7K 1/16W +-1%(0402)'                  | 'CHIP0402'     | ''          | ''            | '20100720'
 '18.7K    '  | '1%  '    | '1/16W'  | '0402LF'  | 'CHIP'   | 'CS31872FB19'(!)        = 'End of Design' | 'Comp-Approve'     | 'CS31872FB19'           |'R0402'| '(R0402-0201)'                 | '18.7k'   | '1%'    | '1/16W'  | 'DISCRETE' | 'RES CHIP 18.7K 1/16W +-1%(0402)'                  | 'CHIP0402'     | ''          | ''            | '20100720'
 '18.7K    '  | '1%  '    | '1/16W'  | '0402LF'  | 'EMPTY'  | 'CS31872FB19'(!)        = 'End of Design' | 'Comp-Approve'     | 'CS31872FB19'           |'R0402'| '(R0402-0201)'                 | '18.7k'   | '1%'    | '1/16W'  | 'IO'       | 'RES CHIP 18.7K 1/16W +-1%(0402)'                  | 'CHIP0402'     | ''          | ''            | '20100720'
 '2.21K    '  | '0.5%  '  | '1/10W'  | '0603LF'  | 'CHIP'   | 'CS22213D906'(!)        = ''              | ''                 | 'CS22213D906'           |'R0603'| '(SMR0603AW)'                  | '2.21K'   | '0.5%'  | '1/10W'  | 'DISCRETE' | 'RESISTOR CHIP 2.21K 1/10W+-0.5%(0603)L-F'         | 'CHIP0603'     | ''          | ''            | '20100727'
 '2.21K    '  | '0.5%  '  | '1/10W'  | '0603LF'  | 'EMPTY'  | 'CS22213D906'(!)        = ''              | ''                 | 'CS22213D906'           |'R0603'| '(SMR0603AW)'                  | '2.21K'   | '0.5%'  | '1/10W'  | 'IO'       | 'RESISTOR CHIP 2.21K 1/10W+-0.5%(0603)L-F'         | 'CHIP0603'     | ''          | ''            | '20100727'
 '33K    '    | '1%  '    | '1/16W'  | '0402LF'  | 'CHIP'   | 'CS33302FB14'(!)        = 'End of Design' | 'Comp-Approve'     | 'CS33302FB14'           |'R0402'| '(R0402-0201)'                 | '33K'     | '1%'    | '1/16W'  | 'DISCRETE' | 'RES CHIP 33K 1/16W +-1%(0402)'                    | 'CHIP0402'     | ''          | ''            | '20100802'
 '33K    '    | '1%  '    | '1/16W'  | '0402LF'  | 'EMPTY'  | 'CS33302FB14'(!)        = 'End of Design' | 'Comp-Approve'     | 'CS33302FB14'           |'R0402'| '(R0402-0201)'                 | '33K'     | '1%'    | '1/16W'  | 'IO'       | 'RES CHIP 33K 1/16W +-1%(0402)'                    | 'CHIP0402'     | ''          | ''            | '20100802'
 '22'         | '5%'      | '1/16W'  | '0402LF'  | 'CHIP'   | 'CS02202JB22'(!)        = 'End of Design' | 'Comp-Approve'     | 'CS02202JB22'           |'R0402'| '(R0402-0201)'                 | '22'      | '5%'    | '1/16W'  | 'DISCRETE' | 'RES CHIP 22 1/16W 5%(0402)'                       | 'CHIP0402'     | ''          | ''            | '20100811'
 '22'         | '5%'      | '1/16W'  | '0402LF'  | 'EMPTY'  | 'CS02202JB22'(!)        = 'End of Design' | 'Comp-Approve'     | 'CS02202JB22'           |'R0402'| '(R0402-0201)'                 | '22'      | '5%'    | '1/16W'  | 'IO'       | 'RES CHIP 22 1/16W 5%(0402)'                       | 'CHIP0402'     | ''          | ''            | '20100811'
 '22.1     '  | '1%  '    | '1/16W'  | '0402LF'  | 'CHIP'   | 'CS02212FB09'(!)        = 'End of Design' | 'Comp-Approve'     | 'CS02212FB09'           |'R0402'| '(R0402-0201)'                 | '22.1'    | '1%'    | '1/16W'  | 'DISCRETE' | 'RES CHIP 22.1 1/16W +-1%(0402) L-F'               | 'CHIP0402'     | ''          | ''            | '20100811'
 '22.1     '  | '1%  '    | '1/16W'  | '0402LF'  | 'EMPTY'  | 'CS02212FB09'(!)        = 'End of Design' | 'Comp-Approve'     | 'CS02212FB09'           |'R0402'| '(R0402-0201)'                 | '22.1'    | '1%'    | '1/16W'  | 'IO'       | 'RES CHIP 22.1 1/16W +-1%(0402) L-F'               | 'CHIP0402'     | ''          | ''            | '20100811'
 '33       '  | '1%  '    | '1/16W'  | '0402LF'  | 'CHIP'   | 'CS03302FB19'(!)        = 'End of Design' | 'Comp-Approve'     | 'CS03302FB19'           |'R0402'| '(R0402-0201)'                 | '33'      | '1%'    | '1/16W'  | 'DISCRETE' | 'RES CHIP 33 1/16W +-1%(0402)'                     | 'CHIP0402'     | ''          | ''            | '20100811'
 '33       '  | '1%  '    | '1/16W'  | '0402LF'  | 'EMPTY'  | 'CS03302FB19'(!)        = 'End of Design' | 'Comp-Approve'     | 'CS03302FB19'           |'R0402'| '(R0402-0201)'                 | '33'      | '1%'    | '1/16W'  | 'IO'       | 'RES CHIP 33 1/16W +-1%(0402)'                     | 'CHIP0402'     | ''          | ''            | '20100811'
 '75'         | '1%'      | '1/16W'  | '0402LF'  | 'CHIP'   | 'CS07502FB17'(!)        = 'End of Design' | 'Comp-Approve'     | 'CS07502FB17'           |'R0402'| '(R0402-0201)'                 | '75'      | '1%'    | '1/16W'  | 'DISCRETE' | 'RES CHIP 75 1/16W +-1% (0402)'                    | 'CHIP0402'     | ''          | ''            | '20100811'
 '75'         | '1%'      | '1/16W'  | '0402LF'  | 'EMPTY'  | 'CS07502FB17'(!)        = 'End of Design' | 'Comp-Approve'     | 'CS07502FB17'           |'R0402'| '(R0402-0201)'                 | '75'      | '1%'    | '1/16W'  | 'IO'       | 'RES CHIP 75 1/16W +-1% (0402)'                    | 'CHIP0402'     | ''          | ''            | '20100811'
 '2.7K     '  | '5%  '    | '1/16W'  | '0402LF'  | 'CHIP'   | 'CS22702JB16'(!)        = 'End of Design' | 'Comp-Approve'     | 'CS22702JB16'           |'R0402'| '(R0402-0201)'                 | '2.7K'    | '5%'    | '1/16W'  | 'DISCRETE' | 'RES CHIP 2.7K 1/16W +-5%(0402)'                   | 'CHIP0402'     | ''          | ''            | '20100811'
 '2.7K     '  | '5%  '    | '1/16W'  | '0402LF'  | 'EMPTY'  | 'CS22702JB16'(!)        = 'End of Design' | 'Comp-Approve'     | 'CS22702JB16'           |'R0402'| '(R0402-0201)'                 | '2.7K'    | '5%'    | '1/16W'  | 'IO'       | 'RES CHIP 2.7K 1/16W +-5%(0402)'                   | 'CHIP0402'     | ''          | ''            | '20100811'
 '8.2K     '  | '5%  '    | '1/16W'  | '0402LF'  | 'CHIP'   | 'CS28202JB14'(!)        = 'End of Design' | 'Comp-Approve'     | 'CS28202JB14'           |'R0402'| '(R0402-0201)'                 | '8.2K'    | '5%'    | '1/16W'  | 'DISCRETE' | 'RES CHIP 8.2K 1/16W +-5% (0402)'                  | 'CHIP0402'     | ''          | ''            | '20100811'
 '8.2K     '  | '5%  '    | '1/16W'  | '0402LF'  | 'EMPTY'  | 'CS28202JB14'(!)        = 'End of Design' | 'Comp-Approve'     | 'CS28202JB14'           |'R0402'| '(R0402-0201)'                 | '8.2K'    | '5%'    | '1/16W'  | 'IO'       | 'RES CHIP 8.2K 1/16W +-5% (0402)'                  | 'CHIP0402'     | ''          | ''            | '20100811'
 '270K     '  | '5%  '    | '1/16W'  | '0402LF'  | 'CHIP'   | 'CS42702JB10'(!)        = 'End of Design' | 'Comp-Approve'     | 'CS42702JB10'           |'R0402'| '(R0402-0201)'                 | '270K'    | '5%'    | '1/16W'  | 'DISCRETE' | 'RES CHIP 270K(1/16W,+-5%,0402)'                   | 'CHIP0402'     | ''          | ''            | '20100811'
 '270K     '  | '5%  '    | '1/16W'  | '0402LF'  | 'EMPTY'  | 'CS42702JB10'(!)        = 'End of Design' | 'Comp-Approve'     | 'CS42702JB10'           |'R0402'| '(R0402-0201)'                 | '270K'    | '5%'    | '1/16W'  | 'IO'       | 'RES CHIP 270K(1/16W,+-5%,0402)'                   | 'CHIP0402'     | ''          | ''            | '20100811'
 '1.21K    '  | '1%  '    | '1/10W'  | '0603LF'  | 'CHIP'   | 'CS21213F914'(!)        = 'End of Design' | 'Comp-Approve'     | 'CS21213F914'           |'R0603'| '(SMR0603AW)'                  | '1.21K'   | '1%'    | '1/10W'  | 'DISCRETE' | 'RES CHIP 1.21K 1/10W +-1% (0603) EP'              | 'CHIP0603'     | ''          | ''            | '20100811'
 '1.21K    '  | '1%  '    | '1/10W'  | '0603LF'  | 'EMPTY'  | 'CS21213F914'(!)        = 'End of Design' | 'Comp-Approve'     | 'CS21213F914'           |'R0603'| '(SMR0603AW)'                  | '1.21K'   | '1%'    | '1/10W'  | 'IO'       | 'RES CHIP 1.21K 1/10W +-1% (0603) EP'              | 'CHIP0603'     | ''          | ''            | '20100811'
 '1.5K'       | '1%'      | '1/10W'  | '0603LF'  | 'CHIP'   | 'CS21503F911'(!)        = ''              | ''                 | 'CS21503F911'           |'R0603'| '(SMR0603AW)'                  | '1.5K'    | '1%'    | '1/10W ' | 'DISCRETE' | 'RESISTOR CHIP 1.5K 1/10W +-1%(1608)'              | 'CHIP0603'     | ''          | ''            | '20100811'
 '1.5K'       | '1%'      | '1/10W'  | '0603LF'  | 'EMPTY'  | 'CS21503F911'(!)        = ''              | ''                 | 'CS21503F911'           |'R0603'| '(SMR0603AW)'                  | '1.5K'    | '1%'    | '1/10W ' | 'IO'       | 'RESISTOR CHIP 1.5K 1/10W +-1%(1608)'              | 'CHIP0603'     | ''          | ''            | '20100811'
 '2.1K'       | '1%'      | '1/10W'  | '0603LF'  | 'CHIP'   | 'CS22103F901'(!)        = ''              | ''                 | 'CS22103F901'           |'R0603'| '(SMR0603AW)'                  | '2.1K'    | '1%'    | '1/10W ' | 'DISCRETE' | 'RES CHIP 2.1K 1/10W +-1% (0603)'                  | 'CHIP0603'     | ''          | ''            | '20100811'
 '2.1K'       | '1%'      | '1/10W'  | '0603LF'  | 'EMPTY'  | 'CS22103F901'(!)        = ''              | ''                 | 'CS22103F901'           |'R0603'| '(SMR0603AW)'                  | '2.1K'    | '1%'    | '1/10W ' | 'IO'       | 'RES CHIP 2.1K 1/10W +-1% (0603)'                  | 'CHIP0603'     | ''          | ''            | '20100811'
 '44.2'       | '1%'      | '1/10W'  | '0603LF'  | 'CHIP'   | 'CS04423F911'(!)        = ''              | ''                 | 'CS04423F911'           |'R0603'| '(SMR0603AW)'                  | '44.2'    | '1%'    | '1/10W ' | 'DISCRETE' | 'RES CHIP 44.2 1/10W +-1%(0603)L-F'                | 'CHIP0603'     | ''          | ''            | '20100811'
 '44.2'       | '1%'      | '1/10W'  | '0603LF'  | 'EMPTY'  | 'CS04423F911'(!)        = ''              | ''                 | 'CS04423F911'           |'R0603'| '(SMR0603AW)'                  | '44.2'    | '1%'    | '1/10W ' | 'IO'       | 'RES CHIP 44.2 1/10W +-1%(0603)L-F'                | 'CHIP0603'     | ''          | ''            | '20100811'
 '1.1K'       | '1%'      | '1/10W'  | '0603LF'  | 'CHIP'   | 'CS21103F916'(!)        = ''              | ''                 | 'CS21103F916'           |'R0603'| '(SMR0603AW)'                  | '1.1K'    | '1%'    | '1/10W ' | 'DISCRETE' | 'RES CHIP 1.1K 1/10W +-1%(0603)'                   | 'CHIP0603'     | ''          | ''            | '20100811'
 '1.1K'       | '1%'      | '1/10W'  | '0603LF'  | 'EMPTY'  | 'CS21103F916'(!)        = ''              | ''                 | 'CS21103F916'           |'R0603'| '(SMR0603AW)'                  | '1.1K'    | '1%'    | '1/10W ' | 'IO'       | 'RES CHIP 1.1K 1/10W +-1%(0603)'                   | 'CHIP0603'     | ''          | ''            | '20100811'
 '240'        | '5%'      | '1/16W'  | '0402LF'  | 'CHIP'   | 'CS12402JB13'(!)        = 'End of Design' | 'Comp-Approve'     | 'CS12402JB13'           |'R0402'| '(R0402-0201)'                 | '240'     | '5%'    | '1/16W'  | 'DISCRETE' | 'RES CHIP 240 1/16W +-5%(0402)'                    | 'CHIP0402'     | ''          | ''            | '20100817'
 '240'        | '5%'      | '1/16W'  | '0402LF'  | 'EMPTY'  | 'CS12402JB13'(!)        = 'End of Design' | 'Comp-Approve'     | 'CS12402JB13'           |'R0402'| '(R0402-0201)'                 | '240'     | '5%'    | '1/16W'  | 'IO'       | 'RES CHIP 240 1/16W +-5%(0402)'                    | 'CHIP0402'     | ''          | ''            | '20100817'
 '240'        | '1%'      | '1/16W'  | '0402LF'  | 'CHIP'   | 'CS12402FB03'(!)        = 'End of Design' | 'Comp-Release Qty' | 'CS12402FB03'           |'R0402'| '(R0402-0201)'                 | '240'     | '1%'    | '1/16W'  | 'DISCRETE' | 'RES CHIP 240 1/16W +-1%(0402)'                    | 'CHIP0402'     | ''          | ''            | '20100827'
 '240'        | '1%'      | '1/16W'  | '0402LF'  | 'EMPTY'  | 'CS12402FB03'(!)        = 'End of Design' | 'Comp-Release Qty' | 'CS12402FB03'           |'R0402'| '(R0402-0201)'                 | '240'     | '1%'    | '1/16W'  | 'IO'       | 'RES CHIP 240 1/16W +-1%(0402)'                    | 'CHIP0402'     | ''          | ''            | '20100827'
 '5.1'        | '5%'      | '1/16W'  | '0402LF'  | 'CHIP'   | 'CS-5102JB03'(!)        = 'End of Design' | 'Comp-Approve'     | 'CS-5102JB03'           |'R0402'| '(R0402-0201)'                 | '5.1'     | '5%'    | '1/16W ' | 'DISCRETE' | 'RES CHIP 5.1 1/16W +-5%(0402)'                    | 'CHIP0402'     | ''          | ''            | '20100827'
 '5.1'        | '5%'      | '1/16W'  | '0402LF'  | 'EMPTY'  | 'CS-5102JB03'(!)        = 'End of Design' | 'Comp-Approve'     | 'CS-5102JB03'           |'R0402'| '(R0402-0201)'                 | '5.1'     | '5%'    | '1/16W ' | 'IO'       | 'RES CHIP 5.1 1/16W +-5%(0402)'                    | 'CHIP0402'     | ''          | ''            | '20100827'
 '82'         | '5%'      | '1/16W'  | '0402LF'  | 'CHIP'   | 'CS08202JB11'(!)        = 'End of Design' | 'Comp-Approve'     | 'CS08202JB11'           |'R0402'| '(R0402-0201)'                 | '82'      | '5%'    | '1/16W'  | 'DISCRETE' | 'RES CHIP 82 1/16W +-5% (0402)'                    | 'CHIP0402'     | ''          | ''            | '20100827'
 '82'         | '5%'      | '1/16W'  | '0402LF'  | 'EMPTY'  | 'CS08202JB11'(!)        = 'End of Design' | 'Comp-Approve'     | 'CS08202JB11'           |'R0402'| '(R0402-0201)'                 | '82'      | '5%'    | '1/16W'  | 'IO'       | 'RES CHIP 82 1/16W +-5% (0402)'                    | 'CHIP0402'     | ''          | ''            | '20100827'
 '36'         | '5%'      | '1/16W'  | '0402LF'  | 'CHIP'   | 'CS03602JB01'(!)        = 'End of Design' | 'End of Life'      | 'CS03602JB01'           |'R0402_EOL'| '(R0402-0201)'                 | '82'      | '5%'    | '1/16W'  | 'DISCRETE' | 'RES CHIP 36 1/16W +-5%(0402)'                     | 'CHIP0402'     | ''          | ''            | '20100827'
 '36'         | '5%'      | '1/16W'  | '0402LF'  | 'EMPTY'  | 'CS03602JB01'(!)        = 'End of Design' | 'End of Life'      | 'CS03602JB01'           |'R0402_EOL'| '(R0402-0201)'                 | '82'      | '5%'    | '1/16W'  | 'IO'       | 'RES CHIP 36 1/16W +-5%(0402)'                     | 'CHIP0402'     | ''          | ''            | '20100827'
 '37.4'       | '1%'      | '1/16W'  | '0402LF'  | 'CHIP'   | 'CS03742FB11'(!)        = 'End of Design' | 'Comp-Approve'     | 'CS03742FB11'           |'R0402'| '(R0402-0201)'                 | '37.4'    | '1%  '  | '1/16W'  | 'DISCRETE' | 'RES CHIP 37.4 1/16W +-1%(0402)'                   | 'CHIP0402'     | ''          | ''            | '20100831'
 '37.4'       | '1%'      | '1/16W'  | '0402LF'  | 'EMPTY'  | 'CS03742FB11'(!)        = 'End of Design' | 'Comp-Approve'     | 'CS03742FB11'           |'R0402'| '(R0402-0201)'                 | '37.4'    | '1%  '  | '1/16W'  | 'IO'       | 'RES CHIP 37.4 1/16W +-1%(0402)'                   | 'CHIP0402'     | ''          | ''            | '20100831'
 '200'        | '1%'      | '1/16W'  | '0402LF'  | 'CHIP'   | 'CS12002FB25'(!)        = 'End of Design' | 'Comp-Approve'     | 'CS12002FB25'           |'R0402'| '(R0402-0201)'                 | '200'     | '1%'    | '1/16W'  | 'DISCRETE' | 'RES CHIP 200 1/16W +-1%(0402)'                    | 'CHIP0402'     | ''          | ''            | '20100831'
 '200'        | '1%'      | '1/16W'  | '0402LF'  | 'EMPTY'  | 'CS12002FB25'(!)        = 'End of Design' | 'Comp-Approve'     | 'CS12002FB25'           |'R0402'| '(R0402-0201)'                 | '200'     | '1%'    | '1/16W'  | 'IO'       | 'RES CHIP 200 1/16W +-1%(0402)'                    | 'CHIP0402'     | ''          | ''            | '20100831'
 '26.1 '      | '1%'      | '1/16W'  | '0402LF'  | 'CHIP'   | 'CS02612FB00'(!)        = 'End of Design' | 'Comp-Approve'     | 'CS02612FB00'           |'R0402'| '(R0402-0201)'                 | '26.1'    | '1%'    | '1/16W ' | 'DISCRETE' | 'RES CHIP 26.1 1/16W +-1%(0402)'                   | 'CHIP0402'     | ''          | ''            | '20100831'
 '26.1 '      | '1%'      | '1/16W'  | '0402LF'  | 'EMPTY'  | 'CS02612FB00'(!)        = 'End of Design' | 'Comp-Approve'     | 'CS02612FB00'           |'R0402'| '(R0402-0201)'                 | '26.1'    | '1%'    | '1/16W ' | 'IO'       | 'RES CHIP 26.1 1/16W +-1%(0402)'                   | 'CHIP0402'     | ''          | ''            | '20100831'
 '20'         | '5%'      | '1/16W'  | '0402LF'  | 'CHIP'   | 'CS02002JB17'(!)        = 'End of Design' | 'Comp-Approve'     | 'CS02002JB17'           |'R0402'| '(R0402-0201)'                 | '20'      | '5%'    | '1/16W'  | 'DISCRETE' | 'RES CHIP 20 1/16W +-5% (0402)'                    | 'CHIP0402'     | ''          | ''            | '20100831'
 '20'         | '5%'      | '1/16W'  | '0402LF'  | 'EMPTY'  | 'CS02002JB17'(!)        = 'End of Design' | 'Comp-Approve'     | 'CS02002JB17'           |'R0402'| '(R0402-0201)'                 | '20'      | '5%'    | '1/16W'  | 'IO'       | 'RES CHIP 20 1/16W +-5% (0402)'                    | 'CHIP0402'     | ''          | ''            | '20100831'
 '75'         | '5%'      | '1/16W'  | '0402LF'  | 'CHIP'   | 'CS07502JB27'(!)        = 'End of Design' | 'Comp-Approve'     | 'CS07502JB27'           |'R0402'| '(R0402-0201)'                 | '75'      | '5%'    | '1/16W'  | 'DISCRETE' | 'RES CHIP 75 1/16W +-5% (0402)'                    | 'CHIP0402'     | ''          | ''            | '20100831'
 '75'         | '5%'      | '1/16W'  | '0402LF'  | 'EMPTY'  | 'CS07502JB27'(!)        = 'End of Design' | 'Comp-Approve'     | 'CS07502JB27'           |'R0402'| '(R0402-0201)'                 | '75'      | '5%'    | '1/16W'  | 'IO'       | 'RES CHIP 75 1/16W +-5% (0402)'                    | 'CHIP0402'     | ''          | ''            | '20100831'
 '1.2K '      | '5%'      | '1/16W'  | '0402LF'  | 'CHIP'   | 'CS21202JB15'(!)        = 'End of Design' | 'Comp-Approve'     | 'CS21202JB15'           |'R0402'| '(R0402-0201)'                 | '1.2K'    | '5%'    | '1/16W'  | 'DISCRETE' | 'RES CHIP 1.2K 1/16W +-5% (0402)'                  | 'CHIP0402'     | ''          | ''            | '20100831'
 '1.2K '      | '5%'      | '1/16W'  | '0402LF'  | 'EMPTY'  | 'CS21202JB15'(!)        = 'End of Design' | 'Comp-Approve'     | 'CS21202JB15'           |'R0402'| '(R0402-0201)'                 | '1.2K'    | '5%'    | '1/16W'  | 'IO'       | 'RES CHIP 1.2K 1/16W +-5% (0402)'                  | 'CHIP0402'     | ''          | ''            | '20100831'
 '1.54K'      | '1%'      | '1/10W'  | '0603LF'  | 'CHIP'   | 'CS21543F927'(!)        = ''              | ''                 | 'CS21543F927'           |'R0603'| '(SMR0603AW)'                  | '1.54K'   | '5%'    | '1/10W'  | 'DISCRETE' | 'RESISTOR CHIP 1.54K 1/10W+-1%(0603)'              | 'CHIP0603'     | ''          | ''            | '20100831'
 '1.54K'      | '1%'      | '1/10W'  | '0603LF'  | 'EMPTY'  | 'CS21543F927'(!)        = ''              | ''                 | 'CS21543F927'           |'R0603'| '(SMR0603AW)'                  | '1.54K'   | '5%'    | '1/10W'  | 'IO'       | 'RESISTOR CHIP 1.54K 1/10W+-1%(0603)'              | 'CHIP0603'     | ''          | ''            | '20100831'
 '294'        | '1%'      | '1/16W'  | '0402LF'  | 'CHIP'   | 'CS12942FB00'(!)        = 'End of Design' | 'Comp-Approve'     | 'CS12942FB00'           |'R0402'| '(R0402-0201)'                 | '294'     | '1%'    | '1/16W'  | 'DISCRETE' | 'RES CHIP 294 1/16W +-1%(0402)'                    | 'CHIP0402'     | ''          | ''            | '20100909'
 '294'        | '1%'      | '1/16W'  | '0402LF'  | 'EMPTY'  | 'CS12942FB00'(!)        = 'End of Design' | 'Comp-Approve'     | 'CS12942FB00'           |'R0402'| '(R0402-0201)'                 | '294'     | '1%'    | '1/16W'  | 'IO'       | 'RES CHIP 294 1/16W +-1%(0402)'                    | 'CHIP0402'     | ''          | ''            | '20100909'
 '180'        | '1%'      | '1/16W'  | '0402LF'  | 'CHIP'   | 'CS11802FB05'(!)        = 'End of Design' | 'Comp-Approve'     | 'CS11802FB05'           |'R0402'| '(R0402-0201)'                 | '180'     | '1%'    | '1/16W'  | 'DISCRETE' | 'RES CHIP 180 1/16W +-1% (0402)'                   | 'CHIP0402'     | ''          | ''            | '20100913'
 '180'        | '1%'      | '1/16W'  | '0402LF'  | 'EMPTY'  | 'CS11802FB05'(!)        = 'End of Design' | 'Comp-Approve'     | 'CS11802FB05'           |'R0402'| '(R0402-0201)'                 | '180'     | '1%'    | '1/16W'  | 'IO'       | 'RES CHIP 180 1/16W +-1% (0402)'                   | 'CHIP0402'     | ''          | ''            | '20100913'
 '2.67K'      | '1%'      | '1/16W'  | '0402LF'  | 'CHIP'   | 'CS22672FB12'(!)        = 'End of Design' | 'Comp-Approve'     | 'CS22672FB12'           |'R0402'| '(R0402-0201)'                 | '2.67K'   | '1%'    | '1/16W'  | 'DISCRETE' | 'RES CHIP 2.67K 1/16W +-1%(0402)'                  | 'CHIP0402'     | ''          | ''            | '20100919'
 '2.67K'      | '1%'      | '1/16W'  | '0402LF'  | 'EMPTY'  | 'CS22672FB12'(!)        = 'End of Design' | 'Comp-Approve'     | 'CS22672FB12'           |'R0402'| '(R0402-0201)'                 | '2.67K'   | '1%'    | '1/16W'  | 'IO'       | 'RES CHIP 2.67K 1/16W +-1%(0402)'                  | 'CHIP0402'     | ''          | ''            | '20100919'
 '294K'       | '1%'      | '1/16W'  | '0402LF'  | 'CHIP'   | 'CS42942FB13'(!)        = 'End of Design' | 'Comp-Approve'     | 'CS42942FB13'           |'R0402'| '(R0402-0201)'                 | '294K'    | '1%'    | '1/16W'  | 'DISCRETE' | 'RES CHIP 294K 1/16W +-1%(0402)'                   | 'CHIP0402'     | ''          | ''            | '20100919'
 '294K'       | '1%'      | '1/16W'  | '0402LF'  | 'EMPTY'  | 'CS42942FB13'(!)        = 'End of Design' | 'Comp-Approve'     | 'CS42942FB13'           |'R0402'| '(R0402-0201)'                 | '294K'    | '1%'    | '1/16W'  | 'IO'       | 'RES CHIP 294K 1/16W +-1%(0402)'                   | 'CHIP0402'     | ''          | ''            | '20100919'
 '27.4'       | '1%'      | '1/16W'  | '0402LF'  | 'CHIP'   | 'CS02742FB19'(!)        = 'End of Design' | 'Comp-Release Qty' | 'CS02742FB19'           |'R0402'| '(R0402-0201)'                 | '27.4'    | '1%'    | '1/16W'  | 'DISCRETE' | 'RES CHIP 27.4 1/16W +-1%(0402)'                   | 'CHIP0402'     | ''          | ''            | '20100923'
 '27.4'       | '1%'      | '1/16W'  | '0402LF'  | 'EMPTY'  | 'CS02742FB19'(!)        = 'End of Design' | 'Comp-Release Qty' | 'CS02742FB19'           |'R0402'| '(R0402-0201)'                 | '27.4'    | '1%'    | '1/16W'  | 'IO'       | 'RES CHIP 27.4 1/16W +-1%(0402)'                   | 'CHIP0402'     | ''          | ''            | '20100923'
 '39'         | '5%'      | '1/16W'  | '0402LF'  | 'CHIP'   | 'CS03902JB21'(!)        = 'End of Design' | 'Comp-Approve'     | 'CS03902JB21'           |'R0402'| '(R0402-0201)'                 | '39'      | '5%'    | '1/16W'  | 'DISCRETE' | 'RES CHIP 39 1/16W +-5%(0402)'                     | 'CHIP0402'     | ''          | ''            | '20100923'
 '39'         | '5%'      | '1/16W'  | '0402LF'  | 'EMPTY'  | 'CS03902JB21'(!)        = 'End of Design' | 'Comp-Approve'     | 'CS03902JB21'           |'R0402'| '(R0402-0201)'                 | '39'      | '5%'    | '1/16W'  | 'IO'       | 'RES CHIP 39 1/16W +-5%(0402)'                     | 'CHIP0402'     | ''          | ''            | '20100923'
 '42.2'       | '1%'      | '1/16W'  | '0402LF'  | 'CHIP'   | 'CS04222FB01'(!)        = 'End of Design' | 'Comp-Approve'     | 'CS04222FB01'           |'R0402'| '(R0402-0201)'                 | '42.2'    | '1%'    | '1/16W'  | 'DISCRETE' | 'RES CHIP 42.2 1/16W +-1%(0402)'                   | 'CHIP0402'     | ''          | ''            | '20100923'
 '42.2'       | '1%'      | '1/16W'  | '0402LF'  | 'EMPTY'  | 'CS04222FB01'(!)        = 'End of Design' | 'Comp-Approve'     | 'CS04222FB01'           |'R0402'| '(R0402-0201)'                 | '42.2'    | '1%'    | '1/16W'  | 'IO'       | 'RES CHIP 42.2 1/16W +-1%(0402)'                   | 'CHIP0402'     | ''          | ''            | '20100923'
 '475'        | '1%'      | '1/16W'  | '0402LF'  | 'CHIP'   | 'CS14752FB11'(!)        = 'End of Design' | 'Comp-Approve'     | 'CS14752FB11'           |'R0402'| '(R0402-0201)'                 | '475'     | '1%'    | '1/16W'  | 'DISCRETE' | 'RES CHIP 475 1/16W +-1%(0402)'                    | 'CHIP0402'     | ''          | ''            | '20100923'
 '475'        | '1%'      | '1/16W'  | '0402LF'  | 'EMPTY'  | 'CS14752FB11'(!)        = 'End of Design' | 'Comp-Approve'     | 'CS14752FB11'           |'R0402'| '(R0402-0201)'                 | '475'     | '1%'    | '1/16W'  | 'IO'       | 'RES CHIP 475 1/16W +-1%(0402)'                    | 'CHIP0402'     | ''          | ''            | '20100923'
 '2.74K'      | '1%'      | '1/16W'  | '0402LF'  | 'CHIP'   | 'CS22742FB00'(!)        = 'End of Design' | 'Comp-Approve'     | 'CS22742FB00'           |'R0402'| '(R0402-0201)'                 | '2.74K'   | '1%'    | '1/16W'  | 'DISCRETE' | 'RES CHIP 2.74K 1/16W +-1%(0402)'                  | 'CHIP0402'     | ''          | ''            | '20100923'
 '2.74K'      | '1%'      | '1/16W'  | '0402LF'  | 'EMPTY'  | 'CS22742FB00'(!)        = 'End of Design' | 'Comp-Approve'     | 'CS22742FB00'           |'R0402'| '(R0402-0201)'                 | '2.74K'   | '1%'    | '1/16W'  | 'IO'       | 'RES CHIP 2.74K 1/16W +-1%(0402)'                  | 'CHIP0402'     | ''          | ''            | '20100923'
 '2.74K'      | '1%'      | '1/10W'  | '0603LF'  | 'CHIP'   | 'CS22743F935'(!)        = ''              | ''                 | 'CS22743F935'           |'R0603'| '(SMR0603AW)'                  | '2.74K'   | '1%'    | '1/10W'  | 'DISCRETE' | 'RES CHIP 2.74K 1/10W +-1%(0603) EP'               | 'CHIP0402'     | ''          | ''            | '20100923'
 '2.74K'      | '1%'      | '1/10W'  | '0603LF'  | 'EMPTY'  | 'CS22743F935'(!)        = ''              | ''                 | 'CS22743F935'           |'R0603'| '(SMR0603AW)'                  | '2.74K'   | '1%'    | '1/10W'  | 'IO'       | 'RES CHIP 2.74K 1/10W +-1%(0603) EP'               | 'CHIP0402'     | ''          | ''            | '20100923'
 '0.015'      | '1%'      | '1/2W'   | '2010LF'  | 'CHIP'   | 'CS+0157FJ00'(!)        = 'End of Design' | 'Comp-Release Qty' | 'CS+0157FJ00'           |'R2010XA'| '(SMR2010AW)'                  | '0.015'   | '1%'    | '1/2W'   | 'DISCRETE' | 'RES CHIP 0.015 1/2W +-1%(2010)'                   | 'CHIP2010'     | ''          | ''            | '20100927'
 '0.015'      | '1%'      | '1/2W'   | '2010LF'  | 'EMPTY'  | 'CS+0157FJ00'(!)        = 'End of Design' | 'Comp-Release Qty' | 'CS+0157FJ00'           |'R2010XA'| '(SMR2010AW)'                  | '0.015'   | '1%'    | '1/2W'   | 'IO'       | 'RES CHIP 0.015 1/2W +-1%(2010)'                   | 'CHIP2010'     | ''          | ''            | '20100927'
 '274'        | '1%'      | '1/10W'  | '0603LF'  | 'CHIP'   | 'CS12743F900'(!)        = 'End of Design' | 'Comp-Approve'     | 'CS12743F900'           |'R0603'| '(SMR0603AW)'                  | '274'     | '1%'    | '1/10W'  | 'DISCRETE' | 'RES CHIP 274 1/10W +-1%(0603)'                    | 'CHIP0603'     | ''          | ''            | '20100927'
 '274'        | '1%'      | '1/10W'  | '0603LF'  | 'EMPTY'  | 'CS12743F900'(!)        = 'End of Design' | 'Comp-Approve'     | 'CS12743F900'           |'R0603'| '(SMR0603AW)'                  | '274'     | '1%'    | '1/10W'  | 'IO'       | 'RES CHIP 274 1/10W +-1%(0603)'                    | 'CHIP0603'     | ''          | ''            | '20100927'
 '412'        | '1%'      | '1/16W'  | '0402LF'  | 'CHIP'   | 'CS14122FB15'(!)        = 'End of Design' | 'Comp-Approve'     | 'CS14122FB15'           |'R0402'| '(R0402-0201)'                 | '412'     | '1%'    | '1/16W'  | 'DISCRETE' | 'RESISTOR CHIP 412 1/16W +-1%(0402)'               | 'CHIP0402'     | ''          | ''            | '20100929'
 '412'        | '1%'      | '1/16W'  | '0402LF'  | 'EMPTY'  | 'CS14122FB15'(!)        = 'End of Design' | 'Comp-Approve'     | 'CS14122FB15'           |'R0402'| '(R0402-0201)'                 | '412'     | '1%'    | '1/16W'  | 'IO'       | 'RESISTOR CHIP 412 1/16W +-1%(0402)'               | 'CHIP0402'     | ''          | ''            | '20100929'
 '200K'       | '1%'      | '1/16W'  | '0402LF'  | 'CHIP'   | 'CS42002FB12'(!)        = 'End of Design' | 'Comp-Approve'     | 'CS42002FB12'           |'R0402'| '(R0402-0201)'                 | '200K'    | '1%'    | '1/16W'  | 'DISCRETE' | 'RES CHIP 200K 1/16W+-1%(0402)'                    | 'CHIP0402'     | ''          | ''            | '20100929'
 '200K'       | '1%'      | '1/16W'  | '0402LF'  | 'EMPTY'  | 'CS42002FB12'(!)        = 'End of Design' | 'Comp-Approve'     | 'CS42002FB12'           |'R0402'| '(R0402-0201)'                 | '200K'    | '1%'    | '1/16W'  | 'IO'       | 'RES CHIP 200K 1/16W+-1%(0402)'                    | 'CHIP0402'     | ''          | ''            | '20100929'
 '9.1K'       | '1%'      | '1/16W'  | '0402LF'  | 'CHIP'   | 'CS29102FB10'(!)        = 'End of Design' | 'Comp-Approve'     | 'CS29102FB10'           |'R0402'| '(R0402-0201)'                 | '9.1K'    | '1%'    | '1/16W'  | 'DISCRETE' | 'RES CHIP 9.1K 1/16W +-1%(0402)'                   | 'CHIP0402'     | ''          | ''            | '20101001'
 '9.1K'       | '1%'      | '1/16W'  | '0402LF'  | 'EMPTY'  | 'CS29102FB10'(!)        = 'End of Design' | 'Comp-Approve'     | 'CS29102FB10'           |'R0402'| '(R0402-0201)'                 | '9.1K'    | '1%'    | '1/16W'  | 'IO'       | 'RES CHIP 9.1K 1/16W +-1%(0402)'                   | 'CHIP0402'     | ''          | ''            | '20101001'
 '9.31K'      | '1%'      | '1/16W'  | '0402LF'  | 'CHIP'   | 'CS29312FB13'(!)        = 'End of Design' | 'Comp-Approve'     | 'CS29312FB13'           |'R0402'| '(R0402-0201)'                 | '9.31K'   | '1%'    | '1/16W'  | 'DISCRETE' | 'RES CHIP 9.31K 1/16W +-1%(0402)'                  | 'CHIP0402'     | ''          | ''            | '20101001'
 '9.31K'      | '1%'      | '1/16W'  | '0402LF'  | 'EMPTY'  | 'CS29312FB13'(!)        = 'End of Design' | 'Comp-Approve'     | 'CS29312FB13'           |'R0402'| '(R0402-0201)'                 | '9.31K'   | '1%'    | '1/16W'  | 'IO'       | 'RES CHIP 9.31K 1/16W +-1%(0402)'                  | 'CHIP0402'     | ''          | ''            | '20101001'
 '0.1'        | '1%'      | '1/4W'   | '0805LF'  | 'CHIP'   | 'CS+1006FA18'(!)        = ''              | ''                 | 'CS+1006FA18'           |'R0805'| '(SMR0805AW)'                  | '0.1'     | '1%'    | '1/4W'   | 'DISCRETE' | 'RES CHIP 0.1 1/4W +-1%(0805)EU'                   | 'CHIP0805'     | ''          | ''            | '20100930'
 '0.1'        | '1%'      | '1/4W'   | '0805LF'  | 'EMPTY'  | 'CS+1006FA18'(!)        = ''              | ''                 | 'CS+1006FA18'           |'R0805'| '(SMR0805AW)'                  | '0.1'     | '1%'    | '1/4W'   | 'IO'       | 'RES CHIP 0.1 1/4W +-1%(0805)EU'                   | 'CHIP0805'     | ''          | ''            | '20100930'
 '22'         | '1%'      | '1/16W'  | '0402LF'  | 'CHIP'   | 'CS02202FB12'(!)        = 'End of Design' | 'Comp-Approve'     | 'CS02202FB12'           |'R0402'| '(R0402-0201)'                 | '22'      | '1%'    | '1/16W'  | 'DISCRETE' | 'RES CHIP 22 1/16W +-1%(0402)'                     | 'CHIP0402'     | ''          | ''            | '20100930'
 '22'         | '1%'      | '1/16W'  | '0402LF'  | 'EMPTY'  | 'CS02202FB12'(!)        = 'End of Design' | 'Comp-Approve'     | 'CS02202FB12'           |'R0402'| '(R0402-0201)'                 | '22'      | '1%'    | '1/16W'  | 'IO'       | 'RES CHIP 22 1/16W +-1%(0402)'                     | 'CHIP0402'     | ''          | ''            | '20100930'
 '22'         | '5%'      | '1/8W'   | '0805LF'  | 'CHIP'   | 'CS02204JA18'(!)        = ''              | ''                 | 'CS02204JA18'           |'R0805'| '(SMR0805AW)'                  | '22'      | '5%'    | '1/8W'   | 'DISCRETE' | 'RES CHIP 22 1/8W +-5%(0805)'                      | 'CHIP0805'     | ''          | ''            | '20100930'
 '22'         | '5%'      | '1/8W'   | '0805LF'  | 'EMPTY'  | 'CS02204JA18'(!)        = ''              | ''                 | 'CS02204JA18'           |'R0805'| '(SMR0805AW)'                  | '22'      | '5%'    | '1/8W'   | 'IO'       | 'RES CHIP 22 1/8W +-5%(0805)'                      | 'CHIP0805'     | ''          | ''            | '20100930'
 '24.9'       | '1%'      | '1/16W'  | '0402LF'  | 'CHIP'   | 'CS02492FB29'(!)        = 'End of Design' | 'Comp-Approve'     | 'CS02492FB29'           |'R0402'| '(R0402-0201)'                 | '24.9'    | '1%'    | '1/16W'  | 'DISCRETE' | 'RES CHIP 24.9 1/16W +-1%(0402)'                   | 'CHIP0402'     | ''          | ''            | '20100930'
 '24.9'       | '1%'      | '1/16W'  | '0402LF'  | 'EMPTY'  | 'CS02492FB29'(!)        = 'End of Design' | 'Comp-Approve'     | 'CS02492FB29'           |'R0402'| '(R0402-0201)'                 | '24.9'    | '1%'    | '1/16W'  | 'IO'       | 'RES CHIP 24.9 1/16W +-1%(0402)'                   | 'CHIP0402'     | ''          | ''            | '20100930'
 '51'         | '5%'      | '1/16W'  | '0402LF'  | 'CHIP'   | 'CS05102JB35'(!)        = 'End of Design' | 'Comp-Approve'     | 'CS05102JB35'           |'R0402'| '(R0402-0201)'                 | '51'      | '5%'    | '1/16W'  | 'DISCRETE' | 'RES CHIP 51 1/16W +-5%(0402)'                     | 'CHIP0402'     | ''          | ''            | '20100930'
 '51'         | '5%'      | '1/16W'  | '0402LF'  | 'EMPTY'  | 'CS05102JB35'(!)        = 'End of Design' | 'Comp-Approve'     | 'CS05102JB35'           |'R0402'| '(R0402-0201)'                 | '51'      | '5%'    | '1/16W'  | 'IO'       | 'RES CHIP 51 1/16W +-5%(0402)'                     | 'CHIP0402'     | ''          | ''            | '20100930'
 '51.1'       | '1%'      | '1/10W'  | '0603LF'  | 'CHIP'   | 'CS05113F918'(!)        = ''              | ''                 | 'CS05113F918'           |'R0603'| '(SMR0603AW)'                  | '51.1'    | '1%'    | '1/10W'  | 'DISCRETE' | 'RES CHIP 51.1 1/10W +-1%(0603)'                   | 'CHIP0603'     | ''          | ''            | '20100930'
 '51.1'       | '1%'      | '1/10W'  | '0603LF'  | 'EMPTY'  | 'CS05113F918'(!)        = ''              | ''                 | 'CS05113F918'           |'R0603'| '(SMR0603AW)'                  | '51.1'    | '1%'    | '1/10W'  | 'IO'       | 'RES CHIP 51.1 1/10W +-1%(0603)'                   | 'CHIP0603'     | ''          | ''            | '20100930'
 '169'        | '1%'      | '1/16W'  | '0402LF'  | 'CHIP'   | 'CS11692FB09'(!)        = 'End of Design' | 'Comp-Approve'     | 'CS11692FB09'           |'R0402'| '(R0402-0201)'                 | '169'     | '1%'    | '1/16W'  | 'DISCRETE' | 'RES CHIP 169 1/16W +-1%(0402)'                    | 'CHIP0402'     | ''          | ''            | '20100930'
 '169'        | '1%'      | '1/16W'  | '0402LF'  | 'EMPTY'  | 'CS11692FB09'(!)        = 'End of Design' | 'Comp-Approve'     | 'CS11692FB09'           |'R0402'| '(R0402-0201)'                 | '169'     | '1%'    | '1/16W'  | 'IO'       | 'RES CHIP 169 1/16W +-1%(0402)'                    | 'CHIP0402'     | ''          | ''            | '20100930'
 '200'        | '5%'      | '1/10W'  | '0603LF'  | 'CHIP'   | 'CS12003J940'(!)        = 'End of Design' | 'Comp-Approve'     | 'CS12003J940'           |'R0603'| '(SMR0603AW)'                  | '200'     | '5%'    | '1/10W'  | 'DISCRETE' | 'RESISTOR CHIP 200 1/10W+-5%(0603)'                | 'CHIP0603'     | ''          | ''            | '20100930'
 '200'        | '5%'      | '1/10W'  | '0603LF'  | 'EMPTY'  | 'CS12003J940'(!)        = 'End of Design' | 'Comp-Approve'     | 'CS12003J940'           |'R0603'| '(SMR0603AW)'                  | '200'     | '5%'    | '1/10W'  | 'IO'       | 'RESISTOR CHIP 200 1/10W+-5%(0603)'                | 'CHIP0603'     | ''          | ''            | '20100930'
 '392'        | '1%'      | '1/16W'  | '0402LF'  | 'CHIP'   | 'CS13922FB11'(!)        = 'End of Design' | 'Comp-Approve'     | 'CS13922FB11'           |'R0402'| '(R0402-0201)'                 | '392'     | '1%'    | '1/16W'  | 'DISCRETE' | 'RES CHIP 392 1/16W +-1%(0402)'                    | 'CHIP0402'     | ''          | ''            | '20100930'
 '392'        | '1%'      | '1/16W'  | '0402LF'  | 'EMPTY'  | 'CS13922FB11'(!)        = 'End of Design' | 'Comp-Approve'     | 'CS13922FB11'           |'R0402'| '(R0402-0201)'                 | '392'     | '1%'    | '1/16W'  | 'IO'       | 'RES CHIP 392 1/16W +-1%(0402)'                    | 'CHIP0402'     | ''          | ''            | '20100930'
 '510'        | '5%'      | '1/16W'  | '0402LF'  | 'CHIP'   | 'CS15102JB00'(!)        = 'End of Design' | 'Comp-Approve'     | 'CS15102JB00'           |'R0402'| '(R0402-0201)'                 | '510'     | '5%'    | '1/16W'  | 'DISCRETE' | 'RES CHIP 510 1/16W +-5%(0402)'                    | 'CHIP0402'     | ''          | ''            | '20100930'
 '510'        | '5%'      | '1/16W'  | '0402LF'  | 'EMPTY'  | 'CS15102JB00'(!)        = 'End of Design' | 'Comp-Approve'     | 'CS15102JB00'           |'R0402'| '(R0402-0201)'                 | '510'     | '5%'    | '1/16W'  | 'IO'       | 'RES CHIP 510 1/16W +-5%(0402)'                    | 'CHIP0402'     | ''          | ''            | '20100930'
 '1.27K'      | '1%'      | '1/16W'  | '0402LF'  | 'CHIP'   | 'CS21272FB15'(!)        = 'End of Design' | 'Comp-Approve'     | 'CS21272FB15'           |'R0402'| '(R0402-0201)'                 | '1.27K'   | '1%'    | '1/16W'  | 'DISCRETE' | 'RES CHIP 1.27K 1/16W +-1% (0402)'                 | 'CHIP0402'     | ''          | ''            | '20100930'
 '1.27K'      | '1%'      | '1/16W'  | '0402LF'  | 'EMPTY'  | 'CS21272FB15'(!)        = 'End of Design' | 'Comp-Approve'     | 'CS21272FB15'           |'R0402'| '(R0402-0201)'                 | '1.27K'   | '1%'    | '1/16W'  | 'IO'       | 'RES CHIP 1.27K 1/16W +-1% (0402)'                 | 'CHIP0402'     | ''          | ''            | '20100930'
 '2.2'        | '1%'      | '1/8W'   | '0805LF'  | 'CHIP'   | 'CS-2204FA00'(!)        = 'End of Design' | 'Comp-Approve'     | 'CS-2204FA00'           |'R0805'| '(SMR0805AW)'                  | '2.2'     | '1%'    | '1/8W'   | 'DISCRETE' | 'RES CHIP 2.2 1/8W +-1%(0805)'                     | 'CHIP0805'     | ''          | ''            | '20100930'
 '2.2'        | '1%'      | '1/8W'   | '0805LF'  | 'EMPTY'  | 'CS-2204FA00'(!)        = 'End of Design' | 'Comp-Approve'     | 'CS-2204FA00'           |'R0805'| '(SMR0805AW)'                  | '2.2'     | '1%'    | '1/8W'   | 'IO'       | 'RES CHIP 2.2 1/8W +-1%(0805)'                     | 'CHIP0805'     | ''          | ''            | '20100930'
 '3.01K'      | '1%'      | '1/16W'  | '0402LF'  | 'CHIP'   | 'CS23012FB16'(!)        = 'End of Design' | 'Comp-Approve'     | 'CS23012FB16'           |'R0402'| '(R0402-0201)'                 | '3.01K'   | '1%'    | '1/16W'  | 'DISCRETE' | 'RES CHIP 3.01K 1/16W +-1%(0402)'                  | 'CHIP0402'     | ''          | ''            | '20100930'
 '3.01K'      | '1%'      | '1/16W'  | '0402LF'  | 'EMPTY'  | 'CS23012FB16'(!)        = 'End of Design' | 'Comp-Approve'     | 'CS23012FB16'           |'R0402'| '(R0402-0201)'                 | '3.01K'   | '1%'    | '1/16W'  | 'IO'       | 'RES CHIP 3.01K 1/16W +-1%(0402)'                  | 'CHIP0402'     | ''          | ''            | '20100930'
 '3.65K'      | '1%'      | '1/16W'  | '0402LF'  | 'CHIP'   | 'CS23652FB08'(!)        = 'End of Design' | 'Comp-Approve'     | 'CS23652FB08'           |'R0402'| '(R0402-0201)'                 | '3.65K'   | '1%'    | '1/16W'  | 'DISCRETE' | 'RES CHIP 3.65K 1/16W +-1%(0402)'                  | 'CHIP0402'     | ''          | ''            | '20100930'
 '3.65K'      | '1%'      | '1/16W'  | '0402LF'  | 'EMPTY'  | 'CS23652FB08'(!)        = 'End of Design' | 'Comp-Approve'     | 'CS23652FB08'           |'R0402'| '(R0402-0201)'                 | '3.65K'   | '1%'    | '1/16W'  | 'IO'       | 'RES CHIP 3.65K 1/16W +-1%(0402)'                  | 'CHIP0402'     | ''          | ''            | '20100930'
 '4.75K'      | '1%'      | '1/16W'  | '0402LF'  | 'CHIP'   | 'CS24752FB12'(!)        = 'End of Design' | 'Comp-Approve'     | 'CS24752FB12'           |'R0402'| '(R0402-0201)'                 | '4.75K'   | '1%'    | '1/16W'  | 'DISCRETE' | 'RES CHIP 4.75K 1/16W +-1%(0402)'                  | 'CHIP0402'     | ''          | ''            | '20100930'
 '4.75K'      | '1%'      | '1/16W'  | '0402LF'  | 'EMPTY'  | 'CS24752FB12'(!)        = 'End of Design' | 'Comp-Approve'     | 'CS24752FB12'           |'R0402'| '(R0402-0201)'                 | '4.75K'   | '1%'    | '1/16W'  | 'IO'       | 'RES CHIP 4.75K 1/16W +-1%(0402)'                  | 'CHIP0402'     | ''          | ''            | '20100930'
 '30K'        | '1%'      | '1/16W'  | '0402LF'  | 'CHIP'   | 'CS33002FB13'(!)        = 'End of Design' | 'Comp-Approve'     | 'CS33002FB13'           |'R0402'| '(R0402-0201)'                 | '30K'     | '1%'    | '1/16W'  | 'DISCRETE' | 'RES CHIP 30K 1/16W +-1%(0402)'                    | 'CHIP0402'     | ''          | ''            | '20100930'
 '30K'        | '1%'      | '1/16W'  | '0402LF'  | 'EMPTY'  | 'CS33002FB13'(!)        = 'End of Design' | 'Comp-Approve'     | 'CS33002FB13'           |'R0402'| '(R0402-0201)'                 | '30K'     | '1%'    | '1/16W'  | 'IO'       | 'RES CHIP 30K 1/16W +-1%(0402)'                    | 'CHIP0402'     | ''          | ''            | '20100930'
 '33K'        | '1%'      | '1/10W'  | '0603LF'  | 'CHIP'   | 'CS33303F911'(!)        = 'End of Design' | 'Comp-Approve'     | 'CS33303F911'           |'R0603'| '(SMR0603AW)'                  | '33K'     | '1%'    | '1/10W'  | 'DISCRETE' | 'RES CHIP 33K 1/10W +-1%(0603)'                    | 'CHIP0603'     | ''          | ''            | '20100930'
 '33K'        | '1%'      | '1/10W'  | '0603LF'  | 'EMPTY'  | 'CS33303F911'(!)        = 'End of Design' | 'Comp-Approve'     | 'CS33303F911'           |'R0603'| '(SMR0603AW)'                  | '33K'     | '1%'    | '1/10W'  | 'IO'       | 'RES CHIP 33K 1/10W +-1%(0603)'                    | 'CHIP0603'     | ''          | ''            | '20100930'
 '36K'        | '1%'      | '1/16W'  | '0402LF'  | 'CHIP'   | 'CS33602FB15'(!)        = 'End of Design' | 'Comp-Approve'     | 'CS33602FB15'           |'R0402'| '(R0402-0201)'                 | '36K'     | '1%'    | '1/16W'  | 'DISCRETE' | 'RES CHIP 36K 1/16W +-1%(0402)'                    | 'CHIP0402'     | ''          | ''            | '20100930'
 '36K'        | '1%'      | '1/16W'  | '0402LF'  | 'EMPTY'  | 'CS33602FB15'(!)        = 'End of Design' | 'Comp-Approve'     | 'CS33602FB15'           |'R0402'| '(R0402-0201)'                 | '36K'     | '1%'    | '1/16W'  | 'IO'       | 'RES CHIP 36K 1/16W +-1%(0402)'                    | 'CHIP0402'     | ''          | ''            | '20100930'
 '130K'       | '1%'      | '1/16W'  | '0402LF'  | 'CHIP'   | 'CS41302FB00'(!)        = 'End of Design' | 'Comp-Approve'     | 'CS41302FB00'           |'R0402'| '(R0402-0201)'                 | '130K'    | '1%'    | '1/16W'  | 'DISCRETE' | 'RES CHIP 130K 1/16W +-1%(0402)'                   | 'CHIP0402'     | ''          | ''            | '20100930'
 '130K'       | '1%'      | '1/16W'  | '0402LF'  | 'EMPTY'  | 'CS41302FB00'(!)        = 'End of Design' | 'Comp-Approve'     | 'CS41302FB00'           |'R0402'| '(R0402-0201)'                 | '130K'    | '1%'    | '1/16W'  | 'IO'       | 'RES CHIP 130K 1/16W +-1%(0402)'                   | 'CHIP0402'     | ''          | ''            | '20100930'
 '330K'       | '5%'      | '1/16W'  | '0402LF'  | 'CHIP'   | 'CS43302JB18'(!)        = 'End of Design' | 'Comp-Approve'     | 'CS43302JB18'           |'R0402'| '(R0402-0201)'                 | '330K'    | '5%'    | '1/16W'  | 'DISCRETE' | 'RES CHIP 330K 1/16W +-5% (0402)'                  | 'CHIP0402'     | ''          | ''            | '20100930'
 '330K'       | '5%'      | '1/16W'  | '0402LF'  | 'EMPTY'  | 'CS43302JB18'(!)        = 'End of Design' | 'Comp-Approve'     | 'CS43302JB18'           |'R0402'| '(R0402-0201)'                 | '330K'    | '5%'    | '1/16W'  | 'IO'       | 'RES CHIP 330K 1/16W +-5% (0402)'                  | 'CHIP0402'     | ''          | ''            | '20100930'
 '10M'        | '5%'      | '1/10W'  | '0603LF'  | 'CHIP'   | 'CS61003J946'(!)        = ''              | ''                 | 'CS61003J946'           |'R0603'| '(SMR0603AW)'                  | '10M'     | '5%'    | '1/10W'  | 'DISCRETE' | 'RES CHIP 10M 1/10W +-5%(0603)EP'                  | 'CHIP0603'     | ''          | ''            | '20100930'
 '10M'        | '5%'      | '1/10W'  | '0603LF'  | 'EMPTY'  | 'CS61003J946'(!)        = ''              | ''                 | 'CS61003J946'           |'R0603'| '(SMR0603AW)'                  | '10M'     | '5%'    | '1/10W'  | 'IO'       | 'RES CHIP 10M 1/10W +-5%(0603)EP'                  | 'CHIP0603'     | ''          | ''            | '20100930'
 '499K'       | '1%'      | '1/16W'  | '0402LF'  | 'CHIP'   | 'CS44992FB11'(!)        = 'End of Design' | 'Comp-Approve'     | 'CS44992FB11'           |'R0402'| '(R0402-0201)'                 | '499K'    | '1%'    | '1/16W'  | 'DISCRETE' | 'RES CHIP 499K 1/16W +-1% (0402)'                  | 'CHIP0603'     | ''          | ''            | '20101005'
 '499K'       | '1%'      | '1/16W'  | '0402LF'  | 'EMPTY'  | 'CS44992FB11'(!)        = 'End of Design' | 'Comp-Approve'     | 'CS44992FB11'           |'R0402'| '(R0402-0201)'                 | '499K'    | '1%'    | '1/16W'  | 'IO'       | 'RES CHIP 499K 1/16W +-1% (0402)'                  | 'CHIP0603'     | ''          | ''            | '20101005'
 '42.2'       | '1%'      | '1/10W'  | '0603LF'  | 'CHIP'   | 'CS04223F900'(!)        = ''              | ''                 | 'CS04223F900'           |'R0603'| '(SMR0603AW)'                  | '42.2'    | '1%'    | '1/10W'  | 'DISCRETE' | 'RES CHIP 42.2 1/10W +-1%(0603)'                   | 'CHIP0603'     | ''          | ''            | '20101006'
 '42.2'       | '1%'      | '1/10W'  | '0603LF'  | 'EMPTY'  | 'CS04223F900'(!)        = ''              | ''                 | 'CS04223F900'           |'R0603'| '(SMR0603AW)'                  | '42.2'    | '1%'    | '1/10W'  | 'IO'       | 'RES CHIP 42.2 1/10W +-1%(0603)'                   | 'CHIP0603'     | ''          | ''            | '20101006'
 '402'        | '1%'      | '1/16W'  | '0402LF'  | 'CHIP'   | 'CS14022FB11'(!)        = 'End of Design' | 'Comp-Approve'     | 'CS14022FB11'           |'R0402'| '(R0402-0201)'                 | '402'     | '1%'    | '1/16W'  | 'DISCRETE' | 'RES CHIP 402 1/16W +-1%( 0402)'                   | 'CHIP0402'     | ''          | ''            | '20101006'
 '402'        | '1%'      | '1/16W'  | '0402LF'  | 'EMPTY'  | 'CS14022FB11'(!)        = 'End of Design' | 'Comp-Approve'     | 'CS14022FB11'           |'R0402'| '(R0402-0201)'                 | '402'     | '1%'    | '1/16W'  | 'IO'       | 'RES CHIP 402 1/16W +-1%( 0402)'                   | 'CHIP0402'     | ''          | ''            | '20101006'
 '976'        | '1%'      | '1/16W'  | '0402LF'  | 'CHIP'   | 'CS19762FB19'(!)        = 'End of Design' | 'Comp-Approve'     | 'CS19762FB19'           |'R0402'| '(R0402-0201)'                 | '976'     | '1%'    | '1/16W'  | 'DISCRETE' | 'RES CHIP 976 1/16W +-1%(0402)'                    | 'CHIP0402'     | ''          | ''            | '20101006'
 '976'        | '1%'      | '1/16W'  | '0402LF'  | 'EMPTY'  | 'CS19762FB19'(!)        = 'End of Design' | 'Comp-Approve'     | 'CS19762FB19'           |'R0402'| '(R0402-0201)'                 | '976'     | '1%'    | '1/16W'  | 'IO'       | 'RES CHIP 976 1/16W +-1%(0402)'                    | 'CHIP0402'     | ''          | ''            | '20101006'
 '1.07K'      | '1%'      | '1/16W'  | '0402LF'  | 'CHIP'   | 'CS21072FB18'(!)        = 'End of Design' | 'Comp-Approve'     | 'CS21072FB18'           |'R0402'| '(R0402-0201)'                 | '1.07K'   | '1%'    | '1/16W'  | 'DISCRETE' | 'RES CHIP 1.07K 1/16W,+-1%(0402)'                  | 'CHIP0402'     | ''          | ''            | '20101006'
 '1.07K'      | '1%'      | '1/16W'  | '0402LF'  | 'EMPTY'  | 'CS21072FB18'(!)        = 'End of Design' | 'Comp-Approve'     | 'CS21072FB18'           |'R0402'| '(R0402-0201)'                 | '1.07K'   | '1%'    | '1/16W'  | 'IO'       | 'RES CHIP 1.07K 1/16W,+-1%(0402)'                  | 'CHIP0402'     | ''          | ''            | '20101006'
 '220K'       | '5%'      | '1/10W'  | '0603LF'  | 'CHIP'   | 'CS42203J918'(!)        = ''              | ''                 | 'CS42203J918'           |'R0603'| '(SMR0603AW)'                  | '220K'    | '5%'    | '1/10W'  | 'DISCRETE' | 'RESISTOR CHIP 220K 1/10W +-5%(1608)'              | 'CHIP0603'     | ''          | ''            | '20101006'
 '220K'       | '5%'      | '1/10W'  | '0603LF'  | 'EMPTY'  | 'CS42203J918'(!)        = ''              | ''                 | 'CS42203J918'           |'R0603'| '(SMR0603AW)'                  | '220K'    | '5%'    | '1/10W'  | 'IO'       | 'RESISTOR CHIP 220K 1/10W +-5%(1608)'              | 'CHIP0603'     | ''          | ''            | '20101006'
 '330K'       | '1%'      | '1/10W'  | '0603LF'  | 'CHIP'   | 'CS43303F912'(!)        = 'End of Design' | 'Comp-Approve'     | 'CS43303F912'           |'R0603'| '(SMR0603AW)'                  | '330K'    | '1%'    | '1/10W'  | 'DISCRETE' | 'RES CHIP 330K 1/10W +-1%(0603)'                   | 'CHIP0603'     | ''          | ''            | '20101006'
 '330K'       | '1%'      | '1/10W'  | '0603LF'  | 'EMPTY'  | 'CS43303F912'(!)        = 'End of Design' | 'Comp-Approve'     | 'CS43303F912'           |'R0603'| '(SMR0603AW)'                  | '330K'    | '1%'    | '1/10W'  | 'IO'       | 'RES CHIP 330K 1/10W +-1%(0603)'                   | 'CHIP0603'     | ''          | ''            | '20101006'
 '2.2'        | '5%'      | '1/10W'  | '0603LF'  | 'CHIP'   | 'CS-2203J913'(!)        = ''              | ''                 | 'CS-2203J913'           |'R0603'| '(SMR0603AW)'                  | '2.2'     | '5%'    | '1/10W'  | 'DISCRETE' | 'RESISTER CHIP 2.2 1/10W+-5%(0603)'                | 'CHIP0603'     | ''          | ''            | '20101006'
 '2.2'        | '5%'      | '1/10W'  | '0603LF'  | 'EMPTY'  | 'CS-2203J913'(!)        = ''              | ''                 | 'CS-2203J913'           |'R0603'| '(SMR0603AW)'                  | '2.2'     | '5%'    | '1/10W'  | 'IO'       | 'RESISTER CHIP 2.2 1/10W+-5%(0603)'                | 'CHIP0603'     | ''          | ''            | '20101006'
 '150'        | '1%'      | '1/10W'  | '0603LF'  | 'CHIP'   | 'CS11503F943'(!)        = ''              | ''                 | 'CS11503F943'           |'R0603'| '(SMR0603AW)'                  | '150'     | '1%'    | '1/10W'  | 'DISCRETE' | 'RESISTOR CHIP 150,1/10W,+-1%(0603)'               | 'CHIP0603'     | ''          | ''            | '20101008'
 '150'        | '1%'      | '1/10W'  | '0603LF'  | 'EMPTY'  | 'CS11503F943'(!)        = ''              | ''                 | 'CS11503F943'           |'R0603'| '(SMR0603AW)'                  | '150'     | '1%'    | '1/10W'  | 'IO'       | 'RESISTOR CHIP 150,1/10W,+-1%(0603)'               | 'CHIP0603'     | ''          | ''            | '20101008'
 '75'         | '1%'      | '1/10W'  | '0603LF'  | 'CHIP'   | 'CS07503F930'(!)        = 'End of Design' | 'Comp-Approve'     | 'CS07503F930'           |'R0603'| '(SMR0603AW)'                  | '75'      | '1%'    | '1/10W'  | 'DISCRETE' | 'RESISTOR CHIP 75 1/10W +-1%(1608)'                | 'CHIP0603'     | ''          | ''            | '20101008'
 '75'         | '1%'      | '1/10W'  | '0603LF'  | 'EMPTY'  | 'CS07503F930'(!)        = 'End of Design' | 'Comp-Approve'     | 'CS07503F930'           |'R0603'| '(SMR0603AW)'                  | '75'      | '1%'    | '1/10W'  | 'IO'       | 'RESISTOR CHIP 75 1/10W +-1%(1608)'                | 'CHIP0603'     | ''          | ''            | '20101008'
 '22.6'       | '1%'      | '1/16W'  | '0402LF'  | 'CHIP'   | 'CS02262FB10'(!)        = 'End of Design' | 'Comp-Approve'     | 'CS02262FB10'           |'R0402'| '(R0402-0201)'                 | '22.6'    | '1%'    | '1/16W'  | 'DISCRETE' | 'RES CHIP 22.6 1/16W +-1%(0402)'                   | 'CHIP0402'     | ''          | ''            | '20101008'
 '22.6'       | '1%'      | '1/16W'  | '0402LF'  | 'EMPTY'  | 'CS02262FB10'(!)        = 'End of Design' | 'Comp-Approve'     | 'CS02262FB10'           |'R0402'| '(R0402-0201)'                 | '22.6'    | '1%'    | '1/16W'  | 'IO'       | 'RES CHIP 22.6 1/16W +-1%(0402)'                   | 'CHIP0402'     | ''          | ''            | '20101008'
 '2'          | '5%'      | '1/10W'  | '0603LF'  | 'CHIP'   | 'CS-2003J932'(!)        = 'End of Design' | 'Comp-Approve'     | 'CS-2003J932'           |'R0603'| '(SMR0603AW)'                  | '2'       | '5%'    | '1/10W'  | 'DISCRETE' | 'RESISTOR CHIP 2 1/10W+-5%(0603)EP'                | 'CHIP0603'     | ''          | ''            | '20101008'
 '2'          | '5%'      | '1/10W'  | '0603LF'  | 'EMPTY'  | 'CS-2003J932'(!)        = 'End of Design' | 'Comp-Approve'     | 'CS-2003J932'           |'R0603'| '(SMR0603AW)'                  | '2'       | '5%'    | '1/10W'  | 'IO'       | 'RESISTOR CHIP 2 1/10W+-5%(0603)EP'                | 'CHIP0603'     | ''          | ''            | '20101008'
 '1.24K'      | '1%'      | '1/16W'  | '0402LF'  | 'CHIP'   | 'CS21242FB20'(!)        = 'End of Design' | 'Comp-Approve'     | 'CS21242FB20'           |'R0402'| '(R0402-0201)'                 | '1.24K'   | '1%'    | '1/16W'  | 'DISCRETE' | 'RES CHIP 1.24K 1/16W +-1%(0402)'                  | 'CHIP0402'     | ''          | ''            | '20101008'
 '1.24K'      | '1%'      | '1/16W'  | '0402LF'  | 'EMPTY'  | 'CS21242FB20'(!)        = 'End of Design' | 'Comp-Approve'     | 'CS21242FB20'           |'R0402'| '(R0402-0201)'                 | '1.24K'   | '1%'    | '1/16W'  | 'IO'       | 'RES CHIP 1.24K 1/16W +-1%(0402)'                  | 'CHIP0402'     | ''          | ''            | '20101008'
 '10M'        | '5%'      | '1/16W'  | '0402LF'  | 'CHIP'   | 'CS61002JB23'(!)        = 'End of Design' | 'Comp-Approve'     | 'CS61002JB23'           |'R0402'| '(R0402-0201)'                 | '10M'     | '5%'    | '1/16W'  | 'DISCRETE' | 'RES CHIP 10M 1/16W +-5% (0402)'                   | 'CHIP0402'     | ''          | ''            | '20101013'
 '10M'        | '5%'      | '1/16W'  | '0402LF'  | 'EMPTY'  | 'CS61002JB23'(!)        = 'End of Design' | 'Comp-Approve'     | 'CS61002JB23'           |'R0402'| '(R0402-0201)'                 | '10M'     | '5%'    | '1/16W'  | 'IO'       | 'RES CHIP 10M 1/16W +-5% (0402)'                   | 'CHIP0402'     | ''          | ''            | '20101013'
 '806'        | '1%'      | '1/16W'  | '0402LF'  | 'CHIP'   | 'CS18062FB29'(!)        = 'End of Design' | 'Comp-Approve'     | 'CS18062FB29'           |'R0402'| '(R0402-0201)'                 | '806'     | '1%'    | '1/16W'  | 'DISCRETE' | 'RES CHIP 806 1/16W +-1%(0402)'                    | 'CHIP0402'     | ''          | ''            | '20101015'
 '806'        | '1%'      | '1/16W'  | '0402LF'  | 'EMPTY'  | 'CS18062FB29'(!)        = 'End of Design' | 'Comp-Approve'     | 'CS18062FB29'           |'R0402'| '(R0402-0201)'                 | '806'     | '1%'    | '1/16W'  | 'IO'       | 'RES CHIP 806 1/16W +-1%(0402)'                    | 'CHIP0402'     | ''          | ''            | '20101015'
 '43'         | '5%'      | '1/16W'  | '0402LF'  | 'CHIP'   | 'CS04302JB13'(!)        = 'End of Design' | 'Comp-Approve'     | 'CS04302JB13'           |'R0402'| '(R0402-0201)'                 | '43'      | '5%'    | '1/16W'  | 'DISCRETE' | 'RES CHIP 43 1/16W +-5%( 0402 )'                   | 'CHIP0402'     | ''          | ''            | '20101018'
 '43'         | '5%'      | '1/16W'  | '0402LF'  | 'EMPTY'  | 'CS04302JB13'(!)        = 'End of Design' | 'Comp-Approve'     | 'CS04302JB13'           |'R0402'| '(R0402-0201)'                 | '43'      | '5%'    | '1/16W'  | 'IO'       | 'RES CHIP 43 1/16W +-5%( 0402 )'                   | 'CHIP0402'     | ''          | ''            | '20101018'
 '0.4'        | '1%'      | '1/10W'  | '0603LF'  | 'CHIP'   | 'CS+4003F900'(!)        = ''              | ''                 | 'CS+4003F900'           |'R0603'| '(SMR0603AW)'                  | '0.4'     | '1%'    | '1/10W'  | 'DISCRETE' | 'RESISTOR CHIP 0.4 1/10W +-1%(0603)'               | 'CHIP0603'     | ''          | ''            | '20101018'
 '0.4'        | '1%'      | '1/10W'  | '0603LF'  | 'EMPTY'  | 'CS+4003F900'(!)        = ''              | ''                 | 'CS+4003F900'           |'R0603'| '(SMR0603AW)'                  | '0.4'     | '1%'    | '1/10W'  | 'IO'       | 'RESISTOR CHIP 0.4 1/10W +-1%(0603)'               | 'CHIP0603'     | ''          | ''            | '20101018'
 '2.32K'      | '1%'      | '1/16W'  | '0402LF'  | 'CHIP'   | 'CS22322FB01'(!)        = 'End of Design' | 'Comp-Approve'     | 'CS22322FB01'           |'R0402'| '(R0402-0201)'                 | '2.32K'   | '1%'    | '1/16W'  | 'DISCRETE' | 'RESISTOR CHIP 2.32K 1/16W +-1%(0402)'             | 'CHIP0402'     | ''          | ''            | '20101028'
 '2.32K'      | '1%'      | '1/16W'  | '0402LF'  | 'EMPTY'  | 'CS22322FB01'(!)        = 'End of Design' | 'Comp-Approve'     | 'CS22322FB01'           |'R0402'| '(R0402-0201)'                 | '2.32K'   | '1%'    | '1/16W'  | 'IO'       | 'RESISTOR CHIP 2.32K 1/16W +-1%(0402)'             | 'CHIP0402'     | ''          | ''            | '20101028'
 '36.5K'      | '1%'      | '1/16W'  | '0402LF'  | 'CHIP'   | 'CS33652FB18'(!)        = 'End of Design' | 'Comp-Approve'     | 'CS33652FB18'           |'R0402'| '(R0402-0201)'                 | '36.5K'   | '1%'    | '1/16W'  | 'DISCRETE' | 'RES CHIP 36.5K 1/16W +-1%(0402)'                  | 'CHIP0402'     | ''          | ''            | '20101028'
 '36.5K'      | '1%'      | '1/16W'  | '0402LF'  | 'EMPTY'  | 'CS33652FB18'(!)        = 'End of Design' | 'Comp-Approve'     | 'CS33652FB18'           |'R0402'| '(R0402-0201)'                 | '36.5K'   | '1%'    | '1/16W'  | 'IO'       | 'RES CHIP 36.5K 1/16W +-1%(0402)'                  | 'CHIP0402'     | ''          | ''            | '20101028'
 '1.8'        | '1%'      | '1/10W'  | '0603LF'  | 'CHIP'   | 'CS-1803F900'(!)        = 'End of Design' | 'P/N Release'      | 'CS-1803F900'           |'R0603'| '(SMR0603AW)'                  | '1.8'     | '1%'    | '1/10W'  | 'DISCRETE' | 'RES CHIP 1.8 1/10W +-1%(0603)'                    | 'CHIP0603'     | ''          | ''            | '20101101'
 '1.8'        | '1%'      | '1/10W'  | '0603LF'  | 'EMPTY'  | 'CS-1803F900'(!)        = 'End of Design' | 'P/N Release'      | 'CS-1803F900'           |'R0603'| '(SMR0603AW)'                  | '1.8'     | '1%'    | '1/10W'  | 'IO'       | 'RES CHIP 1.8 1/10W +-1%(0603)'                    | 'CHIP0603'     | ''          | ''            | '20101101'
 '1.8'        | '5%'      | '1/10W'  | '0603LF'  | 'CHIP'   | 'CS-1803J900'(!)        = 'End of Design' | 'Comp-Approve'     | 'CS-1803J900'           |'R0603'| '(SMR0603AW)'                  | '1.8'     | '5%'    | '1/10W'  | 'DISCRETE' | 'RES CHIP 1.8 1/10W +-5%(0603)'                    | 'CHIP0603'     | ''          | ''            | '20101101'
 '1.8'        | '5%'      | '1/10W'  | '0603LF'  | 'EMPTY'  | 'CS-1803J900'(!)        = 'End of Design' | 'Comp-Approve'     | 'CS-1803J900'           |'R0603'| '(SMR0603AW)'                  | '1.8'     | '5%'    | '1/10W'  | 'IO'       | 'RES CHIP 1.8 1/10W +-5%(0603)'                    | 'CHIP0603'     | ''          | ''            | '20101101'
 '0.0005'     | '1%'      | '3W'     | '2512LF'  | 'CHIP'   | 'CS0000DFR00'(!)        = ''              | ''                 | 'CS0000DFR00'           |'R2512A'| '(SMR2512AW)'                  | '0.0005'  | '1%'    | '3W'     | 'DISCRETE' | 'RES CHIP 0.0005 3W +-1%(2512)'                    | 'CHIP2512'     | ''          | ''            | '20101105'
 '0.0005'     | '1%'      | '3W'     | '2512LF'  | 'EMPTY'  | 'CS0000DFR00'(!)        = ''              | ''                 | 'CS0000DFR00'           |'R2512A'| '(SMR2512AW)'                  | '0.0005'  | '1%'    | '3W'     | 'IO'       | 'RES CHIP 0.0005 3W +-1%(2512)'                    | 'CHIP2512'     | ''          | ''            | '20101105'
 '14.7K'      | '1%'      | '1/16W'  | '0402LF'  | 'CHIP'   | 'CS31472FB14'(!)        = 'End of Design' | 'Comp-Approve'     | 'CS31472FB14'           |'R0402'| '(R0402-0201)'                 | '14.7K'   | '1%'    | '1/16W'  | 'DISCRETE' | 'RES CHIP 14.7K 1/16W +-1% (0402)'                 | 'CHIP0402'     | ''          | ''            | '20101213'
 '14.7K'      | '1%'      | '1/16W'  | '0402LF'  | 'EMPTY'  | 'CS31472FB14'(!)        = 'End of Design' | 'Comp-Approve'     | 'CS31472FB14'           |'R0402'| '(R0402-0201)'                 | '14.7K'   | '1%'    | '1/16W'  | 'IO'       | 'RES CHIP 14.7K 1/16W +-1% (0402)'                 | 'CHIP0402'     | ''          | ''            | '20101213'
 '64.9K'      | '1%'      | '1/16W'  | '0402LF'  | 'CHIP'   | 'CS36492FB17'(!)        = 'End of Design' | 'Comp-Approve'     | 'CS36492FB17'           |'R0402'| '(R0402-0201)'                 | '64.9K'   | '1%'    | '1/16W'  | 'DISCRETE' | 'RES CHIP 64.9K 1/16W +-1%(0402)'                  | 'CHIP0402'     | ''          | ''            | '20101221'
 '64.9K'      | '1%'      | '1/16W'  | '0402LF'  | 'EMPTY'  | 'CS36492FB17'(!)        = 'End of Design' | 'Comp-Approve'     | 'CS36492FB17'           |'R0402'| '(R0402-0201)'                 | '64.9K'   | '1%'    | '1/16W'  | 'IO'       | 'RES CHIP 64.9K 1/16W +-1%(0402)'                  | 'CHIP0402'     | ''          | ''            | '20101221'
 '7.5K'       | '1%'      | '1/10W'  | '0603LF'  | 'CHIP'   | 'CS27503F917'(!)        = 'End of Design' | 'Comp-Approve'     | 'CS27503F917'           |'R0603'| '(SMR0603AW)'                  | '7.5K'    | '1%'    | '1/10W'  | 'DISCRETE' | 'RES CHIP 7.5K 1/10W +-1%(0603)'                   | 'CHIP0603'     | ''          | ''            | '20101221'
 '7.5K'       | '1%'      | '1/10W'  | '0603LF'  | 'EMPTY'  | 'CS27503F917'(!)        = 'End of Design' | 'Comp-Approve'     | 'CS27503F917'           |'R0603'| '(SMR0603AW)'                  | '7.5K'    | '1%'    | '1/10W'  | 'IO'       | 'RES CHIP 7.5K 1/10W +-1%(0603)'                   | 'CHIP0603'     | ''          | ''            | '20101221'
 '499'        | '1%'      | '1/10W'  | '0603LF'  | 'CHIP'   | 'CS14993F939'(!)        = ''              | ''                 | 'CS14993F939'           |'R0603'| '(SMR0603AW)'                  | '499'     | '1%'    | '1/10W'  | 'DISCRETE' | 'RESISTOR CHIP 499 1/10W +-1%(0603)'               | 'CHIP0603'     | ''          | ''            | '20101221'
 '499'        | '1%'      | '1/10W'  | '0603LF'  | 'EMPTY'  | 'CS14993F939'(!)        = ''              | ''                 | 'CS14993F939'           |'R0603'| '(SMR0603AW)'                  | '499'     | '1%'    | '1/10W'  | 'IO'       | 'RESISTOR CHIP 499 1/10W +-1%(0603)'               | 'CHIP0603'     | ''          | ''            | '20101221'
 '150K'       | '1%'      | '1/10W'  | '0603LF'  | 'CHIP'   | 'CS41503F906'(!)        = ''              | ''                 | 'CS41503F906'           |'R0603'| '(SMR0603AW)'                  | '150K'    | '1%'    | '1/10W'  | 'DISCRETE' | 'RES CHIP 150K 1/10W +-1%(0603)'                   | 'CHIP0603'     | ''          | ''            | '20110106'
 '150K'       | '1%'      | '1/10W'  | '0603LF'  | 'EMPTY'  | 'CS41503F906'(!)        = ''              | ''                 | 'CS41503F906'           |'R0603'| '(SMR0603AW)'                  | '150K'    | '1%'    | '1/10W'  | 'IO'       | 'RES CHIP 150K 1/10W +-1%(0603)'                   | 'CHIP0603'     | ''          | ''            | '20110106'
 '499'        | '1%'      | '1/10W'  | '0603LF'  | 'CHIP'   | 'CS41503F914'(!)        = 'End of Design' | 'Comp-Approve'     | 'CS41503F914'           |'R0603'| '(SMR0603AW)'                  | '499'     | '1%'    | '1/10W'  | 'DISCRETE' | 'RES CHIP 150K 1/10W +-1%(0603)'                   | 'CHIP0603'     | ''          | ''            | '20110106'
 '499'        | '1%'      | '1/10W'  | '0603LF'  | 'EMPTY'  | 'CS41503F914'(!)        = 'End of Design' | 'Comp-Approve'     | 'CS41503F914'           |'R0603'| '(SMR0603AW)'                  | '499'     | '1%'    | '1/10W'  | 'IO'       | 'RES CHIP 150K 1/10W +-1%(0603)'                   | 'CHIP0603'     | ''          | ''            | '20110106'
 '0.004'      | '1%'      | '1W'     | '2512LF'  | 'CHIP'   | 'CS+0048FR00'(!)        = ''              | ''                 | 'CS+0048FR00'           |'R2512A'| '(SMR2512AW)'                  | '0.004'   | '1%'    | '1W'     | 'DISCRETE' | 'RES CHIP 0.004 1W +-1%(2512)'                     | 'CHIP2512'     | ''          | ''            | '20110106'
 '0.004'      | '1%'      | '1W'     | '2512LF'  | 'EMPTY'  | 'CS+0048FR00'(!)        = ''              | ''                 | 'CS+0048FR00'           |'R2512A'| '(SMR2512AW)'                  | '0.004'   | '1%'    | '1W'     | 'IO'       | 'RES CHIP 0.004 1W +-1%(2512)'                     | 'CHIP2512'     | ''          | ''            | '20110106'
 '0'          | '1%'      | '1/2W'   | '1206LF'  | 'CHIP'   | 'CS00007F209'(!)        = 'End of Design' | 'Comp-Approve'     | 'CS00007F209'           |'R1206'| '(SMR1206AW)'                  | '0'       | '1%'    | '1/2W'   | 'DISCRETE' | 'RESISTOR CHIP 0 1/2W 1%(1206)'                    | 'CHIP1206'     | ''          | ''            | '20110113'
 '0'          | '1%'      | '1/2W'   | '1206LF'  | 'EMPTY'  | 'CS00007F209'(!)        = 'End of Design' | 'Comp-Approve'     | 'CS00007F209'           |'R1206'| '(SMR1206AW)'                  | '0'       | '1%'    | '1/2W'   | 'IO'       | 'RESISTOR CHIP 0 1/2W 1%(1206)'                    | 'CHIP1206'     | ''          | ''            | '20110113'
 '75'         | '1%'      | '1/8W'   | '0805LF'  | 'CHIP'   | 'CS07504FA11'(!)        = ''              | ''                 | 'CS07504FA11'           |'R0805'| '(SMR0805AW)'                  | '75'      | '1%'    | '1/8W'   | 'DISCRETE' | 'RES CHIP 75 1/8W +-1%(0805)'                      | 'CHIP0805'     | ''          | ''            | '20110113'
 '75'         | '1%'      | '1/8W'   | '0805LF'  | 'EMPTY'  | 'CS07504FA11'(!)        = ''              | ''                 | 'CS07504FA11'           |'R0805'| '(SMR0805AW)'                  | '75'      | '1%'    | '1/8W'   | 'IO'       | 'RES CHIP 75 1/8W +-1%(0805)'                      | 'CHIP0805'     | ''          | ''            | '20110113'
 '118'        | '1%'      | '1/16W'  | '0402LF'  | 'CHIP'   | 'CS11182FB00'(!)        = 'End of Design' | 'Comp-Approve'     | 'CS11182FB00'           |'R0402'| '(R0402-0201)'                 | '118'     | '1%'    | '1/16W'  | 'DISCRETE' | 'RES CHIP 118 1/16W +-1%(0402)'                    | 'CHIP0402'     | ''          | ''            | '20110113'
 '118'        | '1%'      | '1/16W'  | '0402LF'  | 'EMPTY'  | 'CS11182FB00'(!)        = 'End of Design' | 'Comp-Approve'     | 'CS11182FB00'           |'R0402'| '(R0402-0201)'                 | '118'     | '1%'    | '1/16W'  | 'IO'       | 'RES CHIP 118 1/16W +-1%(0402)'                    | 'CHIP0402'     | ''          | ''            | '20110113'
 '140'        | '1%'      | '1/16W'  | '0402LF'  | 'CHIP'   | 'CS11402FB19'(!)        = 'End of Design' | 'Comp-Approve'     | 'CS11402FB19'           |'R0402'| '(R0402-0201)'                 | '140'     | '1%'    | '1/16W'  | 'DISCRETE' | 'RES CHIP 140 1/16W +-1%(0402)'                    | 'CHIP0402'     | ''          | ''            | '20110113'
 '140'        | '1%'      | '1/16W'  | '0402LF'  | 'EMPTY'  | 'CS11402FB19'(!)        = 'End of Design' | 'Comp-Approve'     | 'CS11402FB19'           |'R0402'| '(R0402-0201)'                 | '140'     | '1%'    | '1/16W'  | 'IO'       | 'RES CHIP 140 1/16W +-1%(0402)'                    | 'CHIP0402'     | ''          | ''            | '20110113'
 '4.99M'      | '1%'      | '1/16W'  | '0402LF'  | 'CHIP'   | 'CS54992FB00'(!)        = 'End of Design' | 'Comp-Release Qty' | 'CS54992FB00'           |'R0402'| '(R0402-0201)'                 | '4.99M'   | '1%'    | '1/16W'  | 'DISCRETE' | 'RES CHIP 4.99M 1/16W +-1%(0402)'                  | 'CHIP0402'     | ''          | ''            | '20110113'
 '4.99M'      | '1%'      | '1/16W'  | '0402LF'  | 'EMPTY'  | 'CS54992FB00'(!)        = 'End of Design' | 'Comp-Release Qty' | 'CS54992FB00'           |'R0402'| '(R0402-0201)'                 | '4.99M'   | '1%'    | '1/16W'  | 'IO'       | 'RES CHIP 4.99M 1/16W +-1%(0402)'                  | 'CHIP0402'     | ''          | ''            | '20110113'
 '10M'        | '1%'      | '1/16W'  | '0402LF'  | 'CHIP'   | 'CS61002FB00'(!)        = 'End of Design' | 'Comp-Approve'     | 'CS61002FB00'           |'R0402'| '(R0402-0201)'                 | '10M'     | '1%'    | '1/16W'  | 'DISCRETE' | 'RES CHIP 10M 1/16W +-1%(0402)'                    | 'CHIP0402'     | ''          | ''            | '20110113'
 '10M'        | '1%'      | '1/16W'  | '0402LF'  | 'EMPTY'  | 'CS61002FB00'(!)        = 'End of Design' | 'Comp-Approve'     | 'CS61002FB00'           |'R0402'| '(R0402-0201)'                 | '10M'     | '1%'    | '1/16W'  | 'IO'       | 'RES CHIP 10M 1/16W +-1%(0402)'                    | 'CHIP0402'     | ''          | ''            | '20110113'
 '31.6'       | '1%'      | '1/16W'  | '0402LF'  | 'CHIP'   | 'CS03162FB01'(!)        = ''              | ''                 | 'CS03162FB01'           |'R0402'| '(R0402-0201)'                 | '31.6'    | '1%'    | '1/16W'  | 'DISCRETE' | 'RES CHIP 31.6 1/16W +-1%(0402)'                   | 'CHIP0402'     | ''          | ''            | '20110124'
 '31.6'       | '1%'      | '1/16W'  | '0402LF'  | 'EMPTY'  | 'CS03162FB01'(!)        = ''              | ''                 | 'CS03162FB01'           |'R0402'| '(R0402-0201)'                 | '31.6'    | '1%'    | '1/16W'  | 'IO'       | 'RES CHIP 31.6 1/16W +-1%(0402)'                   | 'CHIP0402'     | ''          | ''            | '20110124'
 '931'        | '1%'      | '1/16W'  | '0402LF'  | 'CHIP'   | 'CS19312FB00'(!)        = 'End of Design' | 'Comp-Approve'     | 'CS19312FB00'           |'R0402'| '(R0402-0201)'                 | '931'     | '1%'    | '1/16W'  | 'DISCRETE' | 'RES CHIP 931 1/16W +-1%(0402)HF'                  | 'CHIP0402'     | ''          | ''            | '20110128'
 '931'        | '1%'      | '1/16W'  | '0402LF'  | 'EMPTY'  | 'CS19312FB00'(!)        = 'End of Design' | 'Comp-Approve'     | 'CS19312FB00'           |'R0402'| '(R0402-0201)'                 | '931'     | '1%'    | '1/16W'  | 'IO'       | 'RES CHIP 931 1/16W +-1%(0402)HF'                  | 'CHIP0402'     | ''          | ''            | '20110128'
 '576'        | '1%'      | '1/16W'  | '0402LF'  | 'CHIP'   | 'CS15762FB26'(!)        = 'End of Design' | 'Comp-Release Qty' | 'CS15762FB26'           |'R0402'| '(R0402-0201)'                 | '576'     | '1%'    | '1/16W'  | 'DISCRETE' | 'RES CHIP 576 1/16W +-1%(0402)'                    | 'CHIP0402'     | ''          | ''            | '20110128'
 '576'        | '1%'      | '1/16W'  | '0402LF'  | 'EMPTY'  | 'CS15762FB26'(!)        = 'End of Design' | 'Comp-Release Qty' | 'CS15762FB26'           |'R0402'| '(R0402-0201)'                 | '576'     | '1%'    | '1/16W'  | 'IO'       | 'RES CHIP 576 1/16W +-1%(0402)'                    | 'CHIP0402'     | ''          | ''            | '20110128'
 '365'        | '1%'      | '1/16W'  | '0402LF'  | 'CHIP'   | 'CS13652FB14'(!)        = 'End of Design' | 'Comp-Approve'     | 'CS13652FB14'           |'R0402'| '(R0402-0201)'                 | '365'     | '1%'    | '1/16W'  | 'DISCRETE' | 'RES CHIP 365 1/16W +-1% (0402)'                   | 'CHIP0402'     | ''          | ''            | '20110128'
 '365'        | '1%'      | '1/16W'  | '0402LF'  | 'EMPTY'  | 'CS13652FB14'(!)        = 'End of Design' | 'Comp-Approve'     | 'CS13652FB14'           |'R0402'| '(R0402-0201)'                 | '365'     | '1%'    | '1/16W'  | 'IO'       | 'RES CHIP 365 1/16W +-1% (0402)'                   | 'CHIP0402'     | ''          | ''            | '20110128'
 '12.4K'      | '1%'      | '1/16W'  | '0402LF'  | 'CHIP'   | 'CS31242FB13'(!)        = 'End of Design' | 'Comp-Approve'     | 'CS31242FB13'           |'R0402'| '(R0402-0201)'                 | '12.4K'   | '1%'    | '1/16W'  | 'DISCRETE' | 'RES CHIP 12.4k 1/16W +-1% (0402)'                 | 'CHIP0402'     | ''          | ''            | '20110215'
 '12.4K'      | '1%'      | '1/16W'  | '0402LF'  | 'EMPTY'  | 'CS31242FB13'(!)        = 'End of Design' | 'Comp-Approve'     | 'CS31242FB13'           |'R0402'| '(R0402-0201)'                 | '12.4K'   | '1%'    | '1/16W'  | 'IO'       | 'RES CHIP 12.4k 1/16W +-1% (0402)'                 | 'CHIP0402'     | ''          | ''            | '20110215'
 '0.001'      | '1%'      | '1W'     | '2512LF'  | 'CHIP'   | 'CS+0018F111'(!)        = 'End of Design' | 'Comp-Approve'     | 'CS+0018F111'           |'R2512XE'| '(SMR2512AW)'                  | '0.001'   | '1%'    | '1W'     | 'DISCRETE' | 'RES CHIP 0.001 1W +-1% (2512)'                    | 'CHIP2512'     | ''          | ''            | '20110405'
 '0.001'      | '1%'      | '1W'     | '2512LF'  | 'EMPTY'  | 'CS+0018F111'(!)        = 'End of Design' | 'Comp-Approve'     | 'CS+0018F111'           |'R2512XE'| '(SMR2512AW)'                  | '0.001'   | '1%'    | '1W'     | 'IO'       | 'RES CHIP 0.001 1W +-1% (2512)'                    | 'CHIP2512'     | ''          | ''            | '20110405'
 '49.9'       | '1%'      | '1/8W'   | '0805LF'  | 'CHIP'   | 'CS04994FA00'(!)        = ''              | ''                 | 'CS04994FA00'           |'R0805'| '(SMR0805AW)'                  | '49.9'    | '1%'    | '1/8W'   | 'DISCRETE' | 'RES CHIP 49.9 1/8W +-1% (0805)'                   | 'CHIP0805'     | ''          | ''            | '20110221'
 '49.9'       | '1%'      | '1/8W'   | '0805LF'  | 'EMPTY'  | 'CS04994FA00'(!)        = ''              | ''                 | 'CS04994FA00'           |'R0805'| '(SMR0805AW)'                  | '49.9'    | '1%'    | '1/8W'   | 'IO'       | 'RES CHIP 49.9 1/8W +-1% (0805)'                   | 'CHIP0805'     | ''          | ''            | '20110221'
 '10'         | '1%'      | '1/10W'  | '0603LF'  | 'CHIP'   | 'CS01003F935'(!)        = ''              | ''                 | 'CS01003F935'           |'R0603'| '(SMR0603AW)'                  | '10'      | '1%'    | '1/10W'  | 'DISCRETE' | 'RES CHIP 10 1/10W +-1% (0603)'                    | 'CHIP0603'     | ''          | ''            | '20110221'
 '10'         | '1%'      | '1/10W'  | '0603LF'  | 'EMPTY'  | 'CS01003F935'(!)        = ''              | ''                 | 'CS01003F935'           |'R0603'| '(SMR0603AW)'                  | '10'      | '1%'    | '1/10W'  | 'IO'       | 'RES CHIP 10 1/10W +-1% (0603)'                    | 'CHIP0603'     | ''          | ''            | '20110221'
 '0.402'      | '1%'      | '1/10W'  | '0603LF'  | 'CHIP'   | 'CS+4023F900'(!)        = ''              | ''                 | 'CS+4023F900'           |'R0603'| '(SMR0603AW)'                  | '0.402'   | '1%'    | '1/10W'  | 'DISCRETE' | 'RES CHIP 0.402 1/10W +-1%(0603)'                  | 'CHIP0603'     | ''          | ''            | '20110302'
 '0.402'      | '1%'      | '1/10W'  | '0603LF'  | 'EMPTY'  | 'CS+4023F900'(!)        = ''              | ''                 | 'CS+4023F900'           |'R0603'| '(SMR0603AW)'                  | '0.402'   | '1%'    | '1/10W'  | 'IO'       | 'RES CHIP 0.402 1/10W +-1%(0603)'                  | 'CHIP0603'     | ''          | ''            | '20110302'
 '0.1'        | '1%'      | '1/10W'  | '0603LF'  | 'CHIP'   | 'CS+1003F900'(!)        = ''              | ''                 | 'CS+1003F900'           |'R0603'| '(SMR0603AW)'                  | '0.1'     | '1%'    | '1/10W'  | 'DISCRETE' | 'RES CHIP 0.1 1/10W +-1%(0603)'                    | 'CHIP0603'     | ''          | ''            | '20110302'
 '0.1'        | '1%'      | '1/10W'  | '0603LF'  | 'EMPTY'  | 'CS+1003F900'(!)        = ''              | ''                 | 'CS+1003F900'           |'R0603'| '(SMR0603AW)'                  | '0.1'     | '1%'    | '1/10W'  | 'IO'       | 'RES CHIP 0.1 1/10W +-1%(0603)'                    | 'CHIP0603'     | ''          | ''            | '20110302'
 '270'        | '1%'      | '1/16W'  | '0402LF'  | 'CHIP'   | 'CS12702FB12'(!)        = 'End of Design' | 'Comp-Approve'     | 'CS12702FB12'           |'R0402'| '(R0402-0201)'                 | '270'     | '1%'    | '1/16W'  | 'DISCRETE' | 'RES CHIP 270 1/16W +-1%(0402)'                    | 'CHIP0402'     | ''          | ''            | '20110303'
 '270'        | '1%'      | '1/16W'  | '0402LF'  | 'EMPTY'  | 'CS12702FB12'(!)        = 'End of Design' | 'Comp-Approve'     | 'CS12702FB12'           |'R0402'| '(R0402-0201)'                 | '270'     | '1%'    | '1/16W'  | 'IO'       | 'RES CHIP 270 1/16W +-1%(0402)'                    | 'CHIP0402'     | ''          | ''            | '20110303'
 '0.05'       | '1%'      | '1W'     | '2512LF'  | 'CHIP'   | 'CS+0508FR00'(!)        = ''              | ''                 | 'CS+0508FR00'           |'R2512XB'| '(SMR2512AW)'                  | '0.05'    | '1%'    | '1W'     | 'DISCRETE' | 'RES CHIP 0.05 1W +-1% (2512)'                     | 'CHIP2512'     | ''          | ''            | '20110304'
 '0.05'       | '1%'      | '1W'     | '2512LF'  | 'EMPTY'  | 'CS+0508FR00'(!)        = ''              | ''                 | 'CS+0508FR00'           |'R2512XB'| '(SMR2512AW)'                  | '0.05'    | '1%'    | '1W'     | 'IO'       | 'RES CHIP 0.05 1W +-1% (2512)'                     | 'CHIP2512'     | ''          | ''            | '20110304'
 '0.05'       | '1%'      | '1W'     | '3720LF'  | 'CHIP'   | 'CS+0508FL11'(!)        = ''              | ''                 | 'CS+0508FL11'           |'R3720'| '(SMR3720AW)'                  | '0.05'    | '1%'    | '1W'     | 'DISCRETE' | 'RES CHIP 0.05 1W +-1%(3720)'                      | 'CHIP3720'     | ''          | ''            | '20110304'
 '0.05'       | '1%'      | '1W'     | '3720LF'  | 'EMPTY'  | 'CS+0508FL11'(!)        = ''              | ''                 | 'CS+0508FL11'           |'R3720'| '(SMR3720AW)'                  | '0.05'    | '1%'    | '1W'     | 'IO'       | 'RES CHIP 0.05 1W +-1%(3720)'                      | 'CHIP3720'     | ''          | ''            | '20110304'
 '523'        | '1%'      | '1/16W'  | '0402LF'  | 'CHIP'   | 'CS15232FB00'(!)        = 'End of Design' | 'Comp-Approve'     | 'CS15232FB00'           |'R0402'| '(R0402-0201)'                 | '523'     | '1%'    | '1/16W'  | 'DISCRETE' | 'RES CHIP 523 1/16W +-1%(0402)'                    | 'CHIP0402'     | ''          | ''            | '20110308'
 '523'        | '1%'      | '1/16W'  | '0402LF'  | 'EMPTY'  | 'CS15232FB00'(!)        = 'End of Design' | 'Comp-Approve'     | 'CS15232FB00'           |'R0402'| '(R0402-0201)'                 | '523'     | '1%'    | '1/16W'  | 'IO'       | 'RES CHIP 523 1/16W +-1%(0402)'                    | 'CHIP0402'     | ''          | ''            | '20110308'
 '19.6K'      | '1%'      | '1/16W'  | '0402LF'  | 'CHIP'   | 'CS31962FB18'(!)        = 'End of Design' | 'Comp-Approve'     | 'CS31962FB18'           |'R0402'| '(R0402-0201)'                 | '19.6K'   | '1%'    | '1/16W'  | 'DISCRETE' | 'RES CHIP 19.6K 1/16W +-1% (0402)'                 | 'CHIP0402'     | ''          | ''            | '20110308'
 '19.6K'      | '1%'      | '1/16W'  | '0402LF'  | 'EMPTY'  | 'CS31962FB18'(!)        = 'End of Design' | 'Comp-Approve'     | 'CS31962FB18'           |'R0402'| '(R0402-0201)'                 | '19.6K'   | '1%'    | '1/16W'  | 'IO'       | 'RES CHIP 19.6K 1/16W +-1% (0402)'                 | 'CHIP0402'     | ''          | ''            | '20110308'
 '46.4K'      | '1%'      | '1/16W'  | '0402LF'  | 'CHIP'   | 'CS34642FB16'(!)        = 'End of Design' | 'Comp-Approve'     | 'CS34642FB16'           |'R0402'| '(R0402-0201)'                 | '46.4K'   | '1%'    | '1/16W'  | 'DISCRETE' | 'RES CHIP 46.4K 1/16W +-1%(0402)'                  | 'CHIP0402'     | ''          | ''            | '20110314'
 '46.4K'      | '1%'      | '1/16W'  | '0402LF'  | 'EMPTY'  | 'CS34642FB16'(!)        = 'End of Design' | 'Comp-Approve'     | 'CS34642FB16'           |'R0402'| '(R0402-0201)'                 | '46.4K'   | '1%'    | '1/16W'  | 'IO'       | 'RES CHIP 46.4K 1/16W +-1%(0402)'                  | 'CHIP0402'     | ''          | ''            | '20110314'
 '43K'        | '1%'      | '1/16W'  | '0402LF'  | 'CHIP'   | 'CS34302FB17'(!)        = 'End of Design' | 'Comp-Approve'     | 'CS34302FB17'           |'R0402'| '(R0402-0201)'                 | '43K'     | '1%'    | '1/16W'  | 'DISCRETE' | 'RES CHIP 43K 1/16W +-1% (0402)'                   | 'CHIP0402'     | ''          | ''            | '20110316'
 '43K'        | '1%'      | '1/16W'  | '0402LF'  | 'EMPTY'  | 'CS34302FB17'(!)        = 'End of Design' | 'Comp-Approve'     | 'CS34302FB17'           |'R0402'| '(R0402-0201)'                 | '43K'     | '1%'    | '1/16W'  | 'IO'       | 'RES CHIP 43K 1/16W +-1% (0402)'                   | 'CHIP0402'     | ''          | ''            | '20110316'
 '1.2K'       | '1%'      | '1/10W'  | '0603LF'  | 'CHIP'   | 'CS21203F910'(!)        = 'End of Design' | 'Comp-Approve'     | 'CS21203F910'           |'R0603'| '(SMR0603AW)'                  | '1.2K'    | '1%'    | '1/10W'  | 'DISCRETE' | 'RES CHIP 1.2K 1/10W +-1%(0603)'                   | 'CHIP0603'     | ''          | ''            | '20110316'
 '1.2K'       | '1%'      | '1/10W'  | '0603LF'  | 'EMPTY'  | 'CS21203F910'(!)        = 'End of Design' | 'Comp-Approve'     | 'CS21203F910'           |'R0603'| '(SMR0603AW)'                  | '1.2K'    | '1%'    | '1/10W'  | 'IO'       | 'RES CHIP 1.2K 1/10W +-1%(0603)'                   | 'CHIP0603'     | ''          | ''            | '20110316'
 '680'        | '1%'      | '1/10W'  | '0603LF'  | 'CHIP'   | 'CS16803F913'(!)        = 'End of Design' | 'Comp-Approve'     | 'CS16803F913'           |'R0603'| '(SMR0603AW)'                  | '680'     | '1%'    | '1/10W'  | 'DISCRETE' | 'RES CHIP 680 1/10W +-1%(0603)'                    | 'CHIP0603'     | ''          | ''            | '20110317'
 '680'        | '1%'      | '1/10W'  | '0603LF'  | 'EMPTY'  | 'CS16803F913'(!)        = 'End of Design' | 'Comp-Approve'     | 'CS16803F913'           |'R0603'| '(SMR0603AW)'                  | '680'     | '1%'    | '1/10W'  | 'IO'       | 'RES CHIP 680 1/10W +-1%(0603)'                    | 'CHIP0603'     | ''          | ''            | '20110317'
 '150K'       | '5%'      | '1/16W'  | '0402LF'  | 'CHIP'   | 'CS41502JB10'(!)        = 'End of Design' | 'Comp-Approve'     | 'CS41502JB10'           |'R0402'| '(R0402-0201)'                 | '150K'    | '5%'    | '1/16W'  | 'DISCRETE' | 'RES CHIP 150K 1/16W+-5%(0402)'                    | 'CHIP0402'     | ''          | ''            | '20110321'
 '150K'       | '5%'      | '1/16W'  | '0402LF'  | 'EMPTY'  | 'CS41502JB10'(!)        = 'End of Design' | 'Comp-Approve'     | 'CS41502JB10'           |'R0402'| '(R0402-0201)'                 | '150K'    | '5%'    | '1/16W'  | 'IO'       | 'RES CHIP 150K 1/16W+-5%(0402)'                    | 'CHIP0402'     | ''          | ''            | '20110321'
 '124K'       | '1%'      | '1/16W'  | '0402LF'  | 'CHIP'   | 'CS41242FB15'(!)        = 'End of Design' | 'Comp-Approve'     | 'CS41242FB15'           |'R0402'| '(R0402-0201)'                 | '124K'    | '1%'    | '1/16W'  | 'DISCRETE' | 'RES CHIP 124K 1/16W +-1%( 0402)'                  | 'CHIP0402'     | ''          | ''            | '20110328'
 '124K'       | '1%'      | '1/16W'  | '0402LF'  | 'EMPTY'  | 'CS41242FB15'(!)        = 'End of Design' | 'Comp-Approve'     | 'CS41242FB15'           |'R0402'| '(R0402-0201)'                 | '124K'    | '1%'    | '1/16W'  | 'IO'       | 'RES CHIP 124K 1/16W +-1%( 0402)'                  | 'CHIP0402'     | ''          | ''            | '20110328'
 '180'        | '1%'      | '1/16W'  | '0402LF'  | 'CHIP'   | 'CS11802FB13'(!)        = 'End of Design' | 'Comp-Approve'     | 'CS11802FB13'           |'R0402'| '(R0402-0201)'                 | '180'     | '1%'    | '1/16W'  | 'DISCRETE' | 'RES CHIP 180 1/16W +-1% (0402)'                   | 'CHIP0402'     | ''          | ''            | '20110331'
 '180'        | '1%'      | '1/16W'  | '0402LF'  | 'EMPTY'  | 'CS11802FB13'(!)        = 'End of Design' | 'Comp-Approve'     | 'CS11802FB13'           |'R0402'| '(R0402-0201)'                 | '180'     | '1%'    | '1/16W'  | 'IO'       | 'RES CHIP 180 1/16W +-1% (0402)'                   | 'CHIP0402'     | ''          | ''            | '20110331'
 '8.25K'      | '1%'      | '1/16W'  | '0402LF'  | 'CHIP'   | 'CS28252FB15'(!)        = 'End of Design' | 'Comp-Approve'     | 'CS28252FB15'           |'R0402'| '(R0402-0201)'                 | '8.25K'   | '1%'    | '1/16W'  | 'DISCRETE' | 'RESISTOR CHIP 8.25K 1/16W+-1%(0402)'              | 'CHIP0402'     | ''          | ''            | '20110331'
 '8.25K'      | '1%'      | '1/16W'  | '0402LF'  | 'EMPTY'  | 'CS28252FB15'(!)        = 'End of Design' | 'Comp-Approve'     | 'CS28252FB15'           |'R0402'| '(R0402-0201)'                 | '8.25K'   | '1%'    | '1/16W'  | 'IO'       | 'RESISTOR CHIP 8.25K 1/16W+-1%(0402)'              | 'CHIP0402'     | ''          | ''            | '20110331'
 '3.9K'       | '1%'      | '1/16W'  | '0402LF'  | 'CHIP'   | 'CS23902FB14'(!)        = 'End of Design' | 'Comp-Approve'     | 'CS23902FB14'           |'R0402'| '(R0402-0201)'                 | '3.9K'    | '1%'    | '1/16W'  | 'DISCRETE' | 'RES CHIP 3.9K 1/16W+-1%(0402)'                    | 'CHIP0402'     | ''          | ''            | '20110331'
 '3.9K'       | '1%'      | '1/16W'  | '0402LF'  | 'EMPTY'  | 'CS23902FB14'(!)        = 'End of Design' | 'Comp-Approve'     | 'CS23902FB14'           |'R0402'| '(R0402-0201)'                 | '3.9K'    | '1%'    | '1/16W'  | 'IO'       | 'RES CHIP 3.9K 1/16W+-1%(0402)'                    | 'CHIP0402'     | ''          | ''            | '20110331'
 '1.6K'       | '1%'      | '1/16W'  | '0402LF'  | 'CHIP'   | 'CS21602FB00'(!)        = 'End of Design' | 'Comp-Approve'     | 'CS21602FB00'           |'R0402'| '(R0402-0201)'                 | '1.6K'    | '1%'    | '1/16W'  | 'DISCRETE' | 'RES CHIP 1.6K(1/16W.+-1%.0402)'                   | 'CHIP0402'     | ''          | ''            | '20110331'
 '1.6K'       | '1%'      | '1/16W'  | '0402LF'  | 'EMPTY'  | 'CS21602FB00'(!)        = 'End of Design' | 'Comp-Approve'     | 'CS21602FB00'           |'R0402'| '(R0402-0201)'                 | '1.6K'    | '1%'    | '1/16W'  | 'IO'       | 'RES CHIP 1.6K(1/16W.+-1%.0402)'                   | 'CHIP0402'     | ''          | ''            | '20110331'
 '56.2K'      | '1%'      | '1/16W'  | '0402LF'  | 'CHIP'   | 'CS35622FB10'(!)        = 'End of Design' | 'Comp-Approve'     | 'CS35622FB10'           |'R0402'| '(R0402-0201)'                 | '56.2K'   | '1%'    | '1/16W'  | 'DISCRETE' | 'RES CHIP 56.2K 1/16W +-1% (0402)'                 | 'CHIP0402'     | ''          | ''            | '20110407'
 '56.2K'      | '1%'      | '1/16W'  | '0402LF'  | 'EMPTY'  | 'CS35622FB10'(!)        = 'End of Design' | 'Comp-Approve'     | 'CS35622FB10'           |'R0402'| '(R0402-0201)'                 | '56.2K'   | '1%'    | '1/16W'  | 'IO'       | 'RES CHIP 56.2K 1/16W +-1% (0402)'                 | 'CHIP0402'     | ''          | ''            | '20110407'
 '71.5K'      | '1%'      | '1/16W'  | '0402LF'  | 'CHIP'   | 'CS37152FB11'(!)        = 'End of Design' | 'Comp-Approve'     | 'CS37152FB11'           |'R0402'| '(R0402-0201)'                 | '71.5K'   | '1%'    | '1/16W'  | 'DISCRETE' | 'RES CHIP 71.5K 1/16W +-1%(0402)'                  | 'CHIP0402'     | ''          | ''            | '20110411'
 '71.5K'      | '1%'      | '1/16W'  | '0402LF'  | 'EMPTY'  | 'CS37152FB11'(!)        = 'End of Design' | 'Comp-Approve'     | 'CS37152FB11'           |'R0402'| '(R0402-0201)'                 | '71.5K'   | '1%'    | '1/16W'  | 'IO'       | 'RES CHIP 71.5K 1/16W +-1%(0402)'                  | 'CHIP0402'     | ''          | ''            | '20110411'
 '2.0M'       | '1%'      | '1/10W'  | '0603LF'  | 'CHIP'   | 'CS52003F911'(!)        = 'End of Design' | 'Comp-Approve'     | 'CS52003F911'           |'R0603'| '(SMR0603AW)'                  | '2.0M'    | '1%'    | '1/10W'  | 'DISCRETE' | 'RESISTOR CHIP 2M 1/10W +-1%(0603)'                | 'CHIP0603'     | ''          | ''            | '20110411'
 '2.0M'       | '1%'      | '1/10W'  | '0603LF'  | 'EMPTY'  | 'CS52003F911'(!)        = 'End of Design' | 'Comp-Approve'     | 'CS52003F911'           |'R0603'| '(SMR0603AW)'                  | '2.0M'    | '1%'    | '1/10W'  | 'IO'       | 'RESISTOR CHIP 2M 1/10W +-1%(0603)'                | 'CHIP0603'     | ''          | ''            | '20110411'
 '4.7M'       | '1%'      | '1/10W'  | '0603LF'  | 'CHIP'   | 'CS54703F903'(!)        = 'End of Design' | 'Comp-Approve'     | 'CS54703F903'           |'R0603'| '(SMR0603AW)'                  | '4.7M'    | '1%'    | '1/10W'  | 'DISCRETE' | 'RES CHIP 4.7M 1/10W +-1%(0603)'                   | 'CHIP0603'     | ''          | ''            | '20110411'
 '4.7M'       | '1%'      | '1/10W'  | '0603LF'  | 'EMPTY'  | 'CS54703F903'(!)        = 'End of Design' | 'Comp-Approve'     | 'CS54703F903'           |'R0603'| '(SMR0603AW)'                  | '4.7M'    | '1%'    | '1/10W'  | 'IO'       | 'RES CHIP 4.7M 1/10W +-1%(0603)'                   | 'CHIP0603'     | ''          | ''            | '20110411'
 '15.4K'      | '1%'      | '1/16W'  | '0402LF'  | 'CHIP'   | 'CS31542FB14'(!)        = 'End of Design' | 'Comp-Approve'     | 'CS31542FB14'           |'R0402'| '(R0402-0201)'                 | '15.4K'   | '1%'    | '1/16W'  | 'DISCRETE' | 'RES CHIP 15.4K 1/16W +-1%(0402)'                  | 'CHIP0402'     | ''          | ''            | '20110411'
 '15.4K'      | '1%'      | '1/16W'  | '0402LF'  | 'EMPTY'  | 'CS31542FB14'(!)        = 'End of Design' | 'Comp-Approve'     | 'CS31542FB14'           |'R0402'| '(R0402-0201)'                 | '15.4K'   | '1%'    | '1/16W'  | 'IO'       | 'RES CHIP 15.4K 1/16W +-1%(0402)'                  | 'CHIP0402'     | ''          | ''            | '20110411'
 '49.9'       | '1%'      | '1/10W'  | '0603LF'  | 'CHIP'   | 'CS04993F953'(!)        = ''              | ''                 | 'CS04993F953'           |'R0603'| '(SMR0603AW)'                  | '49.9'    | '1%'    | '1/10W'  | 'DISCRETE' | 'RESISTOR CHIP 49.9 1/10W +-1%(1608) '             | 'CHIP0603'     | ''          | ''            | '20110419'
 '49.9'       | '1%'      | '1/10W'  | '0603LF'  | 'EMPTY'  | 'CS04993F953'(!)        = ''              | ''                 | 'CS04993F953'           |'R0603'| '(SMR0603AW)'                  | '49.9'    | '1%'    | '1/10W'  | 'IO'       | 'RESISTOR CHIP 49.9 1/10W +-1%(1608) '             | 'CHIP0603'     | ''          | ''            | '20110419'
 '35.7K'      | '1%'      | '1/16W'  | '0402LF'  | 'CHIP'   | 'CS33572FB13'(!)        = 'End of Design' | 'Comp-Approve'     | 'CS33572FB13'           |'R0402'| '(R0402-0201)'                 | '35.7K'   | '1%'    | '1/16W'  | 'DISCRETE' | 'RES CHIP 35.7K 1/16W +-1%(0402)'                  | 'CHIP0402'     | ''          | ''            | '20110420'
 '35.7K'      | '1%'      | '1/16W'  | '0402LF'  | 'EMPTY'  | 'CS33572FB13'(!)        = 'End of Design' | 'Comp-Approve'     | 'CS33572FB13'           |'R0402'| '(R0402-0201)'                 | '35.7K'   | '1%'    | '1/16W'  | 'IO'       | 'RES CHIP 35.7K 1/16W +-1%(0402)'                  | 'CHIP0402'     | ''          | ''            | '20110420'
 '24.3K'      | '1%'      | '1/16W'  | '0402LF'  | 'CHIP'   | 'CS32432FB19'(!)        = 'End of Design' | 'Comp-Approve'     | 'CS32432FB19'           |'R0402'| '(R0402-0201)'                 | '24.3K'   | '1%'    | '1/16W'  | 'DISCRETE' | 'RES CHIP 24.3K 1/16W +-1%(0402)'                  | 'CHIP0402'     | ''          | ''            | '20110420'
 '24.3K'      | '1%'      | '1/16W'  | '0402LF'  | 'EMPTY'  | 'CS32432FB19'(!)        = 'End of Design' | 'Comp-Approve'     | 'CS32432FB19'           |'R0402'| '(R0402-0201)'                 | '24.3K'   | '1%'    | '1/16W'  | 'IO'       | 'RES CHIP 24.3K 1/16W +-1%(0402)'                  | 'CHIP0402'     | ''          | ''            | '20110420'
 '25.5K'      | '1%'      | '1/16W'  | '0402LF'  | 'CHIP'   | 'CS32552FB11'(!)        = 'End of Design' | 'Comp-Approve'     | 'CS32552FB11'           |'R0402'| '(R0402-0201)'                 | '25.5K'   | '1%'    | '1/16W'  | 'DISCRETE' | 'RES CHIP 25.5K 1/16W +-1%(0402)'                  | 'CHIP0402'     | ''          | ''            | '20110420'
 '25.5K'      | '1%'      | '1/16W'  | '0402LF'  | 'EMPTY'  | 'CS32552FB11'(!)        = 'End of Design' | 'Comp-Approve'     | 'CS32552FB11'           |'R0402'| '(R0402-0201)'                 | '25.5K'   | '1%'    | '1/16W'  | 'IO'       | 'RES CHIP 25.5K 1/16W +-1%(0402)'                  | 'CHIP0402'     | ''          | ''            | '20110420'
 '60.4K'      | '1%'      | '1/16W'  | '0402LF'  | 'CHIP'   | 'CS36042FB10'(!)        = 'End of Design' | 'Comp-Approve'     | 'CS36042FB10'           |'R0402'| '(R0402-0201)'                 | '60.4K'   | '1%'    | '1/16W'  | 'DISCRETE' | 'RES CHIP 60.4K 1/16W +-1%(0402)'                  | 'CHIP0402'     | ''          | ''            | '20110531'
 '60.4K'      | '1%'      | '1/16W'  | '0402LF'  | 'EMPTY'  | 'CS36042FB10'(!)        = 'End of Design' | 'Comp-Approve'     | 'CS36042FB10'           |'R0402'| '(R0402-0201)'                 | '60.4K'   | '1%'    | '1/16W'  | 'IO'       | 'RES CHIP 60.4K 1/16W +-1%(0402)'                  | 'CHIP0402'     | ''          | ''            | '20110531'
 '39.2K'      | '1%'      | '1/16W'  | '0402LF'  | 'CHIP'   | 'CS33922FB15'(!)        = 'End of Design' | 'Comp-Approve'     | 'CS33922FB15'           |'R0402'| '(R0402-0201)'                 | '39.2K'   | '1%'    | '1/16W'  | 'DISCRETE' | 'RES CHIP 39.2K 1/16W +-1%(0402)'                  | 'CHIP0402'     | ''          | ''            | '20110531'
 '39.2K'      | '1%'      | '1/16W'  | '0402LF'  | 'EMPTY'  | 'CS33922FB15'(!)        = 'End of Design' | 'Comp-Approve'     | 'CS33922FB15'           |'R0402'| '(R0402-0201)'                 | '39.2K'   | '1%'    | '1/16W'  | 'IO'       | 'RES CHIP 39.2K 1/16W +-1%(0402)'                  | 'CHIP0402'     | ''          | ''            | '20110531'
 '1.18K'      | '1%'      | '1/16W'  | '0402LF'  | 'CHIP'   | 'CS21182FB08'(!)        = 'End of Design' | 'Comp-Approve'     | 'CS21182FB08'           |'R0402'| '(R0402-0201)'                 | '1.18K'   | '1%'    | '1/16W'  | 'DISCRETE' | 'RES CHIP 1.18K 1/16W +-1%(0402)'                  | 'CHIP0402'     | ''          | ''            | '20110601'
 '1.18K'      | '1%'      | '1/16W'  | '0402LF'  | 'EMPTY'  | 'CS21182FB08'(!)        = 'End of Design' | 'Comp-Approve'     | 'CS21182FB08'           |'R0402'| '(R0402-0201)'                 | '1.18K'   | '1%'    | '1/16W'  | 'IO'       | 'RES CHIP 1.18K 1/16W +-1%(0402)'                  | 'CHIP0402'     | ''          | ''            | '20110601'
 '4.22K'      | '1%'      | '1/16W'  | '0402LF'  | 'CHIP'   | 'CS24222FB11'(!)        = 'End of Design' | 'Comp-Approve'     | 'CS24222FB11'           |'R0402'| '(R0402-0201)'                 | '4.22K'   | '1%'    | '1/16W'  | 'DISCRETE' | 'RES CHIP 4.22K 1/16W +-1%(0402)'                  | 'CHIP0402'     | ''          | ''            | '20110601'
 '4.22K'      | '1%'      | '1/16W'  | '0402LF'  | 'EMPTY'  | 'CS24222FB11'(!)        = 'End of Design' | 'Comp-Approve'     | 'CS24222FB11'           |'R0402'| '(R0402-0201)'                 | '4.22K'   | '1%'    | '1/16W'  | 'IO'       | 'RES CHIP 4.22K 1/16W +-1%(0402)'                  | 'CHIP0402'     | ''          | ''            | '20110601'
 '2'          | '1%'      | '1/10W'  | '0603LF'  | 'CHIP'   | 'CS-2003F900'(!)        = ''              | ''                 | 'CS-2003F900'           |'R0603'| '(SMR0603AW)'                  | '2'       | '1%'    | '1/10W'  | 'DISCRETE' | 'RES CHIP 2 1/10W +-1%(0603)'                      | 'CHIP0603'     | ''          | ''            | '20110624'
 '2'          | '1%'      | '1/10W'  | '0603LF'  | 'EMPTY'  | 'CS-2003F900'(!)        = ''              | ''                 | 'CS-2003F900'           |'R0603'| '(SMR0603AW)'                  | '2'       | '1%'    | '1/10W'  | 'IO'       | 'RES CHIP 2 1/10W +-1%(0603)'                      | 'CHIP0603'     | ''          | ''            | '20110624'
 '29.4K'      | '1%'      | '1/16W'  | '0402LF'  | 'CHIP'   | 'CS32942FB03'(!)        = 'End of Design' | 'Comp-Approve'     | 'CS32942FB03'           |'R0402'| '(R0402-0201)'                 | '29.4K'   | '1%'    | '1/16W'  | 'DISCRETE' | 'RES CHIP 29.4K 1/16W +-1%(0402)'                  | 'CHIP0402'     | ''          | ''            | '20110725'
 '29.4K'      | '1%'      | '1/16W'  | '0402LF'  | 'EMPTY'  | 'CS32942FB03'(!)        = 'End of Design' | 'Comp-Approve'     | 'CS32942FB03'           |'R0402'| '(R0402-0201)'                 | '29.4K'   | '1%'    | '1/16W'  | 'IO'       | 'RES CHIP 29.4K 1/16W +-1%(0402)'                  | 'CHIP0402'     | ''          | ''            | '20110725'
 '22.6K'      | '1%'      | '1/16W'  | '0402LF'  | 'CHIP'   | 'CS32262FB15'(!)        = 'End of Design' | 'Comp-Approve'     | 'CS32262FB15'           |'R0402'| '(R0402-0201)'                 | '22.6K'   | '1%'    | '1/16W'  | 'DISCRETE' | 'RES CHIP 22.6K 1/16W +-1%(0402)'                  | 'CHIP0402'     | ''          | ''            | '20110725'
 '22.6K'      | '1%'      | '1/16W'  | '0402LF'  | 'EMPTY'  | 'CS32262FB15'(!)        = 'End of Design' | 'Comp-Approve'     | 'CS32262FB15'           |'R0402'| '(R0402-0201)'                 | '22.6K'   | '1%'    | '1/16W'  | 'IO'       | 'RES CHIP 22.6K 1/16W +-1%(0402)'                  | 'CHIP0402'     | ''          | ''            | '20110725'
 '383'        | '1%'      | '1/16W'  | '0402LF'  | 'CHIP'   | 'CS13832FB00'(!)        = 'End of Design' | 'Comp-Approve'     | 'CS13832FB00'           |'R0402'| '(R0402-0201)'                 | '383'     | '1%'    | '1/16W'  | 'DISCRETE' | 'RES CHIP 383 1/16W +-1%(0402)'                    | 'CHIP0402'     | ''          | ''            | '20110725'
 '383'        | '1%'      | '1/16W'  | '0402LF'  | 'EMPTY'  | 'CS13832FB00'(!)        = 'End of Design' | 'Comp-Approve'     | 'CS13832FB00'           |'R0402'| '(R0402-0201)'                 | '383'     | '1%'    | '1/16W'  | 'IO'       | 'RES CHIP 383 1/16W +-1%(0402)'                    | 'CHIP0402'     | ''          | ''            | '20110725'
 '2.2'        | '1%'      | '1/16W'  | '0402LF'  | 'CHIP'   | 'CS-2202FB00'(!)        = 'End of Design' | 'Comp-Approve'     | 'CS-2202FB00'           |'R0402'| '(R0402-0201)'                 | '2.2'     | '1%'    | '1/16W'  | 'DISCRETE' | 'RES CHIP 2.2 1/16W +-1% (0402)'                   | 'CHIP0402'     | ''          | ''            | '20110725'
 '2.2'        | '1%'      | '1/16W'  | '0402LF'  | 'EMPTY'  | 'CS-2202FB00'(!)        = 'End of Design' | 'Comp-Approve'     | 'CS-2202FB00'           |'R0402'| '(R0402-0201)'                 | '2.2'     | '1%'    | '1/16W'  | 'IO'       | 'RES CHIP 2.2 1/16W +-1% (0402)'                   | 'CHIP0402'     | ''          | ''            | '20110725'
 '1.13k'      | '1%'      | '1/16W'  | '0402LF'  | 'CHIP'   | 'CS21132FB13'(!)        = ''              | ''                 | 'CS21132FB13'           |'R0402'| '(R0402-0201)'                 | '1.13k'   | '1%'    | '1/16W'  | 'DISCRETE' | 'RES CHIP 1.13K 1/16W +-1%(0402)'                  | 'CHIP0402'     | ''          | ''            | '20110725'
 '1.13k'      | '1%'      | '1/16W'  | '0402LF'  | 'EMPTY'  | 'CS21132FB13'(!)        = ''              | ''                 | 'CS21132FB13'           |'R0402'| '(R0402-0201)'                 | '1.13k'   | '1%'    | '1/16W'  | 'IO'       | 'RES CHIP 1.13K 1/16W +-1%(0402)'                  | 'CHIP0402'     | ''          | ''            | '20110725'
 '38.3K'      | '1%'      | '1/16W'  | '0402LF'  | 'CHIP'   | 'CS33832FB08'(!)        = 'End of Design' | 'Comp-Approve'     | 'CS33832FB08'           |'R0402'| '(R0402-0201)'                 | '38.3K'   | '1%'    | '1/16W'  | 'DISCRETE' | 'RES CHIP 38.3K 1/16W +-1% (0402)'                 | 'CHIP0402'     | ''          | ''            | '20110725'
 '38.3K'      | '1%'      | '1/16W'  | '0402LF'  | 'EMPTY'  | 'CS33832FB08'(!)        = 'End of Design' | 'Comp-Approve'     | 'CS33832FB08'           |'R0402'| '(R0402-0201)'                 | '38.3K'   | '1%'    | '1/16W'  | 'IO'       | 'RES CHIP 38.3K 1/16W +-1% (0402)'                 | 'CHIP0402'     | ''          | ''            | '20110725'
 '4.12K'      | '1%'      | '1/16W'  | '0402LF'  | 'CHIP'   | 'CS24122FB17'(!)        = 'End of Design' | 'Comp-Approve'     | 'CS24122FB17'           |'R0402'| '(R0402-0201)'                 | '4.12K'   | '1%'    | '1/16W'  | 'DISCRETE' | 'RES CHIP 4.12K 1/16W +-1%(0402)'                  | 'CHIP0402'     | ''          | ''            | '20110805'
 '4.12K'      | '1%'      | '1/16W'  | '0402LF'  | 'EMPTY'  | 'CS24122FB17'(!)        = 'End of Design' | 'Comp-Approve'     | 'CS24122FB17'           |'R0402'| '(R0402-0201)'                 | '4.12K'   | '1%'    | '1/16W'  | 'IO'       | 'RES CHIP 4.12K 1/16W +-1%(0402)'                  | 'CHIP0402'     | ''          | ''            | '20110805'
 '1.91K'      | '1%'      | '1/16W'  | '0402LF'  | 'CHIP'   | 'CS21912FB05'(!)        = ''              | ''                 | 'CS21912FB05'           |'R0402'| '(R0402-0201)'                 | '1.91K'   | '1%'    | '1/16W'  | 'DISCRETE' | 'RES CHIP 1.91K 1/16W +-1%(0402)'                  | 'CHIP0402'     | ''          | ''            | '20110810'
 '1.91K'      | '1%'      | '1/16W'  | '0402LF'  | 'EMPTY'  | 'CS21912FB05'(!)        = ''              | ''                 | 'CS21912FB05'           |'R0402'| '(R0402-0201)'                 | '1.91K'   | '1%'    | '1/16W'  | 'IO'       | 'RES CHIP 1.91K 1/16W +-1%(0402)'                  | 'CHIP0402'     | ''          | ''            | '20110810'
 '88.7K'      | '1%'      | '1/16W'  | '0402LF'  | 'CHIP'   | 'CS38872FB18'(!)        = 'End of Design' | 'Comp-Approve'     | 'CS38872FB18'           |'R0402'| '(R0402-0201)'                 | '88.7K'   | '1%'    | '1/16W'  | 'DISCRETE' | 'RES CHIP 88.7K 1/16W +-1%(0402)'                  | 'CHIP0402'     | ''          | ''            | '20110812'
 '88.7K'      | '1%'      | '1/16W'  | '0402LF'  | 'EMPTY'  | 'CS38872FB18'(!)        = 'End of Design' | 'Comp-Approve'     | 'CS38872FB18'           |'R0402'| '(R0402-0201)'                 | '88.7K'   | '1%'    | '1/16W'  | 'IO'       | 'RES CHIP 88.7K 1/16W +-1%(0402)'                  | 'CHIP0402'     | ''          | ''            | '20110812'
 '5.9K'       | '1%'      | '1/16W'  | '0402LF'  | 'CHIP'   | 'CS25902FB10'(!)        = 'End of Design' | 'Comp-Approve'     | 'CS25902FB10'           |'R0402'| '(R0402-0201)'                 | '5.9K'    | '1%'    | '1/16W'  | 'DISCRETE' | 'RES CHIP 5.9K 1/16W +-1%(0402)'                   | 'CHIP0402'     | ''          | ''            | '20110812'
 '5.9K'       | '1%'      | '1/16W'  | '0402LF'  | 'EMPTY'  | 'CS25902FB10'(!)        = 'End of Design' | 'Comp-Approve'     | 'CS25902FB10'           |'R0402'| '(R0402-0201)'                 | '5.9K'    | '1%'    | '1/16W'  | 'IO'       | 'RES CHIP 5.9K 1/16W +-1%(0402)'                   | 'CHIP0402'     | ''          | ''            | '20110812'
 '4.42K'      | '1%'      | '1/16W'  | '0402LF'  | 'CHIP'   | 'CS24422FB00'(!)        = 'End of Design' | 'Comp-Approve'     | 'CS24422FB00'           |'R0402'| '(R0402-0201)'                 | '4.42K'   | '1%'    | '1/16W'  | 'DISCRETE' | 'RES CHIP 4.42K 1/16W +-1%(0402)'                  | 'CHIP0402'     | ''          | ''            | '20110812'
 '4.42K'      | '1%'      | '1/16W'  | '0402LF'  | 'EMPTY'  | 'CS24422FB00'(!)        = 'End of Design' | 'Comp-Approve'     | 'CS24422FB00'           |'R0402'| '(R0402-0201)'                 | '4.42K'   | '1%'    | '1/16W'  | 'IO'       | 'RES CHIP 4.42K 1/16W +-1%(0402)'                  | 'CHIP0402'     | ''          | ''            | '20110812'
 '17.4K'      | '1%'      | '1/16W'  | '0402LF'  | 'CHIP'   | 'CS31742FB20'(!)        = 'End of Design' | 'Comp-Approve'     | 'CS31742FB20'           |'R0402'| '(R0402-0201)'                 | '17.4K'   | '1%'    | '1/16W'  | 'DISCRETE' | 'RES CHIP 17.4K 1/16W +-1% (0402)'                 | 'CHIP0402'     | ''          | ''            | '20110823'
 '17.4K'      | '1%'      | '1/16W'  | '0402LF'  | 'EMPTY'  | 'CS31742FB20'(!)        = 'End of Design' | 'Comp-Approve'     | 'CS31742FB20'           |'R0402'| '(R0402-0201)'                 | '17.4K'   | '1%'    | '1/16W'  | 'IO'       | 'RES CHIP 17.4K 1/16W +-1% (0402)'                 | 'CHIP0402'     | ''          | ''            | '20110823'
 '26.7K'      | '1%'      | '1/16W'  | '0402LF'  | 'CHIP'   | 'CS32672FB14'(!)        = 'End of Design' | 'Comp-Approve'     | 'CS32672FB14'           |'R0402'| '(R0402-0201)'                 | '26.7K'   | '1%'    | '1/16W'  | 'DISCRETE' | 'RES CHIP 26.7K 1/16W +-1%(0402)'                  | 'CHIP0402'     | ''          | ''            | '20110825'
 '26.7K'      | '1%'      | '1/16W'  | '0402LF'  | 'EMPTY'  | 'CS32672FB14'(!)        = 'End of Design' | 'Comp-Approve'     | 'CS32672FB14'           |'R0402'| '(R0402-0201)'                 | '26.7K'   | '1%'    | '1/16W'  | 'IO'       | 'RES CHIP 26.7K 1/16W +-1%(0402)'                  | 'CHIP0402'     | ''          | ''            | '20110825'
 '102K'       | '1%'      | '1/16W'  | '0402LF'  | 'CHIP'   | 'CS41022FB19'(!)        = 'End of Design' | 'Comp-Approve'     | 'CS41022FB19'           |'R0402'| '(R0402-0201)'                 | '102K'    | '1%'    | '1/16W'  | 'DISCRETE' | 'RES CHIP 102K 1/16W +-1%(0402)'                   | 'CHIP0402'     | ''          | ''            | '20110826'
 '102K'       | '1%'      | '1/16W'  | '0402LF'  | 'EMPTY'  | 'CS41022FB19'(!)        = 'End of Design' | 'Comp-Approve'     | 'CS41022FB19'           |'R0402'| '(R0402-0201)'                 | '102K'    | '1%'    | '1/16W'  | 'IO'       | 'RES CHIP 102K 1/16W +-1%(0402)'                   | 'CHIP0402'     | ''          | ''            | '20110826'
 '105K'       | '1%'      | '1/16W'  | '0402LF'  | 'CHIP'   | 'CS41052FB04'(!)        = 'End of Design' | 'Comp-Approve'     | 'CS41052FB04'           |'R0402'| '(R0402-0201)'                 | '105K'    | '1%'    | '1/16W'  | 'DISCRETE' | 'RES CHIP 105K 1/16W +-1%(0402)'                   | 'CHIP0402'     | ''          | ''            | '20110826'
 '105K'       | '1%'      | '1/16W'  | '0402LF'  | 'EMPTY'  | 'CS41052FB04'(!)        = 'End of Design' | 'Comp-Approve'     | 'CS41052FB04'           |'R0402'| '(R0402-0201)'                 | '105K'    | '1%'    | '1/16W'  | 'IO'       | 'RES CHIP 105K 1/16W +-1%(0402)'                   | 'CHIP0402'     | ''          | ''            | '20110826'
 '182K'       | '1%'      | '1/16W'  | '0402LF'  | 'CHIP'   | 'CS41822FB18'(!)        = 'End of Design' | 'Comp-Approve'     | 'CS41822FB18'           |'R0402'| '(R0402-0201)'                 | '182K'    | '1%'    | '1/16W'  | 'DISCRETE' | 'RES CHIP 182K 1/16W +-1%(0402)'                   | 'CHIP0402'     | ''          | ''            | '20110826'
 '182K'       | '1%'      | '1/16W'  | '0402LF'  | 'EMPTY'  | 'CS41822FB18'(!)        = 'End of Design' | 'Comp-Approve'     | 'CS41822FB18'           |'R0402'| '(R0402-0201)'                 | '182K'    | '1%'    | '1/16W'  | 'IO'       | 'RES CHIP 182K 1/16W +-1%(0402)'                   | 'CHIP0402'     | ''          | ''            | '20110826'
 '280K'       | '1%'      | '1/16W'  | '0402LF'  | 'CHIP'   | 'CS42802FB03'(!)        = 'End of Design' | 'Comp-Approve'     | 'CS42802FB03'           |'R0402'| '(R0402-0201)'                 | '182K'    | '1%'    | '1/16W'  | 'DISCRETE' | 'RES CHIP 280K 1/16W +-1%(0402)'                   | 'CHIP0402'     | ''          | ''            | '20110826'
 '280K'       | '1%'      | '1/16W'  | '0402LF'  | 'EMPTY'  | 'CS42802FB03'(!)        = 'End of Design' | 'Comp-Approve'     | 'CS42802FB03'           |'R0402'| '(R0402-0201)'                 | '182K'    | '1%'    | '1/16W'  | 'IO'       | 'RES CHIP 280K 1/16W +-1%(0402)'                   | 'CHIP0402'     | ''          | ''            | '20110826'
 '5.6K'       | '1%'      | '1/16W'  | '0402LF'  | 'CHIP'   | 'CS25602FB19'(!)        = 'End of Design' | 'Comp-Approve'     | 'CS25602FB19'           |'R0402'| '(R0402-0201)'                 | '5.6K'    | '1%'    | '1/16W'  | 'DISCRETE' | 'RES CHIP 5.6K 1/16W +-1%(0402)'                   | 'CHIP0402'     | ''          | ''            | '20110826'
 '5.6K'       | '1%'      | '1/16W'  | '0402LF'  | 'EMPTY'  | 'CS25602FB19'(!)        = 'End of Design' | 'Comp-Approve'     | 'CS25602FB19'           |'R0402'| '(R0402-0201)'                 | '5.6K'    | '1%'    | '1/16W'  | 'IO'       | 'RES CHIP 5.6K 1/16W +-1%(0402)'                   | 'CHIP0402'     | ''          | ''            | '20110826'
 '1K'         | '0.1%'    | '1/16W'  | '0402LF'  | 'CHIP'   | 'CS21002BB00'(!)        = ''              | ''                 | 'CS21002BB00'           |'R0402'| '(R0402-0201)'                 | '1K'      | '0.1%'  | '1/16W'  | 'DISCRETE' | 'RES CHIP 1K 1/16W +-0.1%(0402)'                   | 'CHIP0402'     | ''          | ''            | '20110909'
 '1K'         | '0.1%'    | '1/16W'  | '0402LF'  | 'EMPTY'  | 'CS21002BB00'(!)        = ''              | ''                 | 'CS21002BB00'           |'R0402'| '(R0402-0201)'                 | '1K'      | '0.1%'  | '1/16W'  | 'IO'       | 'RES CHIP 1K 1/16W +-0.1%(0402)'                   | 'CHIP0402'     | ''          | ''            | '20110909'
 '24.9'       | '0.5%'    | '1/16W'  | '0402LF'  | 'CHIP'   | 'CS02492DB00'(!)        = 'End of Design' | 'Comp-Approve'     | 'CS02492DB00'           |'R0402'| '(R0402-0201)'                 | '24.9'    | '0.5%'  | '1/16W'  | 'DISCRETE' | 'RES CHIP 24.9 1/16W +-0.5%(0402)'                 | 'CHIP0402'     | ''          | ''            | '20110909'
 '24.9'       | '0.5%'    | '1/16W'  | '0402LF'  | 'EMPTY'  | 'CS02492DB00'(!)        = 'End of Design' | 'Comp-Approve'     | 'CS02492DB00'           |'R0402'| '(R0402-0201)'                 | '24.9'    | '0.5%'  | '1/16W'  | 'IO'       | 'RES CHIP 24.9 1/16W +-0.5%(0402)'                 | 'CHIP0402'     | ''          | ''            | '20110909'
 '619K'       | '1%'      | '1/16W'  | '0402LF'  | 'CHIP'   | 'CS46192FB18'(!)        = 'End of Design' | 'Comp-Release Qty' | 'CS46192FB18'           |'R0402'| '(R0402-0201)'                 | '619K'    | '1%'    | '1/16W'  | 'DISCRETE' | 'RES CHIP 619K 1/16W +-1%(0402)'                   | 'CHIP0402'     | ''          | ''            | '20111111'
 '619K'       | '1%'      | '1/16W'  | '0402LF'  | 'EMPTY'  | 'CS46192FB18'(!)        = 'End of Design' | 'Comp-Release Qty' | 'CS46192FB18'           |'R0402'| '(R0402-0201)'                 | '619K'    | '1%'    | '1/16W'  | 'IO'       | 'RES CHIP 619K 1/16W +-1%(0402))'                  | 'CHIP0402'     | ''          | ''            | '20111111'
 '10.7K'      | '1%'      | '1/16W'  | '0402LF'  | 'CHIP'   | 'CS31072FB10'(!)        = 'End of Design' | 'Comp-Approve'     | 'CS31072FB10'           |'R0402'| '(R0402-0201)'                 | '10.7K'   | '1%'    | '1/16W'  | 'DISCRETE' | 'RES CHIP 10.7K 1/16W +-1% (0402)'                 | 'CHIP0402'     | ''          | ''            | '20111122'
 '10.7K'      | '1%'      | '1/16W'  | '0402LF'  | 'EMPTY'  | 'CS31072FB10'(!)        = 'End of Design' | 'Comp-Approve'     | 'CS31072FB10'           |'R0402'| '(R0402-0201)'                 | '10.7K'   | '1%'    | '1/16W'  | 'IO'       | 'RES CHIP 10.7K 1/16W +-1% (0402)'                 | 'CHIP0402'     | ''          | ''            | '20111122'
 '51K'        | '1%'      | '1/16W'  | '0402LF'  | 'CHIP'   | 'CS35102FB04'(!)        = 'End of Design' | 'Comp-Approve'     | 'CS35102FB04'           |'R0402'| '(R0402-0201)'                 | '51K'     | '1%'    | '1/16W'  | 'DISCRETE' | 'RES CHIP 51K 1/16W +-1%(0402)'                    | 'CHIP0402'     | ''          | ''            | '20111123'
 '51K'        | '1%'      | '1/16W'  | '0402LF'  | 'EMPTY'  | 'CS35102FB04'(!)        = 'End of Design' | 'Comp-Approve'     | 'CS35102FB04'           |'R0402'| '(R0402-0201)'                 | '51K'     | '1%'    | '1/16W'  | 'IO'       | 'RES CHIP 51K 1/16W +-1%(0402)'                    | 'CHIP0402'     | ''          | ''            | '20111123'
 '3.6K'       | '5%'      | '1/16W'  | '0402LF'  | 'CHIP'   | 'CS23602JB15'(!)        = 'End of Design' | 'Comp-Approve'     | 'CS23602JB15'           |'R0402'| '(R0402-0201)'                 | '3.6K'    | '5%'    | '1/16W'  | 'DISCRETE' | 'RES CHIP 3.6K 1/16W +-5%(0402)'                   | 'CHIP0402'     | ''          | ''            | '20111123'
 '3.6K'       | '5%'      | '1/16W'  | '0402LF'  | 'EMPTY'  | 'CS23602JB15'(!)        = 'End of Design' | 'Comp-Approve'     | 'CS23602JB15'           |'R0402'| '(R0402-0201)'                 | '3.6K'    | '5%'    | '1/16W'  | 'IO'       | 'RES CHIP 3.6K 1/16W +-5%(0402)'                   | 'CHIP0402'     | ''          | ''            | '20111123'
 '7.5'        | '1%'      | '1/16W'  | '0402LF'  | 'CHIP'   | 'CS-7502FB00'(!)        = 'End of Design' | 'Comp-Approve'     | 'CS-7502FB00'           |'R0402'| '(R0402-0201)'                 | '7.5'     | '1%'    | '1/16W'  | 'DISCRETE' | 'RES CHIP 7.5 1/16W +-1%(0402)'                    | 'CHIP0402'     | ''          | ''            | '20111123'
 '7.5'        | '1%'      | '1/16W'  | '0402LF'  | 'EMPTY'  | 'CS-7502FB00'(!)        = 'End of Design' | 'Comp-Approve'     | 'CS-7502FB00'           |'R0402'| '(R0402-0201)'                 | '7.5'     | '1%'    | '1/16W'  | 'IO'       | 'RES CHIP 7.5 1/16W +-1%(0402)'                    | 'CHIP0402'     | ''          | ''            | '20111123'
 '20'         | '5%'      | '2W'     | '2512LF'  | 'CHIP'   | 'CS0200AJR00'(!)        = ''              | ''                 | 'CS0200AJR00'           |'R2512'| '(SMR2512AW)'                  | '20'      | '5%'    | '2W'     | 'DISCRETE' | 'RESISTOR CHIP 20 2W +-5%(2512)'                   | 'CHIP2512'     | ''          | ''            | '20111124'
 '20'         | '5%'      | '2W'     | '2512LF'  | 'EMPTY'  | 'CS0200AJR00'(!)        = ''              | ''                 | 'CS0200AJR00'           |'R2512'| '(SMR2512AW)'                  | '20'      | '5%'    | '2W'     | 'IO'       | 'RESISTOR CHIP 20 2W +-5%(2512)'                   | 'CHIP2512'     | ''          | ''            | '20111124'
 '698'        | '1%'      | '1/16W'  | '0402LF'  | 'CHIP'   | 'CS16982FB00'(!)        = 'End of Design' | 'Comp-Approve'     | 'CS16982FB00'           |'R0402'| '(R0402-0201)'                 | '698'     | '1%'    | '1/16W'  | 'DISCRETE' | 'RES CHIP 698 1/16W +-1%(0402)'                    | 'CHIP0402'     | ''          | ''            | '20111125'
 '698'        | '1%'      | '1/16W'  | '0402LF'  | 'EMPTY'  | 'CS16982FB00'(!)        = 'End of Design' | 'Comp-Approve'     | 'CS16982FB00'           |'R0402'| '(R0402-0201)'                 | '698'     | '1%'    | '1/16W'  | 'IO'       | 'RES CHIP 698 1/16W +-1%(0402)'                    | 'CHIP0402'     | ''          | ''            | '20111125'
 '75K'        | '1%'      | '1/16W'  | '0402LF'  | 'CHIP'   | 'CS37502FB12'(!)        = 'End of Design' | 'Comp-Approve'     | 'CS37502FB12'           |'R0402'| '(R0402-0201)'                 | '75K'     | '1%'    | '1/16W'  | 'DISCRETE' | 'RES CHIP 75K 1/16W +-1%(0402)'                    | 'CHIP0402'     | ''          | ''            | '20111130'
 '75K'        | '1%'      | '1/16W'  | '0402LF'  | 'EMPTY'  | 'CS37502FB12'(!)        = 'End of Design' | 'Comp-Approve'     | 'CS37502FB12'           |'R0402'| '(R0402-0201)'                 | '75K'     | '1%'    | '1/16W'  | 'IO'       | 'RES CHIP 75K 1/16W +-1%(0402)'                    | 'CHIP0402'     | ''          | ''            | '20111130'
 '121K'       | '1%'      | '1/16W'  | '0402LF'  | 'CHIP'   | 'CS41212FB11'(!)        = 'End of Design' | 'Comp-Approve'     | 'CS41212FB11'           |'R0402'| '(R0402-0201)'                 | '121K'    | '1%'    | '1/16W'  | 'DISCRETE' | 'RES CHIP 121K 1/16W +-1%(0402)'                   | 'CHIP0402'     | ''          | ''            | '20111130'
 '121K'       | '1%'      | '1/16W'  | '0402LF'  | 'EMPTY'  | 'CS41212FB11'(!)        = 'End of Design' | 'Comp-Approve'     | 'CS41212FB11'           |'R0402'| '(R0402-0201)'                 | '121K'    | '1%'    | '1/16W'  | 'IO'       | 'RES CHIP 121K 1/16W +-1%(0402)'                   | 'CHIP0402'     | ''          | ''            | '20111130'
 '22.1K'      | '1%'      | '1/16W'  | '0402LF'  | 'CHIP'   | 'CS32212FB12'(!)        = 'End of Design' | 'Comp-Approve'     | 'CS32212FB12'           |'R0402'| '(R0402-0201)'                 | '22.1K'   | '1%'    | '1/16W'  | 'DISCRETE' | 'RES CHIP 22.1K 1/16W +-1%(0402)'                  | 'CHIP0402'     | ''          | ''            | '20111130'
 '22.1K'      | '1%'      | '1/16W'  | '0402LF'  | 'EMPTY'  | 'CS32212FB12'(!)        = 'End of Design' | 'Comp-Approve'     | 'CS32212FB12'           |'R0402'| '(R0402-0201)'                 | '22.1K'   | '1%'    | '1/16W'  | 'IO'       | 'RES CHIP 22.1K 1/16W +-1%(0402)'                  | 'CHIP0402'     | ''          | ''            | '20111130'
 '3K'         | '1%'      | '1/10W'  | '0603LF'  | 'CHIP'   | 'CS23003F926'(!)        = 'End of Design' | 'Comp-Approve'     | 'CS23003F926'           |'R0603'| '(SMR0603AW)'                  | '3K'      | '1%'    | '1/10W'  | 'DISCRETE' | 'RES CHIP 3K 1/10W +-1%(0603)'                     | 'CHIP0603'     | ''          | ''            | '20111202'
 '3K'         | '1%'      | '1/10W'  | '0603LF'  | 'EMPTY'  | 'CS23003F926'(!)        = 'End of Design' | 'Comp-Approve'     | 'CS23003F926'           |'R0603'| '(SMR0603AW)'                  | '3K'      | '1%'    | '1/10W'  | 'IO'       | 'RES CHIP 3K 1/10W +-1%(0603)'                     | 'CHIP0603'     | ''          | ''            | '20111202'
 '470'        | '5%'      | '1/10W'  | '0603LF'  | 'CHIP'   | 'CS14703J941'(!)        = 'End of Design' | 'Comp-Approve'     | 'CS14703J941'           |'R0603'| '(SMR0603AW)'                  | '470'     | '5%'    | '1/10W'  | 'DISCRETE' | 'RESISTOR CHIP 470 1/10W+-5%(0603)'                | 'CHIP0603'     | ''          | ''            | '20111207'
 '470'        | '5%'      | '1/10W'  | '0603LF'  | 'EMPTY'  | 'CS14703J941'(!)        = 'End of Design' | 'Comp-Approve'     | 'CS14703J941'           |'R0603'| '(SMR0603AW)'                  | '470'     | '5%'    | '1/10W'  | 'IO'       | 'RESISTOR CHIP 470 1/10W+-5%(0603)'                | 'CHIP0603'     | ''          | ''            | '20111207'
 '8.2K'       | '1%'      | '1/16W'  | '0402LF'  | 'CHIP'   | 'CS28202FB12'(!)        = 'End of Design' | 'Comp-Approve'     | 'CS28202FB12'           |'R0402'| '(R0402-0201)'                 | '8.2K'    | '1%'    | '1/16W'  | 'DISCRETE' | 'RES CHIP 8.2K 1/16W +-1%(0402)'                   | 'CHIP0402'     | ''          | ''            | '20111208'
 '8.2K'       | '1%'      | '1/16W'  | '0402LF'  | 'EMPTY'  | 'CS28202FB12'(!)        = 'End of Design' | 'Comp-Approve'     | 'CS28202FB12'           |'R0402'| '(R0402-0201)'                 | '8.2K'    | '1%'    | '1/16W'  | 'IO'       | 'RES CHIP 8.2K 1/16W +-1%(0402)'                   | 'CHIP0402'     | ''          | ''            | '20111208'
 '63.4K'      | '1%'      | '1/16W'  | '0402LF'  | 'CHIP'   | 'CS36342FB11'(!)        = 'End of Design' | 'Comp-Approve'     | 'CS36342FB11'           |'R0402'| '(R0402-0201)'                 | '63.4K'   | '1%'    | '1/16W'  | 'DISCRETE' | 'RES CHIP 63.4K 1/16W +-1% (0402)'                 | 'CHIP0402'     | ''          | ''            | '20111208'
 '63.4K'      | '1%'      | '1/16W'  | '0402LF'  | 'EMPTY'  | 'CS36342FB11'(!)        = 'End of Design' | 'Comp-Approve'     | 'CS36342FB11'           |'R0402'| '(R0402-0201)'                 | '63.4K'   | '1%'    | '1/16W'  | 'IO'       | 'RES CHIP 63.4K 1/16W +-1% (0402)'                 | 'CHIP0402'     | ''          | ''            | '20111208'
 '2K'         | '1%'      | '1/10W'  | '0603LF'  | 'CHIP'   | 'CS22003F915'(!)        = ''              | ''                 | 'CS22003F915'           |'R0603'| '(SMR0603AW)'                  | '2K'      | '1%'    | '1/10W'  | 'DISCRETE' | 'RES CHIP 2K 1/10W +-1%(0603)'                     | 'CHIP0603'     | ''          | ''            | '20111208'
 '2K'         | '1%'      | '1/10W'  | '0603LF'  | 'EMPTY'  | 'CS22003F915'(!)        = ''              | ''                 | 'CS22003F915'           |'R0603'| '(SMR0603AW)'                  | '2K'      | '1%'    | '1/10W'  | 'IO'       | 'RES CHIP 2K 1/10W +-1%(0603)'                     | 'CHIP0603'     | ''          | ''            | '20111208'
 '5.11'       | '1%'      | '1/16W'  | '0402LF'  | 'CHIP'   | 'CS-5112FB06'(!)        = 'End of Design' | 'Comp-Approve'     | 'CS-5112FB06'           |'R0402'| '(R0402-0201)'                 | '5.11'    | '1%'    | '1/16W'  | 'DISCRETE' | 'RES CHIP 5.11 1/16W +-1%(0402)'                   | 'CHIP0402'     | ''          | ''            | '20111209'
 '5.11'       | '1%'      | '1/16W'  | '0402LF'  | 'EMPTY'  | 'CS-5112FB06'(!)        = 'End of Design' | 'Comp-Approve'     | 'CS-5112FB06'           |'R0402'| '(R0402-0201)'                 | '5.11'    | '1%'    | '1/16W'  | 'IO'       | 'RES CHIP 5.11 1/16W +-1%(0402)'                   | 'CHIP0402'     | ''          | ''            | '20111209'
 '0.51'       | '1%'      | '1/16W'  | '0402LF'  | 'CHIP'   | 'CS+5102FB00'(!)        = ''              | ''                 | 'CS+5102FB00'           |'R0402'| '(R0402-0201)'                 | '0.51'    | '1%'    | '1/16W'  | 'DISCRETE' | 'RES CHIP 0.51 1/16W +-1%(0402)'                   | 'CHIP0402'     | ''          | ''            | '20111209'
 '0.51'       | '1%'      | '1/16W'  | '0402LF'  | 'EMPTY'  | 'CS+5102FB00'(!)        = ''              | ''                 | 'CS+5102FB00'           |'R0402'| '(R0402-0201)'                 | '0.51'    | '1%'    | '1/16W'  | 'IO'       | 'RES CHIP 0.51 1/16W +-1%(0402)'                   | 'CHIP0402'     | ''          | ''            | '20111209'
 '39K'        | '1%'      | '1/10W'  | '0603LF ' | 'CHIP'   | 'CS33903F912'(!)        = ''              | ''                 | 'CS33903F912'           |'R0603'| '(SMR0603AW)'                  | '39K'     | '1%'    | '1/10W'  | 'DISCRETE' | 'RESISTOR CHIP 39K 1/10W+-1%(0603)'                | 'CHIP0603'     | ''          | ''            | '20111209'
 '39K'        | '1%'      | '1/10W'  | '0603LF ' | 'EMPTY'  | 'CS33903F912'(!)        = ''              | ''                 | 'CS33903F912'           |'R0603'| '(SMR0603AW)'                  | '39K'     | '1%'    | '1/10W'  | 'IO'       | 'RESISTOR CHIP 39K 1/10W+-1%(0603)'                | 'CHIP0603'     | ''          | ''            | '20111209'
 '31.6'       | '1%'      | '1/16W'  | '0402LF'  | 'CHIP'   | 'CS03162FB00'(!)        = ''              | ''                 | 'CS03162FB00'           |'R0402'| '(R0402-0201)'                 | '31.6'    | '1%'    | '1/16W'  | 'DISCRETE' | 'RES CHIP 31.6 1/16W +-1%(0402)'                   | 'CHIP0402'     | ''          | ''            | '20111213'
 '31.6'       | '1%'      | '1/16W'  | '0402LF'  | 'EMPTY'  | 'CS03162FB00'(!)        = ''              | ''                 | 'CS03162FB00'           |'R0402'| '(R0402-0201)'                 | '31.6'    | '1%'    | '1/16W'  | 'IO'       | 'RES CHIP 31.6 1/16W +-1%(0402)'                   | 'CHIP0402'     | ''          | ''            | '20111213'
 '33.2'       | '1%'      | '1/16W'  | '0402LF'  | 'CHIP'   | 'CS03322FB34'(!)        = 'End of Design' | 'Comp-Approve'     | 'CS03322FB34'           |'R0402'| '(R0402-0201)'                 | '33.2'    | '1%'    | '1/16W'  | 'DISCRETE' | 'RES CHIP 33.2 1/16W +-1%(0402)'                   | 'CHIP0402'     | ''          | ''            | '20111213'
 '33.2'       | '1%'      | '1/16W'  | '0402LF'  | 'EMPTY'  | 'CS03322FB34'(!)        = 'End of Design' | 'Comp-Approve'     | 'CS03322FB34'           |'R0402'| '(R0402-0201)'                 | '33.2'    | '1%'    | '1/16W'  | 'IO'       | 'RES CHIP 33.2 1/16W +-1%(0402)'                   | 'CHIP0402'     | ''          | ''            | '20111213'
 '42.2'       | '1%'      | '1/16W'  | '0402LF'  | 'CHIP'   | 'CS04222FB00'(!)        = 'End of Design' | 'End of Life'      | 'CS04222FB00'           |'R0402_EOL'| '(R0402-0201)'                 | '42.2'    | '1%'    | '1/16W'  | 'DISCRETE' | 'RES CHIP 42.2 1/16W +-1%(0402)'                   | 'CHIP0402'     | ''          | ''            | '20111213'
 '42.2'       | '1%'      | '1/16W'  | '0402LF'  | 'EMPTY'  | 'CS04222FB00'(!)        = 'End of Design' | 'End of Life'      | 'CS04222FB00'           |'R0402_EOL'| '(R0402-0201)'                 | '42.2'    | '1%'    | '1/16W'  | 'IO'       | 'RES CHIP 42.2 1/16W +-1%(0402)'                   | 'CHIP0402'     | ''          | ''            | '20111213'
 '51.1'       | '1%'      | '1/16W'  | '0402LF'  | 'CHIP'   | 'CS05112FB11'(!)        = 'End of Design' | 'Comp-Approve'     | 'CS05112FB11'           |'R0402'| '(R0402-0201)'                 | '51.1'    | '1%'    | '1/16W'  | 'DISCRETE' | 'RESISTOR CHIP 51.1,1/16W,+-1%(0402)'              | 'CHIP0402'     | ''          | ''            | '20111213'
 '51.1'       | '1%'      | '1/16W'  | '0402LF'  | 'EMPTY'  | 'CS05112FB11'(!)        = 'End of Design' | 'Comp-Approve'     | 'CS05112FB11'           |'R0402'| '(R0402-0201)'                 | '51.1'    | '1%'    | '1/16W'  | 'IO'       | 'RESISTOR CHIP 51.1,1/16W,+-1%(0402)'              | 'CHIP0402'     | ''          | ''            | '20111213'
 '270'        | '5%'      | '1/16W'  | '0402LF'  | 'CHIP'   | 'CS12702JB14'(!)        = 'End of Design' | 'Comp-Approve'     | 'CS12702JB14'           |'R0402'| '(R0402-0201)'                 | '270'     | '5%'    | '1/16W'  | 'DISCRETE' | 'RES CHIP 270(1/16W,+-5%,0402)'                    | 'CHIP0402'     | ''          | ''            | '20111213'
 '270'        | '5%'      | '1/16W'  | '0402LF'  | 'EMPTY'  | 'CS12702JB14'(!)        = 'End of Design' | 'Comp-Approve'     | 'CS12702JB14'           |'R0402'| '(R0402-0201)'                 | '270'     | '5%'    | '1/16W'  | 'IO'       | 'RES CHIP 270(1/16W,+-5%,0402)'                    | 'CHIP0402'     | ''          | ''            | '20111213'
 '274'        | '1%'      | '1/16W'  | '0402LF'  | 'CHIP'   | 'CS12742FB02'(!)        = 'End of Design' | 'Comp-Approve'     | 'CS12742FB02'           |'R0402'| '(R0402-0201)'                 | '274'     | '1%'    | '1/16W'  | 'DISCRETE' | 'RES CHIP 274 1/16W +-1%(0402)'                    | 'CHIP0402'     | ''          | ''            | '20111213'
 '274'        | '1%'      | '1/16W'  | '0402LF'  | 'EMPTY'  | 'CS12742FB02'(!)        = 'End of Design' | 'Comp-Approve'     | 'CS12742FB02'           |'R0402'| '(R0402-0201)'                 | '274'     | '1%'    | '1/16W'  | 'IO'       | 'RES CHIP 274 1/16W +-1%(0402)'                    | 'CHIP0402'     | ''          | ''            | '20111213'
 '2.43K'      | '1%'      | '1/16W'  | '0402LF'  | 'CHIP'   | 'CS22432FB09'(!)        = 'End of Design' | 'Comp-Approve'     | 'CS22432FB09'           |'R0402'| '(R0402-0201)'                 | '2.43K'   | '1%'    | '1/16W'  | 'DISCRETE' | 'RES CHIP 2.43K 1/16W +-1%(0402)'                  | 'CHIP0402'     | ''          | ''            | '20111213'
 '2.43K'      | '1%'      | '1/16W'  | '0402LF'  | 'EMPTY'  | 'CS22432FB09'(!)        = 'End of Design' | 'Comp-Approve'     | 'CS22432FB09'           |'R0402'| '(R0402-0201)'                 | '2.43K'   | '1%'    | '1/16W'  | 'IO'       | 'RES CHIP 2.43K 1/16W +-1%(0402)'                  | 'CHIP0402'     | ''          | ''            | '20111213'
 '27.4K'      | '1%'      | '1/10W'  | '0603LF'  | 'CHIP'   | 'CS32743F929'(!)        = ''              | ''                 | 'CS32743F929'           |'R0603'| '(SMR0603AW)'                  | '27.4K'   | '1%'    | '1/10W'  | 'DISCRETE' | 'RES CHIP 27.4K 1/10W +-1%(0603)'                  | 'CHIP0603'     | ''          | ''            | '20111213'
 '27.4K'      | '1%'      | '1/10W'  | '0603LF'  | 'EMPTY'  | 'CS32743F929'(!)        = ''              | ''                 | 'CS32743F929'           |'R0603'| '(SMR0603AW)'                  | '27.4K'   | '1%'    | '1/10W'  | 'IO'       | 'RES CHIP 27.4K 1/10W +-1%(0603)'                  | 'CHIP0603'     | ''          | ''            | '20111213'
 '48.7K'      | '1%'      | '1/16W'  | '0402LF'  | 'CHIP'   | 'CS34872FB17'(!)        = 'End of Design' | 'Comp-Approve'     | 'CS34872FB17'           |'R0402'| '(R0402-0201)'                 | '48.7K'   | '1%'    | '1/16W'  | 'DISCRETE' | 'RES CHIP 48.7K 1/16W +-1%(0402)'                  | 'CHIP0402'     | ''          | ''            | '20111213'
 '48.7K'      | '1%'      | '1/16W'  | '0402LF'  | 'EMPTY'  | 'CS34872FB17'(!)        = 'End of Design' | 'Comp-Approve'     | 'CS34872FB17'           |'R0402'| '(R0402-0201)'                 | '48.7K'   | '1%'    | '1/16W'  | 'IO'       | 'RES CHIP 48.7K 1/16W +-1%(0402)'                  | 'CHIP0402'     | ''          | ''            | '20111213'
 '220K'       | '5%'      | '1/16W'  | '0402LF'  | 'CHIP'   | 'CS42202JB11'(!)        = 'End of Design' | 'Comp-Approve'     | 'CS42202JB11'           |'R0402'| '(R0402-0201)'                 | '220K'    | '5%'    | '1/16W'  | 'DISCRETE' | 'RES CHIP 220K 1/16W+-5%(0402)'                    | 'CHIP0402'     | ''          | ''            | '20111213'
 '220K'       | '5%'      | '1/16W'  | '0402LF'  | 'EMPTY'  | 'CS42202JB11'(!)        = 'End of Design' | 'Comp-Approve'     | 'CS42202JB11'           |'R0402'| '(R0402-0201)'                 | '220K'    | '5%'    | '1/16W'  | 'IO'       | 'RES CHIP 220K 1/16W+-5%(0402)'                    | 'CHIP0402'     | ''          | ''            | '20111213'
 '390K'       | '5%'      | '1/16W'  | '0402LF'  | 'CHIP'   | 'CS43902JB10'(!)        = 'End of Design' | 'Comp-Approve'     | 'CS43902JB10'           |'R0402'| '(R0402-0201)'                 | '390K'    | '5%'    | '1/16W'  | 'DISCRETE' | 'RES CHIP 390K(1/16W +-5% 0402)'                   | 'CHIP0402'     | ''          | ''            | '20111213'
 '390K'       | '5%'      | '1/16W'  | '0402LF'  | 'EMPTY'  | 'CS43902JB10'(!)        = 'End of Design' | 'Comp-Approve'     | 'CS43902JB10'           |'R0402'| '(R0402-0201)'                 | '390K'    | '5%'    | '1/16W'  | 'IO'       | 'RES CHIP 390K(1/16W +-5% 0402)'                   | 'CHIP0402'     | ''          | ''            | '20111213'
 '0.01'       | '5%'      | '3/4W'   | '2010LF'  | 'CHIP'   | 'CS+010BFJ28'(!)        = 'End of Design' | 'Comp-Approve'     | 'CS+010BFJ28'           |'R2010'| '(SMR2010AW)'                  | '0.01'    | '5%'    | '3/4W'   | 'DISCRETE' | 'RES CHIP 0.01 3/4W +-1%(2010)'                    | 'CHIP2010'     | ''          | ''            | '20111215'
 '0.01'       | '5%'      | '3/4W'   | '2010LF'  | 'EMPTY'  | 'CS+010BFJ28'(!)        = 'End of Design' | 'Comp-Approve'     | 'CS+010BFJ28'           |'R2010'| '(SMR2010AW)'                  | '0.01'    | '5%'    | '3/4W'   | 'IO'       | 'RES CHIP 0.01 3/4W +-1%(2010)'                    | 'CHIP2010'     | ''          | ''            | '20111215'
 '5.11'       | '1%'      | '1/4W'   | '1206LF'  | 'CHIP'   | 'CS-5116F208'(!)        = ''              | ''                 | 'CS-5116F208'           |'R1206'| '(SMR1206AW)'                  | '5.11'    | '1%'    | '1/4W'   | 'DISCRETE' | 'RES CHIP 5.11 1/4W +-1%(1206)'                    | 'CHIP1206'     | ''          | ''            | '20111219'
 '5.11'       | '1%'      | '1/4W'   | '1206LF'  | 'EMPTY'  | 'CS-5116F208'(!)        = ''              | ''                 | 'CS-5116F208'           |'R1206'| '(SMR1206AW)'                  | '5.11'    | '1%'    | '1/4W'   | 'IO'       | 'RES CHIP 5.11 1/4W +-1%(1206)'                    | 'CHIP1206'     | ''          | ''            | '20111219'
 '20'         | '1%'      | '1/4W'   | '1206LF'  | 'CHIP'   | 'CS02006F200'(!)        = ''              | ''                 | 'CS02006F200'           |'R1206'| '(SMR1206AW)'                  | '20'      | '1%'    | '1/4W'   | 'DISCRETE' | 'RES CHIP 20 1/4 +-1%(1206)'                       | 'CHIP1206'     | ''          | ''            | '20111219'
 '20'         | '1%'      | '1/4W'   | '1206LF'  | 'EMPTY'  | 'CS02006F200'(!)        = ''              | ''                 | 'CS02006F200'           |'R1206'| '(SMR1206AW)'                  | '20'      | '1%'    | '1/4W'   | 'IO'       | 'RES CHIP 20 1/4 +-1%(1206)'                       | 'CHIP1206'     | ''          | ''            | '20111219'
 '121'        | '1%'      | '1/16W'  | '0402LF'  | 'CHIP'   | 'CS11212FB24'(!)        = 'End of Design' | 'Comp-Approve'     | 'CS11212FB24'           |'R0402'| '(R0402-0201)'                 | '121'     | '1%'    | '1/16W'  | 'DISCRETE' | 'RES CHIP 121 1/16W +-1%(0402)'                    | 'CHIP0402'     | ''          | ''            | '20111219'
 '121'        | '1%'      | '1/16W'  | '0402LF'  | 'EMPTY'  | 'CS11212FB24'(!)        = 'End of Design' | 'Comp-Approve'     | 'CS11212FB24'           |'R0402'| '(R0402-0201)'                 | '121'     | '1%'    | '1/16W'  | 'IO'       | 'RES CHIP 121 1/16W +-1%(0402)'                    | 'CHIP0402'     | ''          | ''            | '20111219'
 '11.5K'      | '1%'      | '1/16W'  | '0402LF'  | 'CHIP'   | 'CS31152FB14'(!)        = 'End of Design' | 'Comp-Approve'     | 'CS31152FB14'           |'R0402'| '(R0402-0201)'                 | '11.5K'   | '1%'    | '1/16W'  | 'DISCRETE' | 'RES CHIP 11.5K 1/16W +-1%( 0402)'                 | 'CHIP0402'     | ''          | ''            | '20111219'
 '11.5K'      | '1%'      | '1/16W'  | '0402LF'  | 'EMPTY'  | 'CS31152FB14'(!)        = 'End of Design' | 'Comp-Approve'     | 'CS31152FB14'           |'R0402'| '(R0402-0201)'                 | '11.5K'   | '1%'    | '1/16W'  | 'IO'       | 'RES CHIP 11.5K 1/16W +-1%( 0402)'                 | 'CHIP0402'     | ''          | ''            | '20111219'
 '0.003'      | '1%'      | '1W'     | '2512LF'  | 'CHIP'   | 'CS+0038F128'(!)        = 'End of Design' | 'Comp-Approve'     | 'CS+0038F128'           |'R2512'| '(SMR2512AW)'                  | '0.003'   | '1%'    | '1W'     | 'DISCRETE' | 'RES CHIP 0.003 1W +-1%(2512)'                     | 'CHIP2512'     | ''          | ''            | '20111219'
 '0.003'      | '1%'      | '1W'     | '2512LF'  | 'EMPTY'  | 'CS+0038F128'(!)        = 'End of Design' | 'Comp-Approve'     | 'CS+0038F128'           |'R2512'| '(SMR2512AW)'                  | '0.003'   | '1%'    | '1W'     | 'IO'       | 'RES CHIP 0.003 1W +-1%(2512)'                     | 'CHIP2512'     | ''          | ''            | '20111219'
 '28K'        | '1%'      | '1/16W'  | '0402LF'  | 'CHIP'   | 'CS32802FB10'(!)        = 'End of Design' | 'Comp-Approve'     | 'CS32802FB10'           |'R0402'| '(R0402-0201)'                 | '28K'     | '1%'    | '1/16W'  | 'DISCRETE' | 'RES CHIP 28K 1/16W +-1%(0402)'                    | 'CHIP0402'     | ''          | ''            | '20111219'
 '28K'        | '1%'      | '1/16W'  | '0402LF'  | 'EMPTY'  | 'CS32802FB10'(!)        = 'End of Design' | 'Comp-Approve'     | 'CS32802FB10'           |'R0402'| '(R0402-0201)'                 | '28K'     | '1%'    | '1/16W'  | 'IO'       | 'RES CHIP 28K 1/16W +-1%(0402)'                    | 'CHIP0402'     | ''          | ''            | '20111219'
 '0.01'       | '1%'      | '1W'     | '2512LF'  | 'CHIP'   | 'CS+0108F128'(!)        = 'End of Design' | 'Comp-Release Qty' | 'CS+0108F128'           |'R2512'| '(SMR2512AW)'                  | '0.01'    | '1%'    | '1W'     | 'DISCRETE' | 'RES CHIP 0.01 1W +-1%(2512)'                      | 'CHIP2512'     | ''          | ''            | '20111219'
 '0.01'       | '1%'      | '1W'     | '2512LF'  | 'EMPTY'  | 'CS+0108F128'(!)        = 'End of Design' | 'Comp-Release Qty' | 'CS+0108F128'           |'R2512'| '(SMR2512AW)'                  | '0.01'    | '1%'    | '1W'     | 'IO'       | 'RES CHIP 0.01 1W +-1%(2512)'                      | 'CHIP2512'     | ''          | ''            | '20111219'
 '100K'       | '1%'      | '1/10W'  | '0603LF'  | 'CHIP'   | 'CS41003F932'(!)        = ''              | ''                 | 'CS41003F932'           |'R0603'| '(SMR0603AW)'                  | '100K'    | '1%'    | '1/10W'  | 'DISCRETE' | 'RESISTOR CHIP 100K 1/10W+-1%(0603)'               | 'CHIP0603'     | ''          | ''            | '20111219'
 '100K'       | '1%'      | '1/10W'  | '0603LF'  | 'EMPTY'  | 'CS41003F932'(!)        = ''              | ''                 | 'CS41003F932'           |'R0603'| '(SMR0603AW)'                  | '100K'    | '1%'    | '1/10W'  | 'IO'       | 'RESISTOR CHIP 100K 1/10W+-1%(0603)'               | 'CHIP0603'     | ''          | ''            | '20111219'
 '475'        | '1%'      | '1/10W'  | '0603LF'  | 'CHIP'   | 'CS14753F933'(!)        = ''              | ''                 | 'CS14753F933'           |'R0603'| '(SMR0603AW)'                  | '475'     | '1%'    | '1/10W'  | 'DISCRETE' | 'RESISTOR CHIP 475 1/10W(+-1%.0603)'               | 'CHIP0603'     | ''          | ''            | '20111223'
 '475'        | '1%'      | '1/10W'  | '0603LF'  | 'EMPTY'  | 'CS14753F933'(!)        = ''              | ''                 | 'CS14753F933'           |'R0603'| '(SMR0603AW)'                  | '475'     | '1%'    | '1/10W'  | 'IO'       | 'RESISTOR CHIP 475 1/10W(+-1%.0603)'               | 'CHIP0603'     | ''          | ''            | '20111223'
 '28K'        | '1%'      | '1/10W'  | '0603LF'  | 'CHIP'   | 'CS32803F932'(!)        = ''              | ''                 | 'CS32803F932'           |'R0603'| '(SMR0603AW)'                  | '28K'     | '1%'    | '1/10W'  | 'DISCRETE' | 'RES CHIP 28K 1/10W+-1%(0603)'                     | 'CHIP0603'     | ''          | ''            | '20111223'
 '28K'        | '1%'      | '1/10W'  | '0603LF'  | 'EMPTY'  | 'CS32803F932'(!)        = ''              | ''                 | 'CS32803F932'           |'R0603'| '(SMR0603AW)'                  | '28K'     | '1%'    | '1/10W'  | 'IO'       | 'RES CHIP 28K 1/10W+-1%(0603)'                     | 'CHIP0603'     | ''          | ''            | '20111223'
 '33'         | '1%'      | '1/10W'  | '0603LF'  | 'CHIP'   | 'CS03303F915'(!)        = ''              | ''                 | 'CS03303F915'           |'R0603'| '(SMR0603AW)'                  | '33'      | '1%'    | '1/10W'  | 'DISCRETE' | 'RES CHIP 33 1/10W +-1%(0603)'                     | 'CHIP0603'     | ''          | ''            | '20111223'
 '33'         | '1%'      | '1/10W'  | '0603LF'  | 'EMPTY'  | 'CS03303F915'(!)        = ''              | ''                 | 'CS03303F915'           |'R0603'| '(SMR0603AW)'                  | '33'      | '1%'    | '1/10W'  | 'IO'       | 'RES CHIP 33 1/10W +-1%(0603)'                     | 'CHIP0603'     | ''          | ''            | '20111223'
 '536'        | '1%'      | '1/16W'  | '0402LF'  | 'CHIP'   | 'CS15362FB13'(!)        = 'End of Design' | 'Comp-Approve'     | 'CS15362FB13'           |'R0402'| '(R0402-0201)'                 | '536'     | '1%'    | '1/16W'  | 'DISCRETE' | 'RES CHIP 536 1/16W.+-1%(0402)'                    | 'CHIP0402'     | ''          | ''            | '20111223'
 '536'        | '1%'      | '1/16W'  | '0402LF'  | 'EMPTY'  | 'CS15362FB13'(!)        = 'End of Design' | 'Comp-Approve'     | 'CS15362FB13'           |'R0402'| '(R0402-0201)'                 | '536'     | '1%'    | '1/16W'  | 'IO'       | 'RES CHIP 536 1/16W.+-1%(0402)'                    | 'CHIP0402'     | ''          | ''            | '20111223'
 '27.4K'      | '1%'      | '1/16W'  | '0402LF'  | 'CHIP'   | 'CS32742FB14'(!)        = 'End of Design' | 'Comp-Approve'     | 'CS32742FB14'           |'R0402'| '(R0402-0201)'                 | '27.4K'   | '1%'    | '1/16W'  | 'DISCRETE' | 'RES CHIP 27.4K 1/16W +-1% (0402)'                 | 'CHIP0402'     | ''          | ''            | '20111223'
 '27.4K'      | '1%'      | '1/16W'  | '0402LF'  | 'EMPTY'  | 'CS32742FB14'(!)        = 'End of Design' | 'Comp-Approve'     | 'CS32742FB14'           |'R0402'| '(R0402-0201)'                 | '27.4K'   | '1%'    | '1/16W'  | 'IO'       | 'RES CHIP 27.4K 1/16W +-1% (0402)'                 | 'CHIP0402'     | ''          | ''            | '20111223'
 '73.2K'      | '1%'      | '1/16W'  | '0402LF'  | 'CHIP'   | 'CS37322FB14'(!)        = 'End of Design' | 'Comp-Approve'     | 'CS37322FB14'           |'R0402'| '(R0402-0201)'                 | '73.2K'   | '1%'    | '1/16W'  | 'DISCRETE' | 'RES CHIP 73.2K 1/16W +-1%(0402)'                  | 'CHIP0402'     | ''          | ''            | '20111223'
 '73.2K'      | '1%'      | '1/16W'  | '0402LF'  | 'EMPTY'  | 'CS37322FB14'(!)        = 'End of Design' | 'Comp-Approve'     | 'CS37322FB14'           |'R0402'| '(R0402-0201)'                 | '73.2K'   | '1%'    | '1/16W'  | 'IO'       | 'RES CHIP 73.2K 1/16W +-1%(0402)'                  | 'CHIP0402'     | ''          | ''            | '20111223'
 '1K'         | '1%'      | '1/8W'   | '0805LF'  | 'CHIP'   | 'CS21004FA10'(!)        = ''              | ''                 | 'CS21004FA10'           |'R0805'| '(SMR0805AW)'                  | '1K'      | '1%'    | '1/8W'   | 'DISCRETE' | 'RES CHIP 1K 1/8W+-1%(0805)L-F'                    | 'CHIP0805'     | ''          | ''            | '20111227'
 '1K'         | '1%'      | '1/8W'   | '0805LF'  | 'EMPTY'  | 'CS21004FA10'(!)        = ''              | ''                 | 'CS21004FA10'           |'R0805'| '(SMR0805AW)'                  | '1K'      | '1%'    | '1/8W'   | 'IO'       | 'RES CHIP 1K 1/8W+-1%(0805)L-F'                    | 'CHIP0805'     | ''          | ''            | '20111227'
 '220'        | '1%'      | '1/10W'  | '0603LF'  | 'CHIP'   | 'CS12203F911'(!)        = 'End of Design' | 'Comp-Approve'     | 'CS12203F911'           |'R0603'| '(SMR0603AW)'                  | '220'     | '1%'    | '1/10W'  | 'DISCRETE' | 'RESISTOR CHIP 220 1/10W.+-1%(0603)'               | 'CHIP0603'     | ''          | ''            | '20111227'
 '220'        | '1%'      | '1/10W'  | '0603LF'  | 'EMPTY'  | 'CS12203F911'(!)        = 'End of Design' | 'Comp-Approve'     | 'CS12203F911'           |'R0603'| '(SMR0603AW)'                  | '220'     | '1%'    | '1/10W'  | 'IO'       | 'RESISTOR CHIP 220 1/10W.+-1%(0603)'               | 'CHIP0603'     | ''          | ''            | '20111227'
 '2.49K'      | '1%'      | '1/10W'  | '0603LF'  | 'CHIP'   | 'CS22493F945'(!)        = ''              | ''                 | 'CS22493F945'           |'R0603'| '(SMR0603AW)'                  | '2.49K'   | '1%'    | '1/10W'  | 'DISCRETE' | 'RES CHIP 2.49K 1/10W +-1%(0603)'                  | 'CHIP0603'     | ''          | ''            | '20111227'
 '2.49K'      | '1%'      | '1/10W'  | '0603LF'  | 'EMPTY'  | 'CS22493F945'(!)        = ''              | ''                 | 'CS22493F945'           |'R0603'| '(SMR0603AW)'                  | '2.49K'   | '1%'    | '1/10W'  | 'IO'       | 'RES CHIP 2.49K 1/10W +-1%(0603)'                  | 'CHIP0603'     | ''          | ''            | '20111227'
 '93.1'       | '1%'      | '1/16W'  | '0402LF'  | 'CHIP'   | 'CS09312FB00'(!)        = 'End of Design' | 'Comp-Approve'     | 'CS09312FB00'           |'R0402'| '(R0402-0201)'                 | '93.1'    | '1%'    | '1/16W'  | 'DISCRETE' | 'RES CHIP 93.1 1/16W +-1%(0402)'                   | 'CHIP0402'     | ''          | ''            | '20111230'
 '93.1'       | '1%'      | '1/16W'  | '0402LF'  | 'EMPTY'  | 'CS09312FB00'(!)        = 'End of Design' | 'Comp-Approve'     | 'CS09312FB00'           |'R0402'| '(R0402-0201)'                 | '93.1'    | '1%'    | '1/16W'  | 'IO'       | 'RES CHIP 93.1 1/16W +-1%(0402)'                   | 'CHIP0402'     | ''          | ''            | '20111230'
 '536'        | '1%'      | '1/8W'   | '0805LF'  | 'CHIP'   | 'CS15364FA00'(!)        = ''              | ''                 | 'CS15364FA00'           |'R0805'| '(SMR0805AW)'                  | '536'     | '1%'    | '1/8W'   | 'DISCRETE' | 'RES CHIP 536 1/8W(+-1%,0805)'                     | 'CHIP0805'     | ''          | ''            | '20111230'
 '536'        | '1%'      | '1/8W'   | '0805LF'  | 'EMPTY'  | 'CS15364FA00'(!)        = ''              | ''                 | 'CS15364FA00'           |'R0805'| '(SMR0805AW)'                  | '536'     | '1%'    | '1/8W'   | 'IO'       | 'RES CHIP 536 1/8W(+-1%,0805)'                     | 'CHIP0805'     | ''          | ''            | '20111230'
 '24K'        | '1%'      | '1/16W'  | '0402LF'  | 'CHIP'   | 'CS32402FB15'(!)        = 'End of Design' | 'Comp-Approve'     | 'CS32402FB15'           |'R0402'| '(R0402-0201)'                 | '24K'     | '1%'    | '1/16W'  | 'DISCRETE' | 'RES CHIP 24K 1/16W +-1%(0402)'                    | 'CHIP0402'     | ''          | ''            | '20111230'
 '24K'        | '1%'      | '1/16W'  | '0402LF'  | 'EMPTY'  | 'CS32402FB15'(!)        = 'End of Design' | 'Comp-Approve'     | 'CS32402FB15'           |'R0402'| '(R0402-0201)'                 | '24K'     | '1%'    | '1/16W'  | 'IO'       | 'RES CHIP 24K 1/16W +-1%(0402)'                    | 'CHIP0402'     | ''          | ''            | '20111230'
 '11.8K'      | '1%'      | '1/10W'  | '0603LF'  | 'CHIP'   | 'CS31183F914'(!)        = ''              | ''                 | 'CS31183F914'           |'R0603'| '(SMR0603AW)'                  | '11.8K'   | '1%'    | '1/10W'  | 'DISCRETE' | 'RES CHIP 11.8K 1/10W +-1%(0603)'                  | 'CHIP0603'     | ''          | ''            | '20111230'
 '11.8K'      | '1%'      | '1/10W'  | '0603LF'  | 'EMPTY'  | 'CS31183F914'(!)        = ''              | ''                 | 'CS31183F914'           |'R0603'| '(SMR0603AW)'                  | '11.8K'   | '1%'    | '1/10W'  | 'IO'       | 'RES CHIP 11.8K 1/10W +-1%(0603)'                  | 'CHIP0603'     | ''          | ''            | '20111230'
 '102K'       | '0.50%'   | '1/10W'  | '0603LF'  | 'CHIP'   | 'CS41023D900'(!)        = ''              | ''                 | 'CS41023D900'           |'R0603'| '(SMR0603AW)'                  | '102K'    | '0.50%' | '1/10W'  | 'DISCRETE' | 'RES CHIP 102K 1/10W +-0.5%(0603)'                 | 'CHIP0603'     | ''          | ''            | '20111230'
 '102K'       | '0.50%'   | '1/10W'  | '0603LF'  | 'EMPTY'  | 'CS41023D900'(!)        = ''              | ''                 | 'CS41023D900'           |'R0603'| '(SMR0603AW)'                  | '102K'    | '0.50%' | '1/10W'  | 'IO'       | 'RES CHIP 102K 1/10W +-0.5%(0603)'                 | 'CHIP0603'     | ''          | ''            | '20111230'
 '442'        | '1%'      | '1/10W'  | '0603LF'  | 'CHIP'   | 'CS14423F939'(!)        = ''              | ''                 | 'CS14423F939'           |'R0603'| '(SMR0603AW)'                  | '442'     | '1%'    | '1/10W'  | 'DISCRETE' | 'RES CHIP 442 1/10W +-1%(0603)EP'                  | 'CHIP0603'     | ''          | ''            | '20111230'
 '442'        | '1%'      | '1/10W'  | '0603LF'  | 'EMPTY'  | 'CS14423F939'(!)        = ''              | ''                 | 'CS14423F939'           |'R0603'| '(SMR0603AW)'                  | '442'     | '1%'    | '1/10W'  | 'IO'       | 'RES CHIP 442 1/10W +-1%(0603)EP'                  | 'CHIP0603'     | ''          | ''            | '20111230'
 '90.9K'      | '1%'      | '1/10W'  | '0603LF'  | 'CHIP'   | 'CS39093F917'(!)        = 'End of Design' | 'Comp-Approve'     | 'CS39093F917'           |'R0603'| '(SMR0603AW)'                  | '90.9K'   | '1%'    | '1/10W'  | 'DISCRETE' | 'RES CHIP 90.9K 1/10W+-1%(0603)'                   | 'CHIP0603'     | ''          | ''            | '20120109'
 '90.9K'      | '1%'      | '1/10W'  | '0603LF'  | 'EMPTY'  | 'CS39093F917'(!)        = 'End of Design' | 'Comp-Approve'     | 'CS39093F917'           |'R0603'| '(SMR0603AW)'                  | '90.9K'   | '1%'    | '1/10W'  | 'IO'       | 'RES CHIP 90.9K 1/10W+-1%(0603)'                   | 'CHIP0603'     | ''          | ''            | '20120109'
 '91K'        | '1%'      | '1/16W'  | '0402LF'  | 'CHIP'   | 'CS39102FB05'(!)        = 'End of Design' | 'Comp-Approve'     | 'CS39102FB05'           |'R0402'| '(R0402-0201)'                 | '91K'     | '1%'    | '1/16W'  | 'DISCRETE' | 'RES CHIP 91K 1/16W +-1%(0402)'                    | 'CHIP0402'     | ''          | ''            | '20120109'
 '91K'        | '1%'      | '1/16W'  | '0402LF'  | 'EMPTY'  | 'CS39102FB05'(!)        = 'End of Design' | 'Comp-Approve'     | 'CS39102FB05'           |'R0402'| '(R0402-0201)'                 | '91K'     | '1%'    | '1/16W'  | 'IO'       | 'RES CHIP 91K 1/16W +-1%(0402)'                    | 'CHIP0402'     | ''          | ''            | '20120109'
 '2.1K'       | '1%'      | '1/16W'  | '0402LF'  | 'CHIP'   | 'CS22102FB12'(!)        = 'End of Design' | 'Comp-Approve'     | 'CS22102FB12'           |'R0402'| '(R0402-0201)'                 | '2.1K'    | '1%'    | '1/16W'  | 'DISCRETE' | 'RES CHIP 2.1K 1/16W +-1%(0402)'                   | 'CHIP0402'     | ''          | ''            | '20120110'
 '2.1K'       | '1%'      | '1/16W'  | '0402LF'  | 'EMPTY'  | 'CS22102FB12'(!)        = 'End of Design' | 'Comp-Approve'     | 'CS22102FB12'           |'R0402'| '(R0402-0201)'                 | '2.1K'    | '1%'    | '1/16W'  | 'IO'       | 'RES CHIP 2.1K 1/16W +-1%(0402)'                   | 'CHIP0402'     | ''          | ''            | '20120110'
 '210'        | '1%'      | '1/16W'  | '0402LF'  | 'CHIP'   | 'CS12102FB11'(!)        = 'End of Design' | 'Comp-Approve'     | 'CS12102FB11'           |'R0402'| '(R0402-0201)'                 | '210'     | '1%'    | '1/16W'  | 'DISCRETE' | 'RES CHIP 210 1/16W 1%(0402)'                      | 'CHIP0402'     | ''          | ''            | '20120113'
 '210'        | '1%'      | '1/16W'  | '0402LF'  | 'EMPTY'  | 'CS12102FB11'(!)        = 'End of Design' | 'Comp-Approve'     | 'CS12102FB11'           |'R0402'| '(R0402-0201)'                 | '210'     | '1%'    | '1/16W'  | 'IO'       | 'RES CHIP 210 1/16W 1%(0402)'                      | 'CHIP0402'     | ''          | ''            | '20120113'
 '44.2K'      | '1%'      | '1/16W'  | '0402LF'  | 'CHIP'   | 'CS34422FB00'(!)        = 'End of Design' | 'Comp-Approve'     | 'CS34422FB00'           |'R0402'| '(R0402-0201)'                 | '44.2K'   | '1%'    | '1/16W'  | 'DISCRETE' | 'RES CHIP 44.2K 1/16W +-1%(0402)'                  | 'CHIP0402'     | ''          | ''            | '20120114'
 '44.2K'      | '1%'      | '1/16W'  | '0402LF'  | 'EMPTY'  | 'CS34422FB00'(!)        = 'End of Design' | 'Comp-Approve'     | 'CS34422FB00'           |'R0402'| '(R0402-0201)'                 | '44.2K'   | '1%'    | '1/16W'  | 'IO'       | 'RES CHIP 44.2K 1/16W +-1%(0402)'                  | 'CHIP0402'     | ''          | ''            | '20120114'
 '174K'       | '1%'      | '1/16W'  | '0402LF'  | 'CHIP'   | 'CS41742FB13'(!)        = 'End of Design' | 'Comp-Approve'     | 'CS41742FB13'           |'R0402'| '(R0402-0201)'                 | '174K'    | '1%'    | '1/16W'  | 'DISCRETE' | 'RES CHIP 174K 1/16W +-1%(0402)'                   | 'CHIP0402'     | ''          | ''            | '20120114'
 '174K'       | '1%'      | '1/16W'  | '0402LF'  | 'EMPTY'  | 'CS41742FB13'(!)        = 'End of Design' | 'Comp-Approve'     | 'CS41742FB13'           |'R0402'| '(R0402-0201)'                 | '174K'    | '1%'    | '1/16W'  | 'IO'       | 'RES CHIP 174K 1/16W +-1%(0402)'                   | 'CHIP0402'     | ''          | ''            | '20120114'
 '1'          | '5%'      | '1/16W'  | '0402LF'  | 'CHIP'   | 'CS-1002JB17'(!)        = 'End of Design' | 'Comp-Approve'     | 'CS-1002JB17'           |'R0402'| '(R0402-0201)'                 | '1'       | '5%'    | '1/16W'  | 'DISCRETE' | 'RES CHIP 1 1/16W +-5%(0402)'                      | 'CHIP0402'     | ''          | ''            | '20120114'
 '1'          | '5%'      | '1/16W'  | '0402LF'  | 'EMPTY'  | 'CS-1002JB17'(!)        = 'End of Design' | 'Comp-Approve'     | 'CS-1002JB17'           |'R0402'| '(R0402-0201)'                 | '1'       | '5%'    | '1/16W'  | 'IO'       | 'RES CHIP 1 1/16W +-5%(0402)'                      | 'CHIP0402'     | ''          | ''            | '20120114'
 '56.2'       | '1%'      | '1/4W'   | '1206LF'  | 'CHIP'   | 'CS05626F216'(!)        = ''              | ''                 | 'CS05626F216'           |'R1206'| '(SMR1206AW)'                  | '56.2'    | '1%'    | '1/4W'   | 'DISCRETE' | 'RESISTOR CHIP 56.2 1/4W +-1%(1206)EP'             | 'CHIP1206'     | ''          | ''            | '20120114'
 '56.2'       | '1%'      | '1/4W'   | '1206LF'  | 'EMPTY'  | 'CS05626F216'(!)        = ''              | ''                 | 'CS05626F216'           |'R1206'| '(SMR1206AW)'                  | '56.2'    | '1%'    | '1/4W'   | 'IO'       | 'RESISTOR CHIP 56.2 1/4W +-1%(1206)EP'             | 'CHIP1206'     | ''          | ''            | '20120114'
 '16.9K'      | '1%'      | '1/16W'  | '0402LF'  | 'CHIP'   | 'CS31692FB11'(!)        = 'End of Design' | 'Comp-Approve'     | 'CS31692FB11'           |'R0402'| '(R0402-0201)'                 | '16.9K'   | '1%'    | '1/16W'  | 'DISCRETE' | 'RES CHIP 16.9K 1/16W +-1% (0402)'                 | 'CHIP0402'     | ''          | ''            | '20120119'
 '16.9K'      | '1%'      | '1/16W'  | '0402LF'  | 'EMPTY'  | 'CS31692FB11'(!)        = 'End of Design' | 'Comp-Approve'     | 'CS31692FB11'           |'R0402'| '(R0402-0201)'                 | '16.9K'   | '1%'    | '1/16W'  | 'IO'       | 'RES CHIP 16.9K 1/16W +-1% (0402)'                 | 'CHIP0402'     | ''          | ''            | '20120119'
 '191K'       | '1%'      | '1/16W'  | '0402LF'  | 'CHIP'   | 'CS41912FB17'(!)        = 'End of Design' | 'Comp-Approve'     | 'CS41912FB17'           |'R0402'| '(R0402-0201)'                 | '191K'    | '1%'    | '1/16W'  | 'DISCRETE' | 'RES CHIP 191K 1/16W +-1%(0402)'                   | 'CHIP0402'     | ''          | ''            | '20120119'
 '191K'       | '1%'      | '1/16W'  | '0402LF'  | 'EMPTY'  | 'CS41912FB17'(!)        = 'End of Design' | 'Comp-Approve'     | 'CS41912FB17'           |'R0402'| '(R0402-0201)'                 | '191K'    | '1%'    | '1/16W'  | 'IO'       | 'RES CHIP 191K 1/16W +-1%(0402)'                   | 'CHIP0402'     | ''          | ''            | '20120119'
 '154K'       | '1%'      | '1/16W'  | '0402LF'  | 'CHIP'   | 'CS41542FB16'(!)        = 'End of Design' | 'Comp-Approve'     | 'CS41542FB16'           |'R0402'| '(R0402-0201)'                 | '154K'    | '1%'    | '1/16W'  | 'DISCRETE' | 'RES CHIP 154K 1/16W +1%(0402)'                    | 'CHIP0402'     | ''          | ''            | '20120119'
 '154K'       | '1%'      | '1/16W'  | '0402LF'  | 'EMPTY'  | 'CS41542FB16'(!)        = 'End of Design' | 'Comp-Approve'     | 'CS41542FB16'           |'R0402'| '(R0402-0201)'                 | '154K'    | '1%'    | '1/16W'  | 'IO'       | 'RES CHIP 154K 1/16W +1%(0402)'                    | 'CHIP0402'     | ''          | ''            | '20120119'
 '4.99'       | '1%'      | '1/10W'  | '0603LF'  | 'CHIP'   | 'CS-4993F913'(!)        = ''              | ''                 | 'CS-4993F913'           |'R0603'| '(SMR0603AW)'                  | '4.99'    | '1%'    | '1/10W'  | 'DISCRETE' | 'RES CHIP 4.99 1/10W +-1%(0603)'                   | 'CHIP0603'     | ''          | ''            | '20120119'
 '4.99'       | '1%'      | '1/10W'  | '0603LF'  | 'EMPTY'  | 'CS-4993F913'(!)        = ''              | ''                 | 'CS-4993F913'           |'R0603'| '(SMR0603AW)'                  | '4.99'    | '1%'    | '1/10W'  | 'IO'       | 'RES CHIP 4.99 1/10W +-1%(0603)'                   | 'CHIP0603'     | ''          | ''            | '20120119'
 '249K'       | '1%'      | '1/16W'  | '0402LF'  | 'CHIP'   | 'CS42492FB00'(!)        = 'End of Design' | 'Comp-Approve'     | 'CS42492FB00'           |'R0402'| '(R0402-0201)'                 | '249K'    | '1%'    | '1/16W'  | 'DISCRETE' | 'RES CHIP 249K 1/16W +-1%(0402)'                   | 'CHIP0402'     | ''          | ''            | '20120120'
 '249K'       | '1%'      | '1/16W'  | '0402LF'  | 'EMPTY'  | 'CS42492FB00'(!)        = 'End of Design' | 'Comp-Approve'     | 'CS42492FB00'           |'R0402'| '(R0402-0201)'                 | '249K'    | '1%'    | '1/16W'  | 'IO'       | 'RES CHIP 249K 1/16W +-1%(0402)'                   | 'CHIP0402'     | ''          | ''            | '20120120'
 '19.1K'      | '1%'      | '1/16W'  | '0402LF'  | 'CHIP'   | 'CS31912FB15'(!)        = 'End of Design' | 'Comp-Approve'     | 'CS31912FB15'           |'R0402'| '(R0402-0201)'                 | '19.1K'   | '1%'    | '1/16W'  | 'DISCRETE' | 'RES CHIP 19.1K 1/16W +-1%(0402)'                  | 'CHIP0402'     | ''          | ''            | '20120120'
 '19.1K'      | '1%'      | '1/16W'  | '0402LF'  | 'EMPTY'  | 'CS31912FB15'(!)        = 'End of Design' | 'Comp-Approve'     | 'CS31912FB15'           |'R0402'| '(R0402-0201)'                 | '19.1K'   | '1%'    | '1/16W'  | 'IO'       | 'RES CHIP 19.1K 1/16W +-1%(0402)'                  | 'CHIP0402'     | ''          | ''            | '20120120'
 '16.5K'      | '1%'      | '1/16W'  | '0402LF'  | 'CHIP'   | 'CS31652FB12'(!)        = 'End of Design' | 'Comp-Approve'     | 'CS31652FB12'           |'R0402'| '(R0402-0201)'                 | '16.5K'   | '1%'    | '1/16W'  | 'DISCRETE' | 'RES CHIP 16.5K 1/16W +-1% (0402)'                 | 'CHIP0402'     | ''          | ''            | '20120120'
 '16.5K'      | '1%'      | '1/16W'  | '0402LF'  | 'EMPTY'  | 'CS31652FB12'(!)        = 'End of Design' | 'Comp-Approve'     | 'CS31652FB12'           |'R0402'| '(R0402-0201)'                 | '16.5K'   | '1%'    | '1/16W'  | 'IO'       | 'RES CHIP 16.5K 1/16W +-1% (0402)'                 | 'CHIP0402'     | ''          | ''            | '20120120'
 '26.1K'      | '1%'      | '1/16W'  | '0402LF'  | 'CHIP'   | 'CS32612FB09'(!)        = 'End of Design' | 'Comp-Approve'     | 'CS32612FB09'           |'R0402'| '(R0402-0201)'                 | '26.1K'   | '1%'    | '1/16W'  | 'DISCRETE' | 'RES CHIP 26.1K 1/16W +-1%(0402)'                  | 'CHIP0402'     | ''          | ''            | '20120120'
 '26.1K'      | '1%'      | '1/16W'  | '0402LF'  | 'EMPTY'  | 'CS32612FB09'(!)        = 'End of Design' | 'Comp-Approve'     | 'CS32612FB09'           |'R0402'| '(R0402-0201)'                 | '26.1K'   | '1%'    | '1/16W'  | 'IO'       | 'RES CHIP 26.1K 1/16W +-1%(0402)'                  | 'CHIP0402'     | ''          | ''            | '20120120'
 '249'        | '1%'      | '1/16W'  | '0402LF'  | 'CHIP'   | 'CS12492FB12'(!)        = 'End of Design' | 'Comp-Approve'     | 'CS12492FB12'           |'R0402'| '(R0402-0201)'                 | '249'     | '1%'    | '1/16W'  | 'DISCRETE' | 'RES CHIP 249 1/16W +-1%(0402)'                    | 'CHIP0402'     | ''          | ''            | '20120120'
 '249'        | '1%'      | '1/16W'  | '0402LF'  | 'EMPTY'  | 'CS12492FB12'(!)        = 'End of Design' | 'Comp-Approve'     | 'CS12492FB12'           |'R0402'| '(R0402-0201)'                 | '249'     | '1%'    | '1/16W'  | 'IO'       | 'RES CHIP 249 1/16W +-1%(0402)'                    | 'CHIP0402'     | ''          | ''            | '20120120'
 '205'        | '1%'      | '1/16W'  | '0402LF'  | 'CHIP'   | 'CS12052FB10'(!)        = 'End of Design' | 'Comp-Release Qty' | 'CS12052FB10'           |'R0402'| '(R0402-0201)'                 | '205'     | '1%'    | '1/16W'  | 'DISCRETE' | 'RES CHIP 205(1/16W.+-1%.0402)'                    | 'CHIP0402'     | ''          | ''            | '20120120'
 '205'        | '1%'      | '1/16W'  | '0402LF'  | 'EMPTY'  | 'CS12052FB10'(!)        = 'End of Design' | 'Comp-Release Qty' | 'CS12052FB10'           |'R0402'| '(R0402-0201)'                 | '205'     | '1%'    | '1/16W'  | 'IO'       | 'RES CHIP 205(1/16W.+-1%.0402)'                    | 'CHIP0402'     | ''          | ''            | '20120120'
 '200K'       | '5%'      | '1/16W'  | '0402LF'  | 'CHIP'   | 'CS42002JB14'(!)        = 'End of Design' | 'Comp-Approve'     | 'CS42002JB14'           |'R0402'| '(R0402-0201)'                 | '200K'    | '5%'    | '1/16W'  | 'DISCRETE' | 'RES CHIP 200K 1/16W +-5%(0402)'                   | 'CHIP0402'     | ''          | ''            | '20120131'
 '200K'       | '5%'      | '1/16W'  | '0402LF'  | 'EMPTY'  | 'CS42002JB14'(!)        = 'End of Design' | 'Comp-Approve'     | 'CS42002JB14'           |'R0402'| '(R0402-0201)'                 | '200K'    | '5%'    | '1/16W'  | 'IO'       | 'RES CHIP 200K 1/16W +-5%(0402)'                   | 'CHIP0402'     | ''          | ''            | '20120131'
 '9.09K'      | '1%'      | '1/16W'  | '0402LF'  | 'CHIP'   | 'CS29092FB27'(!)        = 'End of Design' | 'Comp-Approve'     | 'CS29092FB27'           |'R0402'| '(R0402-0201)'                 | '9.09K'   | '1%'    | '1/16W'  | 'DISCRETE' | 'RES CHIP 9.09K 1/16W +-1%(0402)'                  | 'CHIP0402'     | ''          | ''            | '20120207'
 '9.09K'      | '1%'      | '1/16W'  | '0402LF'  | 'EMPTY'  | 'CS29092FB27'(!)        = 'End of Design' | 'Comp-Approve'     | 'CS29092FB27'           |'R0402'| '(R0402-0201)'                 | '9.09K'   | '1%'    | '1/16W'  | 'IO'       | 'RES CHIP 9.09K 1/16W +-1%(0402)'                  | 'CHIP0402'     | ''          | ''            | '20120207'
 '1.21M'      | '1%'      | '1/16W'  | '0402LF'  | 'CHIP'   | 'CS51212FB00'(!)        = ''              | ''                 | 'CS51212FB00'           |'R0402'| '(R0402-0201)'                 | '1.21M'   | '1%'    | '1/16W'  | 'DISCRETE' | 'RES CHIP 1.21M 1/16W +-1%(0402)'                  | 'CHIP0402'     | ''          | ''            | '20120202'
 '1.21M'      | '1%'      | '1/16W'  | '0402LF'  | 'EMPTY'  | 'CS51212FB00'(!)        = ''              | ''                 | 'CS51212FB00'           |'R0402'| '(R0402-0201)'                 | '1.21M '  | '1%'    | '1/16W'  | 'IO'       | 'RES CHIP 1.21M 1/16W +-1%(0402)'                  | 'CHIP0402'     | ''          | ''            | '20120202'
 '301K'       | '1%'      | '1/16W'  | '0402LF'  | 'CHIP'   | 'CS43012FB10'(!)        = 'End of Design' | 'Comp-Approve'     | 'CS43012FB10'           |'R0402'| '(R0402-0201)'                 | '301K  '  | '1%'    | '1/16W'  | 'DISCRETE' | 'RES CHIP 301K 1/16W +-1%( 0402)'                  | 'CHIP0402'     | ''          | ''            | '20120202'
 '301K'       | '1%'      | '1/16W'  | '0402LF'  | 'EMPTY'  | 'CS43012FB10'(!)        = 'End of Design' | 'Comp-Approve'     | 'CS43012FB10'           |'R0402'| '(R0402-0201)'                 | '301K'    | '1%'    | '1/16W'  | 'IO'       | 'RES CHIP 301K 1/16W +-1%( 0402)'                  | 'CHIP0402'     | ''          | ''            | '20120202'
 '43.2'       | '1%'      | '1/16W'  | '0402LF'  | 'CHIP'   | 'CS04322FB11'(!)        = 'End of Design' | 'Comp-Approve'     | 'CS04322FB11'           |'R0402'| '(R0402-0201)'                 | '43.2'    | '1%'    | '1/16W'  | 'DISCRETE' | 'RES CHIP 43.2 1/16W +-1%(0402)'                   | 'CHIP0402'     | ''          | ''            | '20120210'
 '43.2'       | '1%'      | '1/16W'  | '0402LF'  | 'EMPTY'  | 'CS04322FB11'(!)        = 'End of Design' | 'Comp-Approve'     | 'CS04322FB11'           |'R0402'| '(R0402-0201)'                 | '43.2'    | '1%'    | '1/16W'  | 'IO'       | 'RES CHIP 43.2 1/16W +-1%(0402)'                   | 'CHIP0402'     | ''          | ''            | '20120210'
 '14K'        | '1%'      | '1/16W'  | '0402LF'  | 'CHIP'   | 'CS31402FB04'(!)        = ''              | ''                 | 'CS31402FB04'           |'R0402'| '(R0402-0201)'                 | '14K'     | '1%'    | '1/16W'  | 'DISCRETE' | 'RES CHIP 14K +-1% 1/16W(0402)'                    | 'CHIP0402'     | ''          | ''            | '20120210'
 '14K'        | '1%'      | '1/16W'  | '0402LF'  | 'EMPTY'  | 'CS31402FB04'(!)        = ''              | ''                 | 'CS31402FB04'           |'R0402'| '(R0402-0201)'                 | '14K'     | '1%'    | '1/16W'  | 'IO'       | 'RES CHIP 14K +-1% 1/16W(0402)'                    | 'CHIP0402'     | ''          | ''            | '20120210'
 '0.00025'    | '1%'      | '4W'     | '2725LF'  | 'CHIP'   | 'CS0000FFT00'(!)        = 'End of Design' | 'Comp-Approve'     | 'CS0000FFT00'           |'R2725'| '(SMR2725AW)'                  | '0.00025' | '1%'    | '4W'     | 'DISCRETE' | 'RES CHIP 0.00025 4W +-1%(2725)H0.99'              | 'CHIP2725'     | ''          | ''            | '20120216'
 '0.00025'    | '1%'      | '4W'     | '2725LF'  | 'EMPTY'  | 'CS0000FFT00'(!)        = 'End of Design' | 'Comp-Approve'     | 'CS0000FFT00'           |'R2725'| '(SMR2725AW)'                  | '0.00025' | '1%'    | '4W'     | 'IO'       | 'RES CHIP 0.00025 4W +-1%(2725)H0.99'              | 'CHIP2725'     | ''          | ''            | '20120216'
 '300K'       | '1%'      | '1/16W'  | '0402LF'  | 'CHIP'   | 'CS43002FB15'(!)        = 'End of Design' | 'Comp-Approve'     | 'CS43002FB15'           |'R0402'| '(R0402-0201)'                 | '300K'    | '1%'    | '1/16W'  | 'DISCRETE' | 'RES CHIP 300K +-1% 1/16W(0402)'                   | 'CHIP0402'     | ''          | ''            | '20120215'
 '300K'       | '1%'      | '1/16W'  | '0402LF'  | 'EMPTY'  | 'CS43002FB15'(!)        = 'End of Design' | 'Comp-Approve'     | 'CS43002FB15'           |'R0402'| '(R0402-0201)'                 | '300K'    | '1%'    | '1/16W'  | 'IO'       | 'RES CHIP 300K +-1% 1/16W(0402)'                   | 'CHIP0402'     | ''          | ''            | '20120215'
 '169K'       | '1%'      | '1/16W'  | '0402LF'  | 'CHIP'   | 'CS41692FB12'(!)        = 'End of Design' | 'Comp-Approve'     | 'CS41692FB12'           |'R0402'| '(R0402-0201)'                 | '169K'    | '1%'    | '1/16W'  | 'DISCRETE' | 'RES CHIP 169K +-1% 1/16W(0402)'                   | 'CHIP0402'     | ''          | ''            | '20120215'
 '169K'       | '1%'      | '1/16W'  | '0402LF'  | 'EMPTY'  | 'CS41692FB12'(!)        = 'End of Design' | 'Comp-Approve'     | 'CS41692FB12'           |'R0402'| '(R0402-0201)'                 | '169K'    | '1%'    | '1/16W'  | 'IO'       | 'RES CHIP 169K +-1% 1/16W(0402)'                   | 'CHIP0402'     | ''          | ''            | '20120215'
 '3.3'        | '1%'      | '1/10W'  | '0603LF'  | 'CHIP'   | 'CS-3303F918'(!)        = 'End of Design' | 'Comp-Approve'     | 'CS-3303F918'           |'R0603'| '(SMR0603AW)'                  | '3.3'     | '1%'    | '1/10W'  | 'DISCRETE' | 'RES CHIP 3.3 1/10W +-1% (0603) EP'                | 'CHIP0603'     | ''          | ''            | '20120215'
 '3.3'        | '1%'      | '1/10W'  | '0603LF'  | 'EMPTY'  | 'CS-3303F918'(!)        = 'End of Design' | 'Comp-Approve'     | 'CS-3303F918'           |'R0603'| '(SMR0603AW)'                  | '3.3'     | '1%'    | '1/10W'  | 'IO'       | 'RES CHIP 3.3 1/10W +-1% (0603) EP'                | 'CHIP0603'     | ''          | ''            | '20120215'
 '0.009'      | '1%'      | '1W'     | '2512LF'  | 'CHIP'   | 'CS00008FR00'(!)        = ''              | ''                 | 'CS00008FR00'           |'R2512XD'| '(SMR2512AW)'                  | '0.009'   | '1%'    | '1W'     | 'DISCRETE' | 'RES CHIP 0.009 1W +-1%(2512)H0.787'               | 'CHIP2512'     | ''          | ''            | '20120216'
 '0.009'      | '1%'      | '1W'     | '2512LF'  | 'EMPTY'  | 'CS00008FR00'(!)        = ''              | ''                 | 'CS00008FR00'           |'R2512XD'| '(SMR2512AW)'                  | '0.009'   | '1%'    | '1W'     | 'IO'       | 'RES CHIP 0.009 1W +-1%(2512)H0.787'               | 'CHIP2512'     | ''          | ''            | '20120216'
 '90.9'       | '1%'      | '1/16W'  | '0402LF'  | 'CHIP'   | 'CS09092FB15'(!)        = 'End of Design' | 'Comp-Approve'     | 'CS09092FB15'           |'R0402'| '(R0402-0201)'                 | '90.9'    | '1%'    | '1/16W'  | 'DISCRETE' | 'RES CHIP 90.9 1/16W +-1%(0402)'                   | 'CHIP0402'     | ''          | ''            | '20120221'
 '90.9'       | '1%'      | '1/16W'  | '0402LF'  | 'EMPTY'  | 'CS09092FB15'(!)        = 'End of Design' | 'Comp-Approve'     | 'CS09092FB15'           |'R0402'| '(R0402-0201)'                 | '90.9'    | '1%'    | '1/16W'  | 'IO'       | 'RES CHIP 90.9 1/16W +-1%(0402)'                   | 'CHIP0402'     | ''          | ''            | '20120221'
 '0.008'      | '1%'      | '2W'     | '2512LF'  | 'CHIP'   | 'CS+008AFR00'(!)        = ''              | ''                 | 'CS+008AFR00'           |'R2512'| '(SMR2512AW)'                  | '0.008'   | '1%'    | '2W'     | 'DISCRETE' | 'RES CHIP 0.008 2W +-1%(2512)'                     | 'CHIP2512'     | ''          | ''            | '20120222'
 '0.008'      | '1%'      | '2W'     | '2512LF'  | 'EMPTY'  | 'CS+008AFR00'(!)        = ''              | ''                 | 'CS+008AFR00'           |'R2512'| '(SMR2512AW)'                  | '0.008'   | '1%'    | '2W'     | 'IO'       | 'RES CHIP 0.008 2W +-1%(2512)'                     | 'CHIP2512'     | ''          | ''            | '20120222'
 '0.008'      | '1%'      | '2W'     | '2512LF'  | 'CHIP'   | 'CS+008AFR01'(!)        = ''              | ''                 | 'CS+008AFR01'           |'R2512'| '(SMR2512AW)'                  | '0.008'   | '1%'    | '2W'     | 'DISCRETE' | 'RES CHIP 0.008 2W +-1%(2512)HF'                   | 'CHIP2512'     | ''          | ''            | '20120222'
 '0.008'      | '1%'      | '2W'     | '2512LF'  | 'EMPTY'  | 'CS+008AFR01'(!)        = ''              | ''                 | 'CS+008AFR01'           |'R2512'| '(SMR2512AW)'                  | '0.008'   | '1%'    | '2W'     | 'IO'       | 'RES CHIP 0.008 2W +-1%(2512)HF'                   | 'CHIP2512'     | ''          | ''            | '20120222'
 '107K'       | '1%'      | '1/16W'  | '0402LF'  | 'CHIP'   | 'CS41072FB11'(!)        = 'End of Design' | 'Comp-Approve'     | 'CS41072FB11'           |'R0402'| '(R0402-0201)'                 | '107K'    | '1%'    | '1/16W'  | 'DISCRETE' | 'RES CHIP 107K 1/16W +-1%(0402)'                   | 'CHIP0402'     | ''          | ''            | '20120222'
 '107K'       | '1%'      | '1/16W'  | '0402LF'  | 'EMPTY'  | 'CS41072FB11'(!)        = 'End of Design' | 'Comp-Approve'     | 'CS41072FB11'           |'R0402'| '(R0402-0201)'                 | '107K'    | '1%'    | '1/16W'  | 'IO'       | 'RES CHIP 107K 1/16W +-1%(0402)'                   | 'CHIP0402'     | ''          | ''            | '20120222'
 '13'         | '1%'      | '1/16W'  | '0402LF'  | 'CHIP'   | 'CS01302FB05'(!)        = 'End of Design' | 'Comp-Approve'     | 'CS01302FB05'           |'R0402'| '(R0402-0201)'                 | '13'      | '1%'    | '1/16W'  | 'DISCRETE' | 'RES CHIP 13 1/16W +-1%(0402)'                     | 'CHIP0402'     | ''          | ''            | '20120228'
 '13'         | '1%'      | '1/16W'  | '0402LF'  | 'EMPTY'  | 'CS01302FB05'(!)        = 'End of Design' | 'Comp-Approve'     | 'CS01302FB05'           |'R0402'| '(R0402-0201)'                 | '13'      | '1%'    | '1/16W'  | 'IO'       | 'RES CHIP 13 1/16W +-1%(0402)'                     | 'CHIP0402'     | ''          | ''            | '20120228'
 '6.8'        | '1%'      | '1/16W'  | '0402LF'  | 'CHIP'   | 'CS-6802FB00'(!)        = 'End of Design' | 'Comp-Approve'     | 'CS-6802FB00'           |'R0402'| '(R0402-0201)'                 | '6.8'     | '1%'    | '1/16W'  | 'DISCRETE' | 'RES CHIP 6.8 1/16W +-1%(0402)'                    | 'CHIP0402'     | ''          | ''            | '20120228'
 '6.8'        | '1%'      | '1/16W'  | '0402LF'  | 'EMPTY'  | 'CS-6802FB00'(!)        = 'End of Design' | 'Comp-Approve'     | 'CS-6802FB00'           |'R0402'| '(R0402-0201)'                 | '6.8'     | '1%'    | '1/16W'  | 'IO'       | 'RES CHIP 6.8 1/16W +-1%(0402)'                    | 'CHIP0402'     | ''          | ''            | '20120228'
 '3.83K'      | '1%'      | '1/16W'  | '0402LF'  | 'CHIP'   | 'CS23832FB01'(!)        = 'End of Design' | 'Comp-Approve'     | 'CS23832FB01'           |'R0402'| '(R0402-0201)'                 | '3.83K'   | '1%'    | '1/16W'  | 'DISCRETE' | 'RES CHIP 3.83K 1/16W +-1%(0402)'                  | 'CHIP0402'     | ''          | ''            | '20120304'
 '3.83K'      | '1%'      | '1/16W'  | '0402LF'  | 'EMPTY'  | 'CS23832FB01'(!)        = 'End of Design' | 'Comp-Approve'     | 'CS23832FB01'           |'R0402'| '(R0402-0201)'                 | '3.83K'   | '1%'    | '1/16W'  | 'IO'       | 'RES CHIP 3.83K 1/16W +-1%(0402)'                  | 'CHIP0402'     | ''          | ''            | '20120304'
 '95.3K'      | '1%'      | '1/16W'  | '0402LF'  | 'CHIP'   | 'CS39532FB03'(!)        = 'End of Design' | 'Comp-Approve'     | 'CS39532FB03'           |'R0402'| '(R0402-0201)'                 | '95.3K'   | '1%'    | '1/16W'  | 'DISCRETE' | 'RESISTOR CHIP 95.3K,1/16W,+-1%(0402)'             | 'CHIP0402'     | ''          | ''            | '20120304'
 '95.3K'      | '1%'      | '1/16W'  | '0402LF'  | 'EMPTY'  | 'CS39532FB03'(!)        = 'End of Design' | 'Comp-Approve'     | 'CS39532FB03'           |'R0402'| '(R0402-0201)'                 | '95.3K'   | '1%'    | '1/16W'  | 'IO'       | 'RESISTOR CHIP 95.3K,1/16W,+-1%(0402)'             | 'CHIP0402'     | ''          | ''            | '20120304'
 '453K'       | '1%'      | '1/16W'  | '0402LF'  | 'CHIP'   | 'CS44532FB10'(!)        = 'End of Design' | 'Comp-Approve'     | 'CS44532FB10'           |'R0402'| '(R0402-0201)'                 | '453K'    | '1%'    | '1/16W'  | 'DISCRETE' | 'RES CHIP 453K 1/16W +-1%(0402)'                   | 'CHIP0402'     | ''          | ''            | '20120304'
 '453K'       | '1%'      | '1/16W'  | '0402LF'  | 'EMPTY'  | 'CS44532FB10'(!)        = 'End of Design' | 'Comp-Approve'     | 'CS44532FB10'           |'R0402'| '(R0402-0201)'                 | '453K'    | '1%'    | '1/16W'  | 'IO'       | 'RES CHIP 453K 1/16W +-1%(0402)'                   | 'CHIP0402'     | ''          | ''            | '20120304'
 '7.68K'      | '1%'      | '1/16W'  | '0402LF'  | 'CHIP'   | 'CS27682FB11'(!)        = 'End of Design' | 'Comp-Approve'     | 'CS27682FB11'           |'R0402'| '(R0402-0201)'                 | '7.68K'   | '1%'    | '1/16W'  | 'DISCRETE' | 'RES CHIP 7.68K 1/16W +-1%(0402)'                  | 'CHIP0402'     | ''          | ''            | '20120304'
 '7.68K'      | '1%'      | '1/16W'  | '0402LF'  | 'EMPTY'  | 'CS27682FB11'(!)        = 'End of Design' | 'Comp-Approve'     | 'CS27682FB11'           |'R0402'| '(R0402-0201)'                 | '7.68K'   | '1%'    | '1/16W'  | 'IO'       | 'RES CHIP 7.68K 1/16W +-1%(0402)'                  | 'CHIP0402'     | ''          | ''            | '20120304'
 '0.0005'     | '1%'      | '2W'     | '2512LF'  | 'CHIP'   | 'CS0000AFR00'(!)        = ''              | ''                 | 'CS0000AFR00'           |'R2512XD'| '(SMR2512AW)'                  | '0.0005'  | '1%'    | '2W'     | 'DISCRETE' | 'RES CHIP 0.0005 2W +-1%(2512)'                    | 'CHIP2512'     | ''          | ''            | '20120627'
 '0.0005'     | '1%'      | '2W'     | '2512LF'  | 'EMPTY'  | 'CS0000AFR00'(!)        = ''              | ''                 | 'CS0000AFR00'           |'R2512XD'| '(SMR2512AW)'                  | '0.0005'  | '1%'    | '2W'     | 'IO'       | 'RES CHIP 0.0005 2W +-1%(2512)'                    | 'CHIP2512'     | ''          | ''            | '20120627'
 '240'        | '1%'      | '1/10W'  | '0603LF'  | 'CHIP'   | 'CS12403F918'(!)        = ''              | ''                 | 'CS12403F918'           |'R0603'| '(SMR0603AW)'                  | '240'     | '1%'    | '1/10W'  | 'DISCRETE' | 'RES CHIP 240 1/10W +-1%(0603)'                    | 'CHIP0603'     | ''          | ''            | '20120310'
 '240'        | '1%'      | '1/10W'  | '0603LF'  | 'EMPTY'  | 'CS12403F918'(!)        = ''              | ''                 | 'CS12403F918'           |'R0603'| '(SMR0603AW)'                  | '240'     | '1%'    | '1/10W'  | 'IO'       | 'RES CHIP 240 1/10W +-1%(0603)'                    | 'CHIP0603'     | ''          | ''            | '20120310'
 '6.34K'      | '1%'      | '1/16W'  | '0402LF'  | 'CHIP'   | 'CS26342FB27'(!)        = 'End of Design' | 'Comp-Approve'     | 'CS26342FB27'           |'R0402'| '(R0402-0201)'                 | '6.34K'   | '1%'    | '1/16W'  | 'DISCRETE' | 'RES CHIP 6.34K 1/16W +-1%(0402)'                  | 'CHIP0402'     | ''          | ''            | '20120314'
 '6.34K'      | '1%'      | '1/16W'  | '0402LF'  | 'EMPTY'  | 'CS26342FB27'(!)        = 'End of Design' | 'Comp-Approve'     | 'CS26342FB27'           |'R0402'| '(R0402-0201)'                 | '6.34K'   | '1%'    | '1/16W'  | 'IO'       | 'RES CHIP 6.34K 1/16W +-1%(0402)'                  | 'CHIP0402'     | ''          | ''            | '20120314'
 '9.76K'      | '1%'      | '1/16W'  | '0402LF'  | 'CHIP'   | 'CS29762FB00'(!)        = 'End of Design' | 'Comp-Approve'     | 'CS29762FB00'           |'R0402'| '(R0402-0201)'                 | '9.76K'   | '1%'    | '1/16W'  | 'DISCRETE' | 'RES CHIP 9.76K 1/16W +-1%(0402)'                  | 'CHIP0402'     | ''          | ''            | '20120314'
 '9.76K'      | '1%'      | '1/16W'  | '0402LF'  | 'EMPTY'  | 'CS29762FB00'(!)        = 'End of Design' | 'Comp-Approve'     | 'CS29762FB00'           |'R0402'| '(R0402-0201)'                 | '9.76K'   | '1%'    | '1/16W'  | 'IO'       | 'RES CHIP 9.76K 1/16W +-1%(0402)'                  | 'CHIP0402'     | ''          | ''            | '20120314'
 '39K'        | '1%'      | '1/16W'  | '0402LF'  | 'CHIP'   | 'CS33902FB16'(!)        = 'End of Design' | 'Comp-Approve'     | 'CS33902FB16'           |'R0402'| '(R0402-0201)'                 | '39K'     | '1%'    | '1/16W'  | 'DISCRETE' | 'RES CHIP 39K 1/16W +-1%(0402)'                    | 'CHIP0402'     | ''          | ''            | '20120314'
 '39K'        | '1%'      | '1/16W'  | '0402LF'  | 'EMPTY'  | 'CS33902FB16'(!)        = 'End of Design' | 'Comp-Approve'     | 'CS33902FB16'           |'R0402'| '(R0402-0201)'                 | '39K'     | '1%'    | '1/16W'  | 'IO'       | 'RES CHIP 39K 1/16W +-1%(0402)'                    | 'CHIP0402'     | ''          | ''            | '20120314'
 '14K'        | '1%'      | '1/16W'  | '0402LF'  | 'CHIP'   | 'CS31402FB12'(!)        = 'End of Design' | 'Comp-Approve'     | 'CS31402FB12'           |'R0402'| '(R0402-0201)'                 | '14K'     | '1%'    | '1/16W'  | 'DISCRETE' | 'RES CHIP 14K 1/16W +-1% (0402)'                   | 'CHIP0402'     | ''          | ''            | '20120314'
 '14K'        | '1%'      | '1/16W'  | '0402LF'  | 'EMPTY'  | 'CS31402FB12'(!)        = 'End of Design' | 'Comp-Approve'     | 'CS31402FB12'           |'R0402'| '(R0402-0201)'                 | '14K'     | '1%'    | '1/16W'  | 'IO'       | 'RES CHIP 14K 1/16W +-1% (0402)'                   | 'CHIP0402'     | ''          | ''            | '20120314'
 '215K'       | '1%'      | '1/16W'  | '0402LF'  | 'CHIP'   | 'CS42152FB19'(!)        = 'End of Design' | 'Comp-Approve'     | 'CS42152FB19'           |'R0402'| '(R0402-0201)'                 | '215K'    | '1%'    | '1/16W'  | 'DISCRETE' | 'RES CHIP 215K 1/16W +-1%(0402)'                   | 'CHIP0402'     | ''          | ''            | '20120320'
 '215K'       | '1%'      | '1/16W'  | '0402LF'  | 'EMPTY'  | 'CS42152FB19'(!)        = 'End of Design' | 'Comp-Approve'     | 'CS42152FB19'           |'R0402'| '(R0402-0201)'                 | '215K'    | '1%'    | '1/16W'  | 'IO'       | 'RES CHIP 215K 1/16W +-1%(0402)'                   | 'CHIP0402'     | ''          | ''            | '20120320'
 '53.6K'      | '1%'      | '1/16W'  | '0402LF'  | 'CHIP'   | 'CS35362FB17'(!)        = 'End of Design' | 'Comp-Approve'     | 'CS35362FB17'           |'R0402'| '(R0402-0201)'                 | '53.6K'   | '1%'    | '1/16W'  | 'DISCRETE' | 'RES CHIP 53.6K 1/16W +-1%(0402)'                  | 'CHIP0402'     | ''          | ''            | '20120320'
 '53.6K'      | '1%'      | '1/16W'  | '0402LF'  | 'EMPTY'  | 'CS35362FB17'(!)        = 'End of Design' | 'Comp-Approve'     | 'CS35362FB17'           |'R0402'| '(R0402-0201)'                 | '53.6K'   | '1%'    | '1/16W'  | 'IO'       | 'RES CHIP 53.6K 1/16W +-1%(0402)'                  | 'CHIP0402'     | ''          | ''            | '20120320'
 '13K'        | '1%'      | '1/10W'  | '0603LF'  | 'CHIP'   | 'CS31303F931'(!)        = ''              | ''                 | 'CS31303F931'           |'R0603'| '(SMR0603AW)'                  | '13K'     | '1%'    | '1/10W'  | 'DISCRETE' | 'RESISTOR CHIP 13K 1/10W +-1%(0603)'               | 'CHIP0603'     | ''          | ''            | '20120321'
 '13K'        | '1%'      | '1/10W'  | '0603LF'  | 'EMPTY'  | 'CS31303F931'(!)        = ''              | ''                 | 'CS31303F931'           |'R0603'| '(SMR0603AW)'                  | '13K'     | '1%'    | '1/10W'  | 'IO'       | 'RESISTOR CHIP 13K 1/10W +-1%(0603)'               | 'CHIP0603'     | ''          | ''            | '20120321'
 '6.81K'      | '1%'      | '1/16W'  | '0402LF'  | 'CHIP'   | 'CS26812FB13'(!)        = 'End of Design' | 'Comp-Approve'     | 'CS26812FB13'           |'R0402'| '(R0402-0201)'                 | '6.81K'   | '1%'    | '1/16W'  | 'DISCRETE' | 'RES CHIP 6.81K 1/16W +-1% (0402)'                 | 'CHIP0402'     | ''          | ''            | '20120322'
 '6.81K'      | '1%'      | '1/16W'  | '0402LF'  | 'EMPTY'  | 'CS26812FB13'(!)        = 'End of Design' | 'Comp-Approve'     | 'CS26812FB13'           |'R0402'| '(R0402-0201)'                 | '6.81K'   | '1%'    | '1/16W'  | 'IO'       | 'RES CHIP 6.81K 1/16W +-1% (0402)'                 | 'CHIP0402'     | ''          | ''            | '20120322'
 '549'        | '1%'      | '1/8W'   | '0805LF'  | 'CHIP'   | 'CS15494FA00'(!)        = ''              | ''                 | 'CS15494FA00'           |'R0805'| '(SMR0805AW)'                  | '549'     | '1%'    | '1/8W'   | 'DISCRETE' | 'RES CHIP 549 1/8W +-1%(0805)'                     | 'CHIP0805'     | ''          | ''            | '20120325'
 '549'        | '1%'      | '1/8W'   | '0805LF'  | 'EMPTY'  | 'CS15494FA00'(!)        = ''              | ''                 | 'CS15494FA00'           |'R0805'| '(SMR0805AW)'                  | '549'     | '1%'    | '1/8W'   | 'IO'       | 'RES CHIP 549 1/8W +-1%(0805)'                     | 'CHIP0805'     | ''          | ''            | '20120325'
 '91'         | '0.1%'    | '1/10W'  | '0603LF'  | 'CHIP'   | 'CS09103B900'(!)        = ''              | ''                 | 'CS09103B900'           |'R0603'| '(SMR0603AW)'                  | '91'      | '0.1%'  | '1/10W'  | 'DISCRETE' | 'RES CHIP 91 1/10W +-0.1%(0603)'                   | 'CHIP0603'     | ''          | ''            | '20120325'
 '91'         | '0.1%'    | '1/10W'  | '0603LF'  | 'EMPTY'  | 'CS09103B900'(!)        = ''              | ''                 | 'CS09103B900'           |'R0603'| '(SMR0603AW)'                  | '91'      | '0.1%'  | '1/10W'  | 'IO'       | 'RES CHIP 91 1/10W +-0.1%(0603)'                   | 'CHIP0603'     | ''          | ''            | '20120325'
 '115'        | '0.1%'    | '1/10W'  | '0603LF'  | 'CHIP'   | 'CS11153B900'(!)        = ''              | ''                 | 'CS11153B900'           |'R0603'| '(SMR0603AW)'                  | '115'     | '0.1%'  | '1/10W'  | 'DISCRETE' | 'RES CHIP 115 1/10W +-0.1%(0603)'                  | 'CHIP0603'     | ''          | ''            | '20120325'
 '115'        | '0.1%'    | '1/10W'  | '0603LF'  | 'EMPTY'  | 'CS11153B900'(!)        = ''              | ''                 | 'CS11153B900'           |'R0603'| '(SMR0603AW)'                  | '115'     | '0.1%'  | '1/10W'  | 'IO'       | 'RES CHIP 115 1/10W +-0.1%(0603)'                  | 'CHIP0603'     | ''          | ''            | '20120325'
 '768'        | '0.1%'    | '1/10W'  | '0603LF'  | 'CHIP'   | 'CS17683B900'(!)        = ''              | ''                 | 'CS17683B900'           |'R0603'| '(SMR0603AW)'                  | '768'     | '0.1%'  | '1/10W'  | 'DISCRETE' | 'RES CHIP 768 1/10W +-0.1%(0603)'                  | 'CHIP0603'     | ''          | ''            | '20120325'
 '768'        | '0.1%'    | '1/10W'  | '0603LF'  | 'EMPTY'  | 'CS17683B900'(!)        = ''              | ''                 | 'CS17683B900'           |'R0603'| '(SMR0603AW)'                  | '768'     | '0.1%'  | '1/10W'  | 'IO'       | 'RES CHIP 768 1/10W +-0.1%(0603)'                  | 'CHIP0603'     | ''          | ''            | '20120325'
 '180K'       | '1%'      | '1/16W'  | '0402LF'  | 'CHIP'   | 'CS41802FB19'(!)        = 'End of Design' | 'Comp-Approve'     | 'CS41802FB19'           |'R0402'| '(R0402-0201)'                 | '180K'    | '1%'    | '1/16W'  | 'DISCRETE' | 'RES CHIP 180K 1/16W +-1%(0402)'                   | 'CHIP0402'     | ''          | ''            | '20120326'
 '180K'       | '1%'      | '1/16W'  | '0402LF'  | 'EMPTY'  | 'CS41802FB19'(!)        = 'End of Design' | 'Comp-Approve'     | 'CS41802FB19'           |'R0402'| '(R0402-0201)'                 | '180K'    | '1%'    | '1/16W'  | 'IO'       | 'RES CHIP 180K 1/16W +-1%(0402)'                   | 'CHIP0402'     | ''          | ''            | '20120326'
 '174'        | '1%'      | '1/16W'  | '0402LF'  | 'CHIP'   | 'CS11742FB00'(!)        = 'End of Design' | 'Comp-Approve'     | 'CS11742FB00'           |'R0402'| '(R0402-0201)'                 | '174'     | '1%'    | '1/16W'  | 'DISCRETE' | 'RES CHIP 174 1/16W +-1%(0402)'                    | 'CHIP0402'     | ''          | ''            | '20120326'
 '174'        | '1%'      | '1/16W'  | '0402LF'  | 'EMPTY'  | 'CS11742FB00'(!)        = 'End of Design' | 'Comp-Approve'     | 'CS11742FB00'           |'R0402'| '(R0402-0201)'                 | '174'     | '1%'    | '1/16W'  | 'IO'       | 'RES CHIP 174 1/16W +-1%(0402)'                    | 'CHIP0402'     | ''          | ''            | '20120326'
 '0.002'      | '1%'      | '2W'     | '2512LF'  | 'CHIP'   | 'CS+002AFR00'(!)        = ''              | ''                 | 'CS+002AFR00'           |'R2512A'| '(SMR2512AW)'                  | '0.002'   | '1%'    | '2W'     | 'DISCRETE' | 'RES CHIP 0.002 2W +-1%(2512)'                     | 'CHIP2512'     | ''          | ''            | '20120326'
 '0.002'      | '1%'      | '2W'     | '2512LF'  | 'EMPTY'  | 'CS+002AFR00'(!)        = ''              | ''                 | 'CS+002AFR00'           |'R2512A'| '(SMR2512AW)'                  | '0.002'   | '1%'    | '2W'     | 'IO'       | 'RES CHIP 0.002 2W +-1%(2512)'                     | 'CHIP2512'     | ''          | ''            | '20120326'
 '3.48M'      | '1%'      | '1/16W'  | '0402LF'  | 'CHIP'   | 'CS53482FB00'(!)        = ''              | ''                 | 'CS53482FB00'           |'R0402'| '(R0402-0201)'                 | '3.48M'   | '1%'    | '1/16W'  | 'DISCRETE' | 'RES CHIP 3.48M 1/16W +-1%(0402)'                  | 'CHIP0402'     | ''          | ''            | '20120329'
 '3.48M'      | '1%'      | '1/16W'  | '0402LF'  | 'EMPTY'  | 'CS53482FB00'(!)        = ''              | ''                 | 'CS53482FB00'           |'R0402'| '(R0402-0201)'                 | '3.48M'   | '1%'    | '1/16W'  | 'IO'       | 'RES CHIP 3.48M 1/16W +-1%(0402)'                  | 'CHIP0402'     | ''          | ''            | '20120329'
 '3.65M'      | '1%'      | '1/16W'  | '0402LF'  | 'CHIP'   | 'CS53652FB00'(!)        = ''              | ''                 | 'CS53652FB00'           |'R0402'| '(R0402-0201)'                 | '3.65M'   | '1%'    | '1/16W'  | 'DISCRETE' | 'RES CHIP 3.65M 1/16W +-1%(0402)'                  | 'CHIP0402'     | ''          | ''            | '20120329'
 '3.65M'      | '1%'      | '1/16W'  | '0402LF'  | 'EMPTY'  | 'CS53652FB00'(!)        = ''              | ''                 | 'CS53652FB00'           |'R0402'| '(R0402-0201)'                 | '3.65M'   | '1%'    | '1/16W'  | 'IO'       | 'RES CHIP 3.65M 1/16W +-1%(0402)'                  | 'CHIP0402'     | ''          | ''            | '20120329'
 '0.5'        | '10%'     | '15W'    | 'THLF'    | 'CHIP'   | 'TMP_T6M_KOOL_0405_1'(!) = ''              | ''                 | 'TMP_T6M_KOOL_0405_1'   |'R18947D'| '(R18947D)'                    | '0.5'     | '10%'   | '15W'    | 'DISCRETE' | 'RESISTOR CEMENT 0.5 15W +-10%'                    | 'R18947D'      | ''          | ''            | '20120405'
 '0.5'        | '10%'     | '15W'    | 'THLF'    | 'EMPTY'  | 'TMP_T6M_KOOL_0405_1'(!) = ''              | ''                 | 'TMP_T6M_KOOL_0405_1'   |'R18947D'| '(R18947D)'                    | '0.5'     | '10%'   | '15W'    | 'IO'       | 'RESISTOR CEMENT 0.5 15W +-10%'                    | 'R18947D'      | ''          | ''            | '20120405'
 '0.39'       | '10%'     | '15W'    | 'THLF'    | 'CHIP'   | 'TMP_T6M_KOOL_0405_2'(!) = ''              | ''                 | 'TMP_T6M_KOOL_0405_2'   |'R18947D'| '(R18947D)'                    | '0.39'    | '10%'   | '15W'    | 'DISCRETE' | 'RESISTOR CEMENT 0.39 15W +-10%'                   | 'R18947D'      | ''          | ''            | '20120405'
 '0.39'       | '10%'     | '15W'    | 'THLF'    | 'EMPTY'  | 'TMP_T6M_KOOL_0405_2'(!) = ''              | ''                 | 'TMP_T6M_KOOL_0405_2'   |'R18947D'| '(R18947D)'                    | '0.39'    | '10%'   | '15W'    | 'IO'       | 'RESISTOR CEMENT 0.39 15W +-10%'                   | 'R18947D'      | ''          | ''            | '20120405'
 '5.76'       | '10%'     | '50W'    | 'THLF'    | 'CHIP'   | 'TMP_T6M_KOOL_0405_3'(!) = ''              | ''                 | 'TMP_T6M_KOOL_0405_3'   |'R35475D'| '(R35475D)'                    | '5.76'    | '10%'   | '50W'    | 'DISCRETE' | 'RESISTOR CEMENT 5.76 50W +-10%'                   | 'R35475D'      | ''          | ''            | '20120405'
 '5.76'       | '10%'     | '50W'    | 'THLF'    | 'EMPTY'  | 'TMP_T6M_KOOL_0405_3'(!) = ''              | ''                 | 'TMP_T6M_KOOL_0405_3'   |'R35475D'| '(R35475D)'                    | '5.76'    | '10%'   | '50W'    | 'IO'       | 'RESISTOR CEMENT 5.76 50W +-10%'                   | 'R35475D'      | ''          | ''            | '20120405'
 '2.88'       | '10%'     | '60W'    | 'THLF'    | 'CHIP'   | 'TMP_T6M_KOOL_0405_4'(!) = ''              | ''                 | 'TMP_T6M_KOOL_0405_4'   |'R35475D'| '(R35475D)'                    | '2.88'    | '10%'   | '60W'    | 'DISCRETE' | 'RESISTOR CEMENT 2.88 60W +-10%'                   | 'R35475D'      | ''          | ''            | '20120405'
 '2.88'       | '10%'     | '60W'    | 'THLF'    | 'EMPTY'  | 'TMP_T6M_KOOL_0405_4'(!) = ''              | ''                 | 'TMP_T6M_KOOL_0405_4'   |'R35475D'| '(R35475D)'                    | '2.88'    | '10%'   | '60W'    | 'IO'       | 'RESISTOR CEMENT 2.88 60W +-10%'                   | 'R35475D'      | ''          | ''            | '20120405'
 '1.5'        | '5%'      | '25W'    | 'THLF'    | 'CHIP'   | 'TMP_T6M_KOOL_0406_1'(!) = ''              | ''                 | 'TMP_T6M_KOOL_0406_1'   |'R23655D'| '(R23655D)'                    | '1.5'     | '5%'    | '25W'    | 'DISCRETE' | 'RESISTOR CEMENT 1.5 25W +-5%'                     | 'R23655D'      | ''          | ''            | '20120406'
 '1.5'        | '5%'      | '25W'    | 'THLF'    | 'EMPTY'  | 'TMP_T6M_KOOL_0406_1'(!) = ''              | ''                 | 'TMP_T6M_KOOL_0406_1'   |'R23655D'| '(R23655D)'                    | '1.5'     | '5%'    | '25W'    | 'IO'       | 'RESISTOR CEMENT 1.5 25W +-5%'                     | 'R23655D'      | ''          | ''            | '20120406'
 '97.6K'      | '1%'      | '1/16W'  | '0402LF'  | 'CHIP'   | 'CS39762FB12'(!)        = 'End of Design' | 'Comp-Approve'     | 'CS39762FB12'           |'R0402'| '(R0402-0201)'                 | '97.6K'   | '1%'    | '1/16W'  | 'DISCRETE' | 'RES CHIP 97.6K 1/16W +-1%(0402)'                  | 'CHIP0402'     | ''          | ''            | '20120406'
 '97.6K'      | '1%'      | '1/16W'  | '0402LF'  | 'EMPTY'  | 'CS39762FB12'(!)        = 'End of Design' | 'Comp-Approve'     | 'CS39762FB12'           |'R0402'| '(R0402-0201)'                 | '97.6K'   | '1%'    | '1/16W'  | 'IO'       | 'RES CHIP 97.6K 1/16W +-1%(0402)'                  | 'CHIP0402'     | ''          | ''            | '20120406'
 '510'        | '1%'      | '1/16W'  | '0402LF'  | 'CHIP'   | 'CS15102FB19'(!)        = 'End of Design' | 'Comp-Approve'     | 'CS15102FB19'           |'R0402'| '(R0402-0201)'                 | '510'     | '1%'    | '1/16W'  | 'DISCRETE' | 'RES CHIP 510 1/16W +-1%(0402)'                    | 'CHIP0402'     | ''          | ''            | '20120414'
 '510'        | '1%'      | '1/16W'  | '0402LF'  | 'EMPTY'  | 'CS15102FB19'(!)        = 'End of Design' | 'Comp-Approve'     | 'CS15102FB19'           |'R0402'| '(R0402-0201)'                 | '510'     | '1%'    | '1/16W'  | 'IO'       | 'RES CHIP 510 1/16W +-1%(0402)'                    | 'CHIP0402'     | ''          | ''            | '20120414'
 '24.9'       | '0.5%'    | '1/16W'  | '0402LF'  | 'CHIP'   | 'CS02492DB01'(!)        = 'End of Design' | 'Comp-Approve'     | 'CS02492DB01'           |'R0402'| '(R0402-0201)'                 | '24.9'    | '0.5%'  | '1/16W'  | 'DISCRETE' | 'RES CHIP 24.9 1/16W +-0.5%(0402)'                 | 'CHIP0402'     | ''          | ''            | '20120416'
 '24.9'       | '0.5%'    | '1/16W'  | '0402LF'  | 'EMPTY'  | 'CS02492DB01'(!)        = 'End of Design' | 'Comp-Approve'     | 'CS02492DB01'           |'R0402'| '(R0402-0201)'                 | '24.9'    | '0.5%'  | '1/16W'  | 'IO'       | 'RES CHIP 24.9 1/16W +-0.5%(0402)'                 | 'CHIP0402'     | ''          | ''            | '20120416'
 '604'        | '1%'      | '1/8W'   | '0805LF'  | 'CHIP'   | 'CS16044FA00'(!)        = ''              | ''                 | 'CS16044FA00'           |'R0805'| '(SMR0805AW)'                  | '604'     | '1%'    | '1/8W'   | 'DISCRETE' | 'RES CHIP 604 1/8W +-1%(0805)'                     | 'CHIP0805'     | ''          | ''            | '20120424'
 '604'        | '1%'      | '1/8W'   | '0805LF'  | 'EMPTY'  | 'CS16044FA00'(!)        = ''              | ''                 | 'CS16044FA00'           |'R0805'| '(SMR0805AW)'                  | '604'     | '1%'    | '1/8W'   | 'IO'       | 'RES CHIP 604 1/8W +-1%(0805)'                     | 'CHIP0805'     | ''          | ''            | '20120424'
 '115'        | '1%'      | '1/16W'  | '0402LF'  | 'CHIP'   | 'CS11152FB11'(!)        = 'End of Design' | 'Comp-Release Qty' | 'CS11152FB11'           |'R0402'| '(R0402-0201)'                 | '115'     | '1%'    | '1/16W'  | 'DISCRETE' | 'RES CHIP 115 1/16W +-1% (0402)'                   | 'CHIP0402'     | ''          | ''            | '20120426'
 '115'        | '1%'      | '1/16W'  | '0402LF'  | 'EMPTY'  | 'CS11152FB11'(!)        = 'End of Design' | 'Comp-Release Qty' | 'CS11152FB11'           |'R0402'| '(R0402-0201)'                 | '115'     | '1%'    | '1/16W'  | 'IO'       | 'RES CHIP 115 1/16W +-1% (0402)'                   | 'CHIP0402'     | ''          | ''            | '20120426'
 '49.9'       | '1%'      | '1/8W'   | '0805LF'  | 'CHIP'   | 'CS04994FA01'(!)        = ''              | ''                 | 'CS04994FA01'           |'R0805'| '(SMR0805AW)'                  | '49.9'    | '1%'    | '1/8W'   | 'DISCRETE' | 'RES CHIP 49.9 1/8W +-1%(0805)'                    | 'CHIP0805'     | ''          | ''            | '20120427'
 '49.9'       | '1%'      | '1/8W'   | '0805LF'  | 'EMPTY'  | 'CS04994FA01'(!)        = ''              | ''                 | 'CS04994FA01'           |'R0805'| '(SMR0805AW)'                  | '49.9'    | '1%'    | '1/8W'   | 'IO'       | 'RES CHIP 49.9 1/8W +-1%(0805)'                    | 'CHIP0805'     | ''          | ''            | '20120427'
 '13.3K'      | '1%'      | '1/16W'  | '0402LF'  | 'CHIP'   | 'CS21332FB02'(!)        = 'End of Design' | 'Comp-Approve'     | 'CS21332FB02'           |'R0402'| '(R0402-0201)'                 | '13.3K'   | '1%'    | '1/16W'  | 'DISCRETE' | 'RES CHIP 13.3K 1/16W +-1%(0402)'                  | 'CHIP0402'     | ''          | ''            | '20120502'
 '13.3K'      | '1%'      | '1/16W'  | '0402LF'  | 'EMPTY'  | 'CS21332FB02'(!)        = 'End of Design' | 'Comp-Approve'     | 'CS21332FB02'           |'R0402'| '(R0402-0201)'                 | '13.3K'   | '1%'    | '1/16W'  | 'IO'       | 'RES CHIP 13.3K 1/16W +-1%(0402)'                  | 'CHIP0402'     | ''          | ''            | '20120502'
 '332K'       | '1%'      | '1/16W'  | '0402LF'  | 'CHIP'   | 'CS43322FB15'(!)        = 'End of Design' | 'Comp-Approve'     | 'CS43322FB15'           |'R0402'| '(R0402-0201)'                 | '332K'    | '1%'    | '1/16W'  | 'DISCRETE' | 'RES CHIP 332K 1/16W +-1%(0402)'                   | 'CHIP0402'     | ''          | ''            | '20120516'
 '332K'       | '1%'      | '1/16W'  | '0402LF'  | 'EMPTY'  | 'CS43322FB15'(!)        = 'End of Design' | 'Comp-Approve'     | 'CS43322FB15'           |'R0402'| '(R0402-0201)'                 | '332K'    | '1%'    | '1/16W'  | 'IO'       | 'RES CHIP 332K 1/16W +-1%(0402)'                   | 'CHIP0402'     | ''          | ''            | '20120516'
 '95.3K'      | '1%'      | '1/8W'   | '0805LF'  | 'CHIP'   | 'CS39534FA00'(!)        = ''              | ''                 | 'CS39534FA00'           |'R0805'| '(SMR0805AW)'                  | '95.3K '  | '1%'    | '1/8W'   | 'DISCRETE' | 'RES CHIP 95.3K 1/8W +-1%(0805)'                   | 'CHIP0805'     | ''          | ''            | '20120524'
 '95.3K'      | '1%'      | '1/8W'   | '0805LF'  | 'EMPTY'  | 'CS39534FA00'(!)        = ''              | ''                 | 'CS39534FA00'           |'R0805'| '(SMR0805AW)'                  | '95.3K '  | '1%'    | '1/8W'   | 'IO'       | 'RES CHIP 95.3K 1/8W +-1%(0805)'                   | 'CHIP0805'     | ''          | ''            | '20120524'
 '453K'       | '1%'      | '1/8W'   | '0805LF'  | 'CHIP'   | 'CS44534FA00'(!)        = ''              | ''                 | 'CS44534FA00'           |'R0805'| '(SMR0805AW)'                  | '453K'    | '1%'    | '1/8W'   | 'DISCRETE' | 'RES CHIP 453K 1/8W +-1%(0805)'                    | 'CHIP0805'     | ''          | ''            | '20120524'
 '453K'       | '1%'      | '1/8W'   | '0805LF'  | 'EMPTY'  | 'CS44534FA00'(!)        = ''              | ''                 | 'CS44534FA00'           |'R0805'| '(SMR0805AW)'                  | '453K'    | '1%'    | '1/8W'   | 'IO'       | 'RES CHIP 453K 1/8W +-1%(0805)'                    | 'CHIP0805'     | ''          | ''            | '20120524'
 '174K'       | '1%'      | '1/8W'   | '0805LF'  | 'CHIP'   | 'CS41744FA00'(!)        = ''              | ''                 | 'CS41744FA00'           |'R0805'| '(SMR0805AW)'                  | '174K'    | '1%'    | '1/8W'   | 'DISCRETE' | 'RES CHIP 174K 1/8W +-1%(0805)'                    | 'CHIP0805'     | ''          | ''            | '20120524'
 '174K'       | '1%'      | '1/8W'   | '0805LF'  | 'EMPTY'  | 'CS41744FA00'(!)        = ''              | ''                 | 'CS41744FA00'           |'R0805'| '(SMR0805AW)'                  | '174K'    | '1%'    | '1/8W'   | 'IO'       | 'RES CHIP 174K 1/8W +-1%(0805)'                    | 'CHIP0805'     | ''          | ''            | '20120524'
 '10'         | '5%'      | '1/20W'  | '0201LF'  | 'CHIP'   | 'CS01001JE00'(!)        = ''              | ''                 | 'CS01001JE00'           |'R0201'| '(SMR0201AW)'                  | '10'      | '5%'    | '1/20W'  | 'DISCRETE' | 'RES CHIP 10(1/20W,+-5%,0201)HF'                   | 'CHIP0201'     | ''          | ''            | '20120524'
 '10'         | '5%'      | '1/20W'  | '0201LF'  | 'EMPTY'  | 'CS01001JE00'(!)        = ''              | ''                 | 'CS01001JE00'           |'R0201'| '(SMR0201AW)'                  | '10'      | '5%'    | '1/20W'  | 'IO'       | 'RES CHIP 10(1/20W,+-5%,0201)HF'                   | 'CHIP0201'     | ''          | ''            | '20120524'
 '1K'         | '5%'      | '1/20W'  | '0201LF'  | 'CHIP'   | 'CS21001JE00'(!)        = ''              | ''                 | 'CS21001JE00'           |'R0201'| '(SMR0201AW)'                  | '1K'      | '5%'    | '1/20W'  | 'DISCRETE' | 'RES CHIP 1K 1/20W +-5%(0201)HF'                   | 'CHIP0201'     | ''          | ''            | '20120524'
 '1K'         | '5%'      | '1/20W'  | '0201LF'  | 'EMPTY'  | 'CS21001JE00'(!)        = ''              | ''                 | 'CS21001JE00'           |'R0201'| '(SMR0201AW)'                  | '1K'      | '5%'    | '1/20W'  | 'IO'       | 'RES CHIP 1K 1/20W +-5%(0201)HF'                   | 'CHIP0201'     | ''          | ''            | '20120524'
 '27K'        | '5%'      | '1/20W'  | '0201LF'  | 'CHIP'   | 'CS32701JE00'(!)        = ''              | ''                 | 'CS32701JE00'           |'R0201'| '(SMR0201AW)'                  | '27K'     | '5%'    | '1/20W'  | 'DISCRETE' | 'RES CHIP 27K 1/20W +-5%(0201)'                    | 'CHIP0201'     | ''          | ''            | '20120524'
 '27K'        | '5%'      | '1/20W'  | '0201LF'  | 'EMPTY'  | 'CS32701JE00'(!)        = ''              | ''                 | 'CS32701JE00'           |'R0201'| '(SMR0201AW)'                  | '27K'     | '5%'    | '1/20W'  | 'IO'       | 'RES CHIP 27K 1/20W +-5%(0201)'                    | 'CHIP0201'     | ''          | ''            | '20120524'
 '100K'       | '5%'      | '1/20W'  | '0201LF'  | 'CHIP'   | 'CS41001JE00'(!)        = ''              | ''                 | 'CS41001JE00'           |'R0201'| '(SMR0201AW)'                  | '100K'    | '5%'    | '1/20W'  | 'DISCRETE' | 'RES CHIP 100K(1/20W,+-5%,0201)'                   | 'CHIP0201'     | ''          | ''            | '20120524'
 '100K'       | '5%'      | '1/20W'  | '0201LF'  | 'EMPTY'  | 'CS41001JE00'(!)        = ''              | ''                 | 'CS41001JE00'           |'R0201'| '(SMR0201AW)'                  | '100K'    | '5%'    | '1/20W'  | 'IO'       | 'RES CHIP 100K(1/20W,+-5%,0201)'                   | 'CHIP0201'     | ''          | ''            | '20120524'
 '499K'       | '1%'      | '1/8W'   | '0805LF'  | 'CHIP'   | 'CS44994FA00'(!)        = ''              | ''                 | 'CS44994FA00'           |'R0805'| '(SMR0805AW)'                  | '499K'    | '1%'    | '1/8W'   | 'DISCRETE' | 'RES CHIP 499K 1/8W+-1%(0805)'                     | 'CHIP0805'     | ''          | ''            | '20120528'
 '499K'       | '1%'      | '1/8W'   | '0805LF'  | 'EMPTY'  | 'CS44994FA00'(!)        = ''              | ''                 | 'CS44994FA00'           |'R0805'| '(SMR0805AW)'                  | '499K'    | '1%'    | '1/8W'   | 'IO'       | 'RES CHIP 499K 1/8W+-1%(0805)'                     | 'CHIP0805'     | ''          | ''            | '20120528'
 '0'          | '5%'      | '1/20W'  | '0201LF'  | 'CHIP'   | 'CS00001JE02'(!)        = 'End of Design' | 'Comp-Approve'     | 'CS00001JE02'           |'R0201'| '(SMR0201AW)'                  | '0'       | '5%'    | '1/20W'  | 'DISCRETE' | 'RES CHIP 0(1/20W,+-5%,0201)HF'                    | 'CHIP0201'     | ''          | ''            | '20120528'
 '0'          | '5%'      | '1/20W'  | '0201LF'  | 'EMPTY'  | 'CS00001JE02'(!)        = 'End of Design' | 'Comp-Approve'     | 'CS00001JE02'           |'R0201'| '(SMR0201AW)'                  | '0'       | '5%'    | '1/20W'  | 'IO'       | 'RES CHIP 0(1/20W,+-5%,0201)HF'                    | 'CHIP0201'     | ''          | ''            | '20120528'
 '4.7K'       | '5%'      | '1/20W'  | '0201LF'  | 'CHIP'   | 'CS24701JE00'(!)        = ''              | ''                 | 'CS24701JE00'           |'R0201'| '(SMR0201AW)'                  | '4.7K'    | '5%'    | '1/20W'  | 'DISCRETE' | 'RES CHIP 4.7K(1/20W,+-5%,0201)'                   | 'CHIP0201'     | ''          | ''            | '20120528'
 '4.7K'       | '5%'      | '1/20W'  | '0201LF'  | 'EMPTY'  | 'CS24701JE00'(!)        = ''              | ''                 | 'CS24701JE00'           |'R0201'| '(SMR0201AW)'                  | '4.7K'    | '5%'    | '1/20W'  | 'IO'       | 'RES CHIP 4.7K(1/20W,+-5%,0201)'                   | 'CHIP0201'     | ''          | ''            | '20120528'
 '33'         | '1%'      | '1/20W'  | '0201LF'  | 'CHIP'   | 'CS03301FE01'(!)        = ''              | ''                 | 'CS03301FE01'           |'R0201'| '(SMR0201AW)'                  | '33'      | '1%'    | '1/20W'  | 'DISCRETE' | 'RES CHIP 33 1/20W +-1%(0201)'                     | 'CHIP0201'     | ''          | ''            | '20120528'
 '33'         | '1%'      | '1/20W'  | '0201LF'  | 'EMPTY'  | 'CS03301FE01'(!)        = ''              | ''                 | 'CS03301FE01'           |'R0201'| '(SMR0201AW)'                  | '33'      | '1%'    | '1/20W'  | 'IO'       | 'RES CHIP 33 1/20W +-1%(0201)'                     | 'CHIP0201'     | ''          | ''            | '20120528'
 '49.9'       | '1%'      | '1/20W'  | '0201LF'  | 'CHIP'   | 'CS04991FE00'(!)        = ''              | ''                 | 'CS04991FE00'           |'R0201'| '(SMR0201AW)'                  | '49.9'    | '1%'    | '1/20W'  | 'DISCRETE' | 'RES CHIP 49.9 1/20W +-1%(0201)'                   | 'CHIP0201'     | ''          | ''            | '20120528'
 '49.9'       | '1%'      | '1/20W'  | '0201LF'  | 'EMPTY'  | 'CS04991FE00'(!)        = ''              | ''                 | 'CS04991FE00'           |'R0201'| '(SMR0201AW)'                  | '49.9'    | '1%'    | '1/20W'  | 'IO'       | 'RES CHIP 49.9 1/20W +-1%(0201)'                   | 'CHIP0201'     | ''          | ''            | '20120528'
 '6.04K'      | '1%'      | '1/20W'  | '0201LF'  | 'CHIP'   | 'CS26041FE06'(!)        = ''              | ''                 | 'CS26041FE06'           |'R0201'| '(SMR0201AW)'                  | '6.04K'   | '1%'    | '1/20W'  | 'DISCRETE' | 'RES CHIP 6.04K 1/20W +-1%(0201)'                  | 'CHIP0201'     | ''          | ''            | '20120528'
 '6.04K'      | '1%'      | '1/20W'  | '0201LF'  | 'EMPTY'  | 'CS26041FE06'(!)        = ''              | ''                 | 'CS26041FE06'           |'R0201'| '(SMR0201AW)'                  | '6.04K'   | '1%'    | '1/20W'  | 'IO'       | 'RES CHIP 6.04K 1/20W +-1%(0201)'                  | 'CHIP0201'     | ''          | ''            | '20120528'
 '100'        | '1%'      | '1/20W'  | '0201LF'  | 'CHIP'   | 'CS11001FE00'(!)        = ''              | ''                 | 'CS11001FE00'           |'R0201'| '(SMR0201AW)'                  | '100'     | '1%'    | '1/20W'  | 'DISCRETE' | 'RES CHIP 100 1/20W +-1%(0201)'                    | 'CHIP0201'     | ''          | ''            | '20120528'
 '100'        | '1%'      | '1/20W'  | '0201LF'  | 'EMPTY'  | 'CS11001FE00'(!)        = ''              | ''                 | 'CS11001FE00'           |'R0201'| '(SMR0201AW)'                  | '100'     | '1%'    | '1/20W'  | 'IO'       | 'RES CHIP 100 1/20W +-1%(0201)'                    | 'CHIP0201'     | ''          | ''            | '20120528'
 '15K'        | '1%'      | '1/20W'  | '0201LF'  | 'CHIP'   | 'CS31501FE01'(!)        = ''              | ''                 | 'CS31501FE01'           |'R0201'| '(SMR0201AW)'                  | '15K'     | '1%'    | '1/20W'  | 'DISCRETE' | 'RES CHIP 15K 1/20W +-1%(0201)HF'                  | 'CHIP0201'     | ''          | ''            | '20120528'
 '15K'        | '1%'      | '1/20W'  | '0201LF'  | 'EMPTY'  | 'CS31501FE01'(!)        = ''              | ''                 | 'CS31501FE01'           |'R0201'| '(SMR0201AW)'                  | '15K'     | '1%'    | '1/20W'  | 'IO'       | 'RES CHIP 15K 1/20W +-1%(0201)HF'                  | 'CHIP0201'     | ''          | ''            | '20120528'
 '240'        | '1%'      | '1/20W'  | '0201LF'  | 'CHIP'   | 'CS12401FE00'(!)        = ''              | ''                 | 'CS12401FE00'           |'R0201'| '(SMR0201AW)'                  | '240'     | '1%'    | '1/20W'  | 'DISCRETE' | 'RES CHIP 240 1/20W +-1%(0201)'                    | 'CHIP0201'     | ''          | ''            | '20120528'
 '240'        | '1%'      | '1/20W'  | '0201LF'  | 'EMPTY'  | 'CS12401FE00'(!)        = ''              | ''                 | 'CS12401FE00'           |'R0201'| '(SMR0201AW)'                  | '240'     | '1%'    | '1/20W'  | 'IO'       | 'RES CHIP 240 1/20W +-1%(0201)'                    | 'CHIP0201'     | ''          | ''            | '20120528'
 '30.1K'      | '1%'      | '1/10W'  | '0603LF'  | 'CHIP'   | 'CS33013F914'(!)        = ''              | ''                 | 'CS33013F914'           |'R0603'| '(SMR0603AW)'                  | '30.1K'   | '1%'    | '1/10W'  | 'DISCRETE' | 'RESISTOR CHIP 30.1K 1/10W+-1%(0603)'              | 'CHIP0603'     | ''          | ''            | '20120529'
 '30.1K'      | '1%'      | '1/10W'  | '0603LF'  | 'EMPTY'  | 'CS33013F914'(!)        = ''              | ''                 | 'CS33013F914'           |'R0603'| '(SMR0603AW)'                  | '30.1K'   | '1%'    | '1/10W'  | 'IO'       | 'RESISTOR CHIP 30.1K 1/10W+-1%(0603)'              | 'CHIP0603'     | ''          | ''            | '20120529'
 '9.76K'      | '0.10%'   | '1/10W'  | '0603LF'  | 'CHIP'   | 'CS29763B903'(!)        = ''              | ''                 | 'CS29763B903'           |'R0603'| '(SMR0603AW)'                  | '9.76K'   | '0.10%' | '1/10W'  | 'DISCRETE' | 'RES CHIP 9.76K 1/10W +-0.1%(0603)'                | 'CHIP0603'     | ''          | ''            | '20120529'
 '9.76K'      | '0.10%'   | '1/10W'  | '0603LF'  | 'EMPTY'  | 'CS29763B903'(!)        = ''              | ''                 | 'CS29763B903'           |'R0603'| '(SMR0603AW)'                  | '9.76K'   | '0.10%' | '1/10W'  | 'IO'       | 'RES CHIP 9.76K 1/10W +-0.1%(0603)'                | 'CHIP0603'     | ''          | ''            | '20120529'
 '1K'         | '5%'      | '1/8W'   | '0805LF'  | 'CHIP'   | 'CS21004JA38'(!)        = ''              | ''                 | 'CS21004JA38'           |'R0805'| '(SMR0805AW)'                  | '1K'      | '5%'    | '1/8W'   | 'DISCRETE' | 'RES CHIP 1K 1/8W +-5%(0805)L-F'                   | 'CHIP0805'     | ''          | ''            | '20120529'
 '1K'         | '5%'      | '1/8W'   | '0805LF'  | 'EMPTY'  | 'CS21004JA38'(!)        = ''              | ''                 | 'CS21004JA38'           |'R0805'| '(SMR0805AW)'                  | '1K'      | '5%'    | '1/8W'   | 'IO'       | 'RES CHIP 1K 1/8W +-5%(0805)L-F'                   | 'CHIP0805'     | ''          | ''            | '20120529'
 '22K'        | '1%'      | '1/10W'  | '0603LF'  | 'CHIP'   | 'CS32203F914'(!)        = ''              | ''                 | 'CS32203F914'           |'R0603'| '(SMR0603AW)'                  | '22K'     | '1%'    | '1/10W'  | 'DISCRETE' | 'RES CHIP 22K 1/10W +-1%(0603)'                    | 'CHIP0603'     | ''          | ''            | '20120529'
 '22K'        | '1%'      | '1/10W'  | '0603LF'  | 'EMPTY'  | 'CS32203F914'(!)        = ''              | ''                 | 'CS32203F914'           |'R0603'| '(SMR0603AW)'                  | '22K'     | '1%'    | '1/10W'  | 'IO'       | 'RES CHIP 22K 1/10W +-1%(0603)'                    | 'CHIP0603'     | ''          | ''            | '20120529'
 '510K'       | '5%'      | '1/16W'  | '0402LF'  | 'CHIP'   | 'CS45102JB16'(!)        = 'End of Design' | 'Comp-Approve'     | 'CS45102JB16'           |'R0402'| '(R0402-0201)'                 | '510K'    | '5%'    | '1/16W'  | 'DISCRETE' | 'RES CHIP 510K(1/16W,+-5%,0402)'                   | 'CHIP0402'     | ''          | ''            | '20120614'
 '510K'       | '5%'      | '1/16W'  | '0402LF'  | 'EMPTY'  | 'CS45102JB16'(!)        = 'End of Design' | 'Comp-Approve'     | 'CS45102JB16'           |'R0402'| '(R0402-0201)'                 | '510K'    | '5%'    | '1/16W'  | 'IO'       | 'RES CHIP 510K(1/16W,+-5%,0402)'                   | 'CHIP0402'     | ''          | ''            | '20120614'
 '130K'       | '5%'      | '1/16W'  | '0402LF'  | 'CHIP'   | 'CS41302JB12'(!)        = 'End of Design' | 'Comp-Approve'     | 'CS41302JB12'           |'R0402'| '(R0402-0201)'                 | '130K'    | '5%'    | '1/16W'  | 'DISCRETE' | 'RES CHIP 130K 1/16W +-5%(0402)'                   | 'CHIP0402'     | ''          | ''            | '20120614'
 '130K'       | '5%'      | '1/16W'  | '0402LF'  | 'EMPTY'  | 'CS41302JB12'(!)        = 'End of Design' | 'Comp-Approve'     | 'CS41302JB12'           |'R0402'| '(R0402-0201)'                 | '130K'    | '5%'    | '1/16W'  | 'IO'       | 'RES CHIP 130K 1/16W +-5%(0402)'                   | 'CHIP0402'     | ''          | ''            | '20120614'
 '56.2'       | '1%'      | '1/16W'  | '0402LF'  | 'CHIP'   | 'CS05622FB22'(!)        = 'End of Design' | 'Comp-Approve'     | 'CS05622FB22'           |'R0402'| '(R0402-0201)'                 | '56.2'    | '1%'    | '1/16W'  | 'DISCRETE' | 'RESISTOR CHIP 56.2 1/16W +-1% (0402)'             | 'CHIP0402'     | ''          | ''            | '20120614'
 '56.2'       | '1%'      | '1/16W'  | '0402LF'  | 'EMPTY'  | 'CS05622FB22'(!)        = 'End of Design' | 'Comp-Approve'     | 'CS05622FB22'           |'R0402'| '(R0402-0201)'                 | '56.2'    | '1%'    | '1/16W'  | 'IO'       | 'RESISTOR CHIP 56.2 1/16W +-1% (0402)'             | 'CHIP0402'     | ''          | ''            | '20120614'
 '20'         | '5%'      | '1/4W'   | '1206LF'  | 'CHIP'   | 'CS02006J201'(!)        = ''              | ''                 | 'CS02006J201'           |'R1206'| '(SMR1206AW)'                  | '20'      | '5%'    | '1/4W'   | 'DISCRETE' | 'RES CHIP 20 1/4W +-5% (1206)'                     | 'CHIP1206'     | ''          | ''            | '20120614'
 '20'         | '5%'      | '1/4W'   | '1206LF'  | 'EMPTY'  | 'CS02006J201'(!)        = ''              | ''                 | 'CS02006J201'           |'R1206'| '(SMR1206AW)'                  | '20'      | '5%'    | '1/4W'   | 'IO'       | 'RES CHIP 20 1/4W +-5% (1206)'                     | 'CHIP1206'     | ''          | ''            | '20120614'
 '5.1'        | '5%'      | '1/4W'   | '1206LF'  | 'CHIP'   | 'CS-5106J205'(!)        = ''              | ''                 | 'CS-5106J205'           |'R1206'| '(SMR1206AW)'                  | '5.1'     | '5%'    | '1/4W'   | 'DISCRETE' | 'RES CHIP 5.1 1/4W +-5% (1206)'                    | 'CHIP1206'     | ''          | ''            | '20120614'
 '5.1'        | '5%'      | '1/4W'   | '1206LF'  | 'EMPTY'  | 'CS-5106J205'(!)        = ''              | ''                 | 'CS-5106J205'           |'R1206'| '(SMR1206AW)'                  | '5.1'     | '5%'    | '1/4W'   | 'IO'       | 'RES CHIP 5.1 1/4W +-5% (1206)'                    | 'CHIP1206'     | ''          | ''            | '20120614'
 '3.3'        | '5%'      | '1/20W'  | '0201LF'  | 'CHIP'   | 'CS-3301JE00'(!)        = ''              | ''                 | 'CS-3301JE00'           |'R0201'| '(SMR0201AW)'                  | '3.3'     | '5%'    | '1/20W'  | 'DISCRETE' | 'RES CHIP 3.3 1/20W +-5%(0201)'                    | 'CHIP0201'     | ''          | ''            | '20120615'
 '3.3'        | '5%'      | '1/20W'  | '0201LF'  | 'EMPTY'  | 'CS-3301JE00'(!)        = ''              | ''                 | 'CS-3301JE00'           |'R0201'| '(SMR0201AW)'                  | '3.3'     | '5%'    | '1/20W'  | 'IO'       | 'RES CHIP 3.3 1/20W +-5%(0201)'                    | 'CHIP0201'     | ''          | ''            | '20120615'
 '4.99'       | '1%'      | '1/20W'  | '0201LF'  | 'CHIP'   | 'CS-4991FE00'(!)        = ''              | ''                 | 'CS-4991FE00'           |'R0201'| '(SMR0201AW)'                  | '4.99'    | '1%'    | '1/20W'  | 'DISCRETE' | 'RES CHIP 4.99 1/20W +-1%(0201)'                   | 'CHIP0201'     | ''          | ''            | '20120615'
 '4.99'       | '1%'      | '1/20W'  | '0201LF'  | 'EMPTY'  | 'CS-4991FE00'(!)        = ''              | ''                 | 'CS-4991FE00'           |'R0201'| '(SMR0201AW)'                  | '4.99'    | '1%'    | '1/20W'  | 'IO'       | 'RES CHIP 4.99 1/20W +-1%(0201)'                   | 'CHIP0201'     | ''          | ''            | '20120615'
 '301'        | '1%'      | '1/20W'  | '0201LF'  | 'CHIP'   | 'CS13011FE01'(!)        = ''              | ''                 | 'CS13011FE01'           |'R0201'| '(SMR0201AW)'                  | '301'     | '1%'    | '1/20W'  | 'DISCRETE' | 'RES CHIP 301 1/20W +-1%(0201)'                    | 'CHIP0201'     | ''          | ''            | '20120615'
 '301'        | '1%'      | '1/20W'  | '0201LF'  | 'EMPTY'  | 'CS13011FE01'(!)        = ''              | ''                 | 'CS13011FE01'           |'R0201'| '(SMR0201AW)'                  | '301'     | '1%'    | '1/20W'  | 'IO'       | 'RES CHIP 301 1/20W +-1%(0201)'                    | 'CHIP0201'     | ''          | ''            | '20120615'
 '1.6K'       | '5%'      | '1/20W'  | '0201LF'  | 'CHIP'   | 'CS21601JE00'(!)        = ''              | ''                 | 'CS21601JE00'           |'R0201'| '(SMR0201AW)'                  | '1.6K'    | '5%'    | '1/20W'  | 'DISCRETE' | 'RES CHIP 1.6K 1/20W +-5%(0201)'                   | 'CHIP0201'     | ''          | ''            | '20120615'
 '1.6K'       | '5%'      | '1/20W'  | '0201LF'  | 'EMPTY'  | 'CS21601JE00'(!)        = ''              | ''                 | 'CS21601JE00'           |'R0201'| '(SMR0201AW)'                  | '1.6K'    | '5%'    | '1/20W'  | 'IO'       | 'RES CHIP 1.6K 1/20W +-5%(0201)'                   | 'CHIP0201'     | ''          | ''            | '20120615'
 '47K'        | '1%'      | '1/20W'  | '0201LF'  | 'CHIP'   | 'CS34701FE00'(!)        = ''              | ''                 | 'CS34701FE00'           |'R0201'| '(SMR0201AW)'                  | '47K'     | '1%'    | '1/20W'  | 'DISCRETE' | 'RES CHIP 47K 1/20W +-1%(0201)'                    | 'CHIP0201'     | ''          | ''            | '20120618'
 '47K'        | '1%'      | '1/20W'  | '0201LF'  | 'EMPTY'  | 'CS34701FE00'(!)        = ''              | ''                 | 'CS34701FE00'           |'R0201'| '(SMR0201AW)'                  | '47K'     | '1%'    | '1/20W'  | 'IO'       | 'RES CHIP 47K 1/20W +-1%(0201)'                    | 'CHIP0201'     | ''          | ''            | '20120618'
 '4.99K'      | '1%'      | '1/20W'  | '0201LF'  | 'CHIP'   | 'CS24991FE00'(!)        = ''              | ''                 | 'CS24991FE00'           |'R0201'| '(SMR0201AW)'                  | '4.99K'   | '1%'    | '1/20W'  | 'DISCRETE' | 'RES CHIP 4.99K(1/20W,+-1%,0201)'                  | 'CHIP0201'     | ''          | ''            | '20120622'
 '4.99K'      | '1%'      | '1/20W'  | '0201LF'  | 'EMPTY'  | 'CS24991FE00'(!)        = ''              | ''                 | 'CS24991FE00'           |'R0201'| '(SMR0201AW)'                  | '4.99K'   | '1%'    | '1/20W'  | 'IO'       | 'RES CHIP 4.99K(1/20W,+-1%,0201)'                  | 'CHIP0201'     | ''          | ''            | '20120622'
 '5.1K'       | '1%'      | '1/20W'  | '0201LF'  | 'CHIP'   | 'CS25101FE00'(!)        = 'End of Design' | 'Comp-Approve'     | 'CS25101FE00'           |'R0201'| '(SMR0201AW)'                  | '5.1K'    | '1%'    | '1/20W'  | 'DISCRETE' | 'RES CHIP 5.1K 1/20W +-1%(0201)'                   | 'CHIP0201'     | ''          | ''            | '20120622'
 '5.1K'       | '1%'      | '1/20W'  | '0201LF'  | 'EMPTY'  | 'CS25101FE00'(!)        = 'End of Design' | 'Comp-Approve'     | 'CS25101FE00'           |'R0201'| '(SMR0201AW)'                  | '5.1K'    | '1%'    | '1/20W'  | 'IO'       | 'RES CHIP 5.1K 1/20W +-1%(0201)'                   | 'CHIP0201'     | ''          | ''            | '20120622'
 '39.2'       | '1%'      | '1/16W'  | '0402LF'  | 'CHIP'   | 'CS03922FB01'(!)        = ''              | ''                 | 'CS03922FB01'           |'R0402'| '(R0402-0201)'                 | '39.2'    | '1%'    | '1/16W'  | 'DISCRETE' | 'RES CHIP 39.2 1/16W +-1%(0402)'                   | 'CHIP0402'     | ''          | ''            | '20120717'
 '39.2'       | '1%'      | '1/16W'  | '0402LF'  | 'EMPTY'  | 'CS03922FB01'(!)        = ''              | ''                 | 'CS03922FB01'           |'R0402'| '(R0402-0201)'                 | '39.2'    | '1%'    | '1/16W'  | 'IO'       | 'RES CHIP 39.2 1/16W +-1%(0402)'                   | 'CHIP0402'     | ''          | ''            | '20120717'
 '562K'       | '1%'      | '1/16W'  | '0402LF'  | 'CHIP'   | 'CS45622FB11'(!)        = 'End of Design' | 'Comp-Approve'     | 'CS45622FB11'           |'R0402'| '(R0402-0201)'                 | '562K'    | '1%'    | '1/16W'  | 'DISCRETE' | 'RES CHIP 562K 1/16W +-1%(0402)'                   | 'CHIP0402'     | ''          | ''            | '20120717'
 '562K'       | '1%'      | '1/16W'  | '0402LF'  | 'EMPTY'  | 'CS45622FB11'(!)        = 'End of Design' | 'Comp-Approve'     | 'CS45622FB11'           |'R0402'| '(R0402-0201)'                 | '562K'    | '1%'    | '1/16W'  | 'IO'       | 'RES CHIP 562K 1/16W +-1%(0402)'                   | 'CHIP0402'     | ''          | ''            | '20120717'
 '3.09K'      | '1%'      | '1/16W'  | '0402LF'  | 'CHIP'   | 'CS23092FB00'(!)        = 'End of Design' | 'Comp-Approve'     | 'CS23092FB00'           |'R0402'| '(R0402-0201)'                 | '3.09K'   | '1%'    | '1/16W'  | 'DISCRETE' | 'RES CHIP 3.09K 1/16W +-1%(0402)'                  | 'CHIP0402'     | ''          | ''            | '20120717'
 '3.09K'      | '1%'      | '1/16W'  | '0402LF'  | 'EMPTY'  | 'CS23092FB00'(!)        = 'End of Design' | 'Comp-Approve'     | 'CS23092FB00'           |'R0402'| '(R0402-0201)'                 | '3.09K'   | '1%'    | '1/16W'  | 'IO'       | 'RES CHIP 3.09K 1/16W +-1%(0402)'                  | 'CHIP0402'     | ''          | ''            | '20120717'
 '1.8K'       | '5%'      | '1/16W'  | '0402LF'  | 'CHIP'   | 'CS21802JB17'(!)        = 'End of Design' | 'Comp-Approve'     | 'CS21802JB17'           |'R0402'| '(R0402-0201)'                 | '1.8K'    | '5%'    | '1/16W'  | 'DISCRETE' | 'RES CHIP 1.8K 1/16W +-5%(0402)'                   | 'CHIP0402'     | ''          | ''            | '20120717'
 '1.8K'       | '5%'      | '1/16W'  | '0402LF'  | 'EMPTY'  | 'CS21802JB17'(!)        = 'End of Design' | 'Comp-Approve'     | 'CS21802JB17'           |'R0402'| '(R0402-0201)'                 | '1.8K'    | '5%'    | '1/16W'  | 'IO'       | 'RES CHIP 1.8K 1/16W +-5%(0402)'                   | 'CHIP0402'     | ''          | ''            | '20120717'
 '1M'         | '1%'      | '1/10W'  | '0603LF'  | 'CHIP'   | 'CS51003F934'(!)        = ''              | ''                 | 'CS51003F934'           |'R0603'| '(SMR0603AW)'                  | '1M'      | '1%'    | '1/10W'  | 'DISCRETE' | 'RESISTOR CHIP 1M 1/10W+-1%(0603)'                 | 'CHIP0603'     | ''          | ''            | '20120717'
 '1M'         | '1%'      | '1/10W'  | '0603LF'  | 'EMPTY'  | 'CS51003F934'(!)        = ''              | ''                 | 'CS51003F934'           |'R0603'| '(SMR0603AW)'                  | '1M'      | '1%'    | '1/10W'  | 'IO'       | 'RESISTOR CHIP 1M 1/10W+-1%(0603)'                 | 'CHIP0603'     | ''          | ''            | '20120717'
 '910'        | '1%'      | '1/16W'  | '0402LF'  | 'CHIP'   | 'CS19102FB01'(!)        = ''              | ''                 | 'CS19102FB01'           |'R0402'| '(R0402-0201)'                 | '910'     | '1%'    | '1/16W'  | 'DISCRETE' | 'RES CHIP 910(1/16W,1%,0402)'                      | 'CHIP0402'     | ''          | ''            | '20120724'
 '910'        | '1%'      | '1/16W'  | '0402LF'  | 'EMPTY'  | 'CS19102FB01'(!)        = ''              | ''                 | 'CS19102FB01'           |'R0402'| '(R0402-0201)'                 | '910'     | '1%'    | '1/16W'  | 'IO'       | 'RES CHIP 910(1/16W,1%,0402)'                      | 'CHIP0402'     | ''          | ''            | '20120724'
 '4.87K'      | '1%'      | '1/16W'  | '0402LF'  | 'CHIP'   | 'CS24872FB07'(!)        = 'End of Design' | 'Comp-Approve'     | 'CS24872FB07'           |'R0402'| '(R0402-0201)'                 | '4.87K'   | '1%'    | '1/16W'  | 'DISCRETE' | 'RES CHIP 4.87K 1/16W+-1%(0402)'                   | 'CHIP0402'     | ''          | ''            | '20120730'
 '4.87K'      | '1%'      | '1/16W'  | '0402LF'  | 'EMPTY'  | 'CS24872FB07'(!)        = 'End of Design' | 'Comp-Approve'     | 'CS24872FB07'           |'R0402'| '(R0402-0201)'                 | '4.87K'   | '1%'    | '1/16W'  | 'IO'       | 'RES CHIP 4.87K 1/16W+-1%(0402)'                   | 'CHIP0402'     | ''          | ''            | '20120730'
 '590'        | '1%'      | '1/16W'  | '0402LF'  | 'CHIP'   | 'CS15902FB00'(!)        = 'End of Design' | 'Comp-Approve'     | 'CS15902FB00'           |'R0402'| '(R0402-0201)'                 | '590'     | '1%'    | '1/16W'  | 'DISCRETE' | 'RES CHIP 590 1/16W +-1%(0402)'                    | 'CHIP0402'     | ''          | ''            | '20120801'
 '590'        | '1%'      | '1/16W'  | '0402LF'  | 'EMPTY'  | 'CS15902FB00'(!)        = 'End of Design' | 'Comp-Approve'     | 'CS15902FB00'           |'R0402'| '(R0402-0201)'                 | '590'     | '1%'    | '1/16W'  | 'IO'       | 'RES CHIP 590 1/16W +-1%(0402)'                    | 'CHIP0402'     | ''          | ''            | '20120801'
 '147K'       | '1%'      | '1/16W'  | '0402LF'  | 'CHIP'   | 'CS41472FB16'(!)        = 'End of Design' | 'Comp-Approve'     | 'CS41472FB16'           |'R0402'| '(R0402-0201)'                 | '147K'    | '1%'    | '1/16W'  | 'DISCRETE' | 'RES CHIP 147K 1/16W +-1%(0402)'                   | 'CHIP0402'     | ''          | ''            | '20120801'
 '147K'       | '1%'      | '1/16W'  | '0402LF'  | 'EMPTY'  | 'CS41472FB16'(!)        = 'End of Design' | 'Comp-Approve'     | 'CS41472FB16'           |'R0402'| '(R0402-0201)'                 | '147K'    | '1%'    | '1/16W'  | 'IO'       | 'RES CHIP 147K 1/16W +-1%(0402)'                   | 'CHIP0402'     | ''          | ''            | '20120801'
 '510K'       | '5%'      | '1/16W'  | '0402LF'  | 'CHIP'   | 'CS45102JB08'(!)        = ''              | ''                 | 'CS45102JB08'           |'R0402'| '(R0402-0201)'                 | '510K'    | '5%'    | '1/16W'  | 'DISCRETE' | 'RES CHIP 510K(1/16W.+-5%.0402)'                   | 'CHIP0402'     | ''          | ''            | '20120801'
 '510K'       | '5%'      | '1/16W'  | '0402LF'  | 'EMPTY'  | 'CS45102JB08'(!)        = ''              | ''                 | 'CS45102JB08'           |'R0402'| '(R0402-0201)'                 | '510K'    | '5%'    | '1/16W'  | 'IO'       | 'RES CHIP 510K(1/16W.+-5%.0402)'                   | 'CHIP0402'     | ''          | ''            | '20120801'
 '6.8K'       | '1%'      | '1/16W'  | '0402LF'  | 'CHIP'   | 'CS26802FB19'(!)        = 'End of Design' | 'Comp-Approve'     | 'CS26802FB19'           |'R0402'| '(R0402-0201)'                 | '6.8K'    | '1%'    | '1/16W'  | 'DISCRETE' | 'RES CHIP 6.8K 1/16W +-1%(0402)'                   | 'CHIP0402'     | ''          | ''            | '20120801'
 '6.8K'       | '1%'      | '1/16W'  | '0402LF'  | 'EMPTY'  | 'CS26802FB19'(!)        = 'End of Design' | 'Comp-Approve'     | 'CS26802FB19'           |'R0402'| '(R0402-0201)'                 | '6.8K'    | '1%'    | '1/16W'  | 'IO'       | 'RES CHIP 6.8K 1/16W +-1%(0402)'                   | 'CHIP0402'     | ''          | ''            | '20120801'
 '619'        | '1%'      | '1/16W'  | '0402LF'  | 'CHIP'   | 'CS16192FB04'(!)        = ''              | ''                 | 'CS16192FB04'           |'R0402'| '(R0402-0201)'                 | '619'     | '1%'    | '1/16W'  | 'DISCRETE' | ' RES CHIP 619 1/16W +-1%(0402)'                   | 'CHIP0402'     | ''          | ''            | '20120807'
 '619'        | '1%'      | '1/16W'  | '0402LF'  | 'EMPTY'  | 'CS16192FB04'(!)        = ''              | ''                 | 'CS16192FB04'           |'R0402'| '(R0402-0201)'                 | '619'     | '1%'    | '1/16W'  | 'IO'       | ' RES CHIP 619 1/16W +-1%(0402)'                   | 'CHIP0402'     | ''          | ''            | '20120807'
 '11'         | '1%'      | '1/16W'  | '0402LF'  | 'CHIP'   | 'CS01102FB08'(!)        = 'End of Design' | 'Comp-Approve'     | 'CS01102FB08'           |'R0402'| '(R0402-0201)'                 | '11'      | '1%'    | '1/16W'  | 'DISCRETE' | 'RES CHIP 11 1/16W +-1%(0402)'                     | 'CHIP0402'     | ''          | ''            | '20120808'
 '11'         | '1%'      | '1/16W'  | '0402LF'  | 'EMPTY'  | 'CS01102FB08'(!)        = 'End of Design' | 'Comp-Approve'     | 'CS01102FB08'           |'R0402'| '(R0402-0201)'                 | '11'      | '1%'    | '1/16W'  | 'IO'       | 'RES CHIP 11 1/16W +-1%(0402)'                     | 'CHIP0402'     | ''          | ''            | '20120808'
 '191'        | '1%'      | '1/16W'  | '0402LF'  | 'CHIP'   | 'CS11912FB00'(!)        = 'End of Design' | 'Comp-Approve'     | 'CS11912FB00'           |'R0402'| '(R0402-0201)'                 | '191'     | '1%'    | '1/16W'  | 'DISCRETE' | 'RES CHIP 191 1/16W +-1%(0402)'                    | 'CHIP0402'     | ''          | ''            | '20120813'
 '191'        | '1%'      | '1/16W'  | '0402LF'  | 'EMPTY'  | 'CS11912FB00'(!)        = 'End of Design' | 'Comp-Approve'     | 'CS11912FB00'           |'R0402'| '(R0402-0201)'                 | '191'     | '1%'    | '1/16W'  | 'IO'       | 'RES CHIP 191 1/16W +-1%(0402)'                    | 'CHIP0402'     | ''          | ''            | '20120813'
 '27K'        | '1%'      | '1/16W'  | '0402LF'  | 'CHIP'   | 'CS32702FB16'(!)        = 'End of Design' | 'Comp-Approve'     | 'CS32702FB16'           |'R0402'| '(R0402-0201)'                 | '27K'     | '1%'    | '1/16W'  | 'DISCRETE' | 'RES CHIP 27K 1/16W +-1%(0402)'                    | 'CHIP0402'     | ''          | ''            | '20120816'
 '27K'        | '1%'      | '1/16W'  | '0402LF'  | 'EMPTY'  | 'CS32702FB16'(!)        = 'End of Design' | 'Comp-Approve'     | 'CS32702FB16'           |'R0402'| '(R0402-0201)'                 | '27K'     | '1%'    | '1/16W'  | 'IO'       | 'RES CHIP 27K 1/16W +-1%(0402)'                    | 'CHIP0402'     | ''          | ''            | '20120816'
 '255K'       | '1%'      | '1/16W'  | '0402LF'  | 'CHIP'   | 'CS42552FB05'(!)        = 'End of Design' | 'Comp-Approve'     | 'CS42552FB05'           |'R0402'| '(R0402-0201)'                 | '255K'    | '1%'    | '1/16W'  | 'DISCRETE' | 'RES CHIP 255K 1/16W +-1%(0402)'                   | 'CHIP0402'     | ''          | ''            | '20120816'
 '255K'       | '1%'      | '1/16W'  | '0402LF'  | 'EMPTY'  | 'CS42552FB05'(!)        = 'End of Design' | 'Comp-Approve'     | 'CS42552FB05'           |'R0402'| '(R0402-0201)'                 | '255K'    | '1%'    | '1/16W'  | 'IO'       | 'RES CHIP 255K 1/16W +-1%(0402)'                   | 'CHIP0402'     | ''          | ''            | '20120816'
 '226'        | '1%'      | '1/16W'  | '0402LF'  | 'CHIP'   | 'CS12262FB11'(!)        = 'End of Design' | 'Comp-Approve'     | 'CS12262FB11'           |'R0402'| '(R0402-0201)'                 | '226'     | '1%'    | '1/16W'  | 'DISCRETE' | 'RES CHIP 226. 1/16W. +-1% (0402)'                 | 'CHIP0402'     | ''          | ''            | '20120829'
 '226'        | '1%'      | '1/16W'  | '0402LF'  | 'EMPTY'  | 'CS12262FB11'(!)        = 'End of Design' | 'Comp-Approve'     | 'CS12262FB11'           |'R0402'| '(R0402-0201)'                 | '226'     | '1%'    | '1/16W'  | 'IO'       | 'RES CHIP 226. 1/16W. +-1% (0402)'                 | 'CHIP0402'     | ''          | ''            | '20120829'
 '52.3K'      | '1%'      | '1/16W'  | '0402LF'  | 'CHIP'   | 'CS35232FB01'(!)        = ''              | ''                 | 'CS35232FB01'           |'R0402'| '(R0402-0201)'                 | '52.3K'   | '1%'    | '1/16W'  | 'DISCRETE' | 'RES CHIP 52.3K 1/16W +-1% (0402)'                 | 'CHIP0402'     | ''          | ''            | '20120904'
 '52.3K'      | '1%'      | '1/16W'  | '0402LF'  | 'EMPTY'  | 'CS35232FB01'(!)        = ''              | ''                 | 'CS35232FB01'           |'R0402'| '(R0402-0201)'                 | '52.3K'   | '1%'    | '1/16W'  | 'IO'       | 'RES CHIP 52.3K 1/16W +-1% (0402)'                 | 'CHIP0402'     | ''          | ''            | '20120904'
 '274K'       | '1%'      | '1/16W'  | '0402LF'  | 'CHIP'   | 'CS42742FB00'(!)        = 'End of Design' | 'Comp-Approve'     | 'CS42742FB00'           |'R0402'| '(R0402-0201)'                 | '274K'    | '1%'    | '1/16W'  | 'DISCRETE' | 'RES CHP 274K 1/16W +-1%(0402)'                    | 'CHIP0402'     | ''          | ''            | '20120904'
 '274K'       | '1%'      | '1/16W'  | '0402LF'  | 'EMPTY'  | 'CS42742FB00'(!)        = 'End of Design' | 'Comp-Approve'     | 'CS42742FB00'           |'R0402'| '(R0402-0201)'                 | '274K'    | '1%'    | '1/16W'  | 'IO'       | 'RES CHP 274K 1/16W +-1%(0402)'                    | 'CHIP0402'     | ''          | ''            | '20120904'
 '487K'       | '1%'      | '1/16W'  | '0402LF'  | 'CHIP'   | 'CS44872FB19'(!)        = 'End of Design' | 'Comp-Approve'     | 'CS44872FB19'           |'R0402'| '(R0402-0201)'                 | '487K'    | '1%'    | '1/16W'  | 'DISCRETE' | 'RES CHIP 487K 1/16W +-1%( 0402)L-F'               | 'CHIP0402'     | ''          | ''            | '20120904'
 '487K'       | '1%'      | '1/16W'  | '0402LF'  | 'EMPTY'  | 'CS44872FB19'(!)        = 'End of Design' | 'Comp-Approve'     | 'CS44872FB19'           |'R0402'| '(R0402-0201)'                 | '487K'    | '1%'    | '1/16W'  | 'IO'       | 'RES CHIP 487K 1/16W +-1%( 0402)L-F'               | 'CHIP0402'     | ''          | ''            | '20120904'
 '2.87K'      | '1%'      | '1/16W'  | '0402LF'  | 'CHIP'   | 'CS22872FB10'(!)        = 'End of Design' | 'Comp-Approve'     | 'CS22872FB10'           |'R0402'| '(R0402-0201)'                 | '2.87K'   | '1%'    | '1/16W'  | 'DISCRETE' | 'RES CHIP 2.87K 1/16W +-1%(0402)'                  | 'CHIP0402'     | ''          | ''            | '20120904'
 '2.87K'      | '1%'      | '1/16W'  | '0402LF'  | 'EMPTY'  | 'CS22872FB10'(!)        = 'End of Design' | 'Comp-Approve'     | 'CS22872FB10'           |'R0402'| '(R0402-0201)'                 | '2.87K'   | '1%'    | '1/16W'  | 'IO'       | 'RES CHIP 2.87K 1/16W +-1%(0402)'                  | 'CHIP0402'     | ''          | ''            | '20120904'
 '316K'       | '1%'      | '1/16W'  | '0402LF'  | 'CHIP'   | 'CS43162FB00'(!)        = 'End of Design' | 'Comp-Approve'     | 'CS43162FB00'           |'R0402'| '(R0402-0201)'                 | '316K'    | '1%'    | '1/16W'  | 'DISCRETE' | 'RES CHIP 316K 1/16W +-1%(0402)'                   | 'CHIP0402'     | ''          | ''            | '20120906'
 '316K'       | '1%'      | '1/16W'  | '0402LF'  | 'EMPTY'  | 'CS43162FB00'(!)        = 'End of Design' | 'Comp-Approve'     | 'CS43162FB00'           |'R0402'| '(R0402-0201)'                 | '316K'    | '1%'    | '1/16W'  | 'IO'       | 'RES CHIP 316K 1/16W +-1%(0402)'                   | 'CHIP0402'     | ''          | ''            | '20120906'
 '348K'       | '1%'      | '1/16W'  | '0402LF'  | 'CHIP'   | 'CS43482FB16'(!)        = 'End of Design' | 'Comp-Approve'     | 'CS43482FB16'           |'R0402'| '(R0402-0201)'                 | '348K'    | '1%'    | '1/16W'  | 'DISCRETE' | 'RES CHIP 348K 1/16W +-1%( 0402)'                  | 'CHIP0402'     | ''          | ''            | '20120906'
 '348K'       | '1%'      | '1/16W'  | '0402LF'  | 'EMPTY'  | 'CS43482FB16'(!)        = 'End of Design' | 'Comp-Approve'     | 'CS43482FB16'           |'R0402'| '(R0402-0201)'                 | '348K'    | '1%'    | '1/16W'  | 'IO'       | 'RES CHIP 348K 1/16W +-1%( 0402)'                  | 'CHIP0402'     | ''          | ''            | '20120906'
 '360K'       | '1%'      | '1/16W'  | '0402LF'  | 'CHIP'   | 'CS43602FB00'(!)        = 'End of Design' | 'Comp-Approve'     | 'CS43602FB00'           |'R0402'| '(R0402-0201)'                 | '360K'    | '1%'    | '1/16W'  | 'DISCRETE' | 'RES CHIP 360K 1/16W +-1%(0402)'                   | 'CHIP0402'     | ''          | ''            | '20120906'
 '360K'       | '1%'      | '1/16W'  | '0402LF'  | 'EMPTY'  | 'CS43602FB00'(!)        = 'End of Design' | 'Comp-Approve'     | 'CS43602FB00'           |'R0402'| '(R0402-0201)'                 | '360K'    | '1%'    | '1/16W'  | 'IO'       | 'RES CHIP 360K 1/16W +-1%(0402)'                   | 'CHIP0402'     | ''          | ''            | '20120906'
 '499'        | '1%'      | '1/16W'  | '0402LF'  | 'CHIP'   | 'CS14992FB24'(!)        = 'End of Design' | 'Comp-Approve'     | 'CS14992FB24'           |'R0402'| '(R0402-0201)'                 | '499'     | '1%'    | '1/16W'  | 'DISCRETE' | 'RES CHIP 499 1/16W +-1%(0402)'                    | 'CHIP0402'     | ''          | ''            | '20120913'
 '499'        | '1%'      | '1/16W'  | '0402LF'  | 'EMPTY'  | 'CS14992FB24'(!)        = 'End of Design' | 'Comp-Approve'     | 'CS14992FB24'           |'R0402'| '(R0402-0201)'                 | '499'     | '1%'    | '1/16W'  | 'IO'       | 'RES CHIP 499 1/16W +-1%(0402)'                    | 'CHIP0402'     | ''          | ''            | '20120913'
 '1.82K'      | '1%'      | '1/16W'  | '0402LF'  | 'CHIP'   | 'CS21822FB14'(!)        = 'End of Design' | 'Comp-Approve'     | 'CS21822FB14'           |'R0402'| '(R0402-0201)'                 | '1.82K'   | '1%'    | '1/16W'  | 'DISCRETE' | 'RES CHIP 1.82K 1/16W +-1%(0402)'                  | 'CHIP0402'     | ''          | ''            | '20120913'
 '1.82K'      | '1%'      | '1/16W'  | '0402LF'  | 'EMPTY'  | 'CS21822FB14'(!)        = 'End of Design' | 'Comp-Approve'     | 'CS21822FB14'           |'R0402'| '(R0402-0201)'                 | '1.82K'   | '1%'    | '1/16W'  | 'IO'       | 'RES CHIP 1.82K 1/16W +-1%(0402)'                  | 'CHIP0402'     | ''          | ''            | '20120913'
 '3.24K'      | '1%'      | '1/16W'  | '0402LF'  | 'CHIP'   | 'CS23242FB17'(!)        = 'End of Design' | 'Comp-Approve'     | 'CS23242FB17'           |'R0402'| '(R0402-0201)'                 | '3.24K'   | '1%'    | '1/16W'  | 'DISCRETE' | 'RES CHIP 3.24K +-1% 1/16W(0402) EP'               | 'CHIP0402'     | ''          | ''            | '20120913'
 '3.24K'      | '1%'      | '1/16W'  | '0402LF'  | 'EMPTY'  | 'CS23242FB17'(!)        = 'End of Design' | 'Comp-Approve'     | 'CS23242FB17'           |'R0402'| '(R0402-0201)'                 | '3.24K'   | '1%'    | '1/16W'  | 'IO'       | 'RES CHIP 3.24K +-1% 1/16W(0402) EP'               | 'CHIP0402'     | ''          | ''            | '20120913'
 '2.0'        | '1%'      | '1/16W'  | '0402LF'  | 'CHIP'   | 'CS-2002FB00'(!)        = 'End of Design' | 'Comp-Approve'     | 'CS-2002FB00'           |'R0402'| '(R0402-0201)'                 | '2.0'     | '1%'    | '1/16W'  | 'DISCRETE' | 'RES CHIP 2.0 1/16W +1%(0402)'                     | 'CHIP0402'     | ''          | ''            | '20120919'
 '2.0'        | '1%'      | '1/16W'  | '0402LF'  | 'EMPTY'  | 'CS-2002FB00'(!)        = 'End of Design' | 'Comp-Approve'     | 'CS-2002FB00'           |'R0402'| '(R0402-0201)'                 | '2.0'     | '1%'    | '1/16W'  | 'IO'       | 'RES CHIP 2.0 1/16W +1%(0402)'                     | 'CHIP0402'     | ''          | ''            | '20120919'
 '32.4K'      | '1%'      | '1/16W'  | '0402LF'  | 'CHIP'   | 'CS33242FB19'(!)        = 'End of Design' | 'Comp-Approve'     | 'CS33242FB19'           |'R0402'| '(R0402-0201)'                 | '32.4K'   | '1%'    | '1/16W'  | 'DISCRETE' | 'RES CHIP 32.4K 1/16W +-1%(0402)'                  | 'CHIP0402'     | ''          | ''            | '20120925'
 '32.4K'      | '1%'      | '1/16W'  | '0402LF'  | 'EMPTY'  | 'CS33242FB19'(!)        = 'End of Design' | 'Comp-Approve'     | 'CS33242FB19'           |'R0402'| '(R0402-0201)'                 | '32.4K'   | '1%'    | '1/16W'  | 'IO'       | 'RES CHIP 32.4K 1/16W +-1%(0402)'                  | 'CHIP0402'     | ''          | ''            | '20120925'
 '1.4K'       | '1%'      | '1/16W'  | '0402LF'  | 'CHIP'   | 'CS21402FB02'(!)        = 'End of Design' | 'Comp-Approve'     | 'CS21402FB02'           |'R0402'| '(R0402-0201)'                 | '1.4K'    | '1%'    | '1/16W'  | 'DISCRETE' | 'RES CHIP 1.4K 1/16W +-1%(0402)'                   | 'CHIP0402'     | ''          | ''            | '20120925'
 '1.4K'       | '1%'      | '1/16W'  | '0402LF'  | 'EMPTY'  | 'CS21402FB02'(!)        = 'End of Design' | 'Comp-Approve'     | 'CS21402FB02'           |'R0402'| '(R0402-0201)'                 | '1.4K'    | '1%'    | '1/16W'  | 'IO'       | 'RES CHIP 1.4K 1/16W +-1%(0402)'                   | 'CHIP0402'     | ''          | ''            | '20120925'
 '825'        | '1%'      | '1/16W'  | '0402LF'  | 'CHIP'   | 'CS18252FB00'(!)        = 'End of Design' | 'Comp-Approve'     | 'CS18252FB00'           |'R0402'| '(R0402-0201)'                 | '825'     | '1%'    | '1/16W'  | 'DISCRETE' | 'RES CHIP 825 1/16W +-1% (0402)'                   | 'CHIP0402'     | ''          | ''            | '20121003'
 '825'        | '1%'      | '1/16W'  | '0402LF'  | 'EMPTY'  | 'CS18252FB00'(!)        = 'End of Design' | 'Comp-Approve'     | 'CS18252FB00'           |'R0402'| '(R0402-0201)'                 | '825'     | '1%'    | '1/16W'  | 'IO'       | 'RES CHIP 825 1/16W +-1% (0402)'                   | 'CHIP0402'     | ''          | ''            | '20121003'
 '61.9'       | '1%'      | '1/16W'  | '0402LF'  | 'CHIP'   | 'CS06192FB02'(!)        = 'End of Design' | 'Comp-Approve'     | 'CS06192FB02'           |'R0402'| '(R0402-0201)'                 | '61.9'    | '1%'    | '1/16W'  | 'DISCRETE' | 'RES CHIP 61.9 1/16W 1%(0402)'                     | 'CHIP0402'     | ''          | ''            | '20121017'
 '61.9'       | '1%'      | '1/16W'  | '0402LF'  | 'EMPTY'  | 'CS06192FB02'(!)        = 'End of Design' | 'Comp-Approve'     | 'CS06192FB02'           |'R0402'| '(R0402-0201)'                 | '61.9'    | '1%'    | '1/16W'  | 'IO'       | 'RES CHIP 61.9 1/16W 1%(0402)'                     | 'CHIP0402'     | ''          | ''            | '20121017'
 '0'          | '1%'      | '1/2W'   | '1206LF'  | 'CHIP'   | 'CS00007F200'(!)        = ''              | ''                 | 'CS00007F200'           |'R1206'| '(SMR1206AW)'                  | '0'       | '1%'    | '1/2W'   | 'DISCRETE' | 'RES CHIP 0 1/2W +-1%(1206)'                       | 'CHIP1206'     | ''          | ''            | '20121023'
 '0'          | '1%'      | '1/2W'   | '1206LF'  | 'EMPTY'  | 'CS00007F200'(!)        = ''              | ''                 | 'CS00007F200'           |'R1206'| '(SMR1206AW)'                  | '0'       | '1%'    | '1/2W'   | 'IO'       | 'RES CHIP 0 1/2W +-1%(1206)'                       | 'CHIP1206'     | ''          | ''            | '20121023'
 '0.001'      | '1%'      | '1W'     | '3720LF'  | 'CHIP'   | 'CS+0018FL00'(!)        = ''              | ''                 | 'CS+0018FL00'           |'R3720'| '(SMR3720AW)'                  | '0.001'   | '1%'    | '1W'     | 'DISCRETE' | 'RES CHIP 0.001 1W +-1%(3720)'                     | 'CHIP3720'     | ''          | ''            | '20121023'
 '0.001'      | '1%'      | '1W'     | '3720LF'  | 'EMPTY'  | 'CS+0018FL00'(!)        = ''              | ''                 | 'CS+0018FL00'           |'R3720'| '(SMR3720AW)'                  | '0.001'   | '1%'    | '1W'     | 'IO'       | 'RES CHIP 0.001 1W +-1%(3720)'                     | 'CHIP3720'     | ''          | ''            | '20121023'
 '6.8M'       | '5%'      | '1/16W'  | '0402LF'  | 'CHIP'   | 'CS56802JB00'(!)        = ''              | ''                 | 'CS56802JB00'           |'R0402'| '(R0402-0201)'                 | '6.8M'    | '5%'    | '1/16W'  | 'DISCRETE' | 'RESISTOR CHIP 6.8M 1/16W +-5%(0402)'              | 'CHIP0402'     | ''          | ''            | '20121024'
 '6.8M'       | '5%'      | '1/16W'  | '0402LF'  | 'EMPTY'  | 'CS56802JB00'(!)        = ''              | ''                 | 'CS56802JB00'           |'R0402'| '(R0402-0201)'                 | '6.8M'    | '5%'    | '1/16W'  | 'IO'       | 'RESISTOR CHIP 6.8M 1/16W +-5%(0402)'              | 'CHIP0402'     | ''          | ''            | '20121024'
 '0.004'      | '1%'      | '1W'     | '1206LF'  | 'CHIP'   | 'CS+0048F200'(!)        = ''              | ''                 | 'CS+0048F200'           |'R1206XA'| '(SMR1206AW)'                  | '0.004'   | '1%'    | '1W'     | 'DISCRETE' | 'RES CHIP 0.004 1W +-1%(1206)'                     | 'CHIP1206'     | ''          | ''            | '20121029'
 '0.004'      | '1%'      | '1W'     | '1206LF'  | 'EMPTY'  | 'CS+0048F200'(!)        = ''              | ''                 | 'CS+0048F200'           |'R1206XA'| '(SMR1206AW)'                  | '0.004'   | '1%'    | '1W'     | 'IO'       | 'RES CHIP 0.004 1W +-1%(1206)'                     | 'CHIP1206'     | ''          | ''            | '20121029'
 '255'        | '1%'      | '1/16W'  | '0402LF'  | 'CHIP'   | 'CS12552FB18'(!)        = 'End of Design' | 'Comp-Approve'     | 'CS12552FB18'           |'R0402'| '(R0402-0201)'                 | '255'     | '1%'    | '1/16W'  | 'DISCRETE' | 'RES CHIP 255 1/16W +-1%(0402)'                    | 'CHIP0402'     | ''          | ''            | '20121031'
 '255'        | '1%'      | '1/16W'  | '0402LF'  | 'EMPTY'  | 'CS12552FB18'(!)        = 'End of Design' | 'Comp-Approve'     | 'CS12552FB18'           |'R0402'| '(R0402-0201)'                 | '255'     | '1%'    | '1/16W'  | 'IO'       | 'RES CHIP 255 1/16W +-1%(0402)'                    | 'CHIP0402'     | ''          | ''            | '20121031'
 '261K'       | '1%'      | '1/16'   | '0402LF'  | 'CHIP'   | 'CS42612FB00'(!)        = 'End of Design' | 'Comp-Approve'     | 'CS42612FB00'           |'R0402'| '(R0402-0201)'                 | '261K'    | '1%'    | '1/16'   | 'DISCRETE' | 'RES CHIP 261K 1/16 +-1%(0402)'                    | 'CHIP0402'     | ''          | ''            | '20121114'
 '261K'       | '1%'      | '1/16'   | '0402LF'  | 'EMPTY'  | 'CS42612FB00'(!)        = 'End of Design' | 'Comp-Approve'     | 'CS42612FB00'           |'R0402'| '(R0402-0201)'                 | '261K'    | '1%'    | '1/16'   | 'IO'       | 'RES CHIP 261K 1/16 +-1%(0402)'                    | 'CHIP0402'     | ''          | ''            | '20121114'
 '680K'       | '1%'      | '1/16'   | '0402LF'  | 'CHIP'   | 'CS46802FB00'(!)        = 'End of Design' | 'Comp-Approve'     | 'CS46802FB00'           |'R0402'| '(R0402-0201)'                 | '680K'    | '1%'    | '1/16'   | 'DISCRETE' | 'RES CHIP 680K 1/16W +-1%(0402)'                   | 'CHIP0402'     | ''          | ''            | '20121115'
 '680K'       | '1%'      | '1/16'   | '0402LF'  | 'EMPTY'  | 'CS46802FB00'(!)        = 'End of Design' | 'Comp-Approve'     | 'CS46802FB00'           |'R0402'| '(R0402-0201)'                 | '680K'    | '1%'    | '1/16'   | 'IO'       | 'RES CHIP 680K 1/16W +-1%(0402)'                   | 'CHIP0402'     | ''          | ''            | '20121115'
 '649'        | '1%'      | '1/16W'  | '0402LF'  | 'CHIP'   | 'CS16492FB13'(!)        = 'End of Design' | 'Comp-Approve'     | 'CS16492FB13'           |'R0402'| '(R0402-0201)'                 | '649'     | '1%'    | '1/16W'  | 'DISCRETE' | 'RES CHIP 649 1/16W +-1%(0402) -EP'                | 'CHIP0402'     | ''          | ''            | '20121120'
 '649'        | '1%'      | '1/16W'  | '0402LF'  | 'EMPTY'  | 'CS16492FB13'(!)        = 'End of Design' | 'Comp-Approve'     | 'CS16492FB13'           |'R0402'| '(R0402-0201)'                 | '649'     | '1%'    | '1/16W'  | 'IO'       | 'RES CHIP 649 1/16W +-1%(0402) -EP'                | 'CHIP0402'     | ''          | ''            | '20121120'
 '160'        | '1%'      | '1/16W'  | '0402LF'  | 'CHIP'   | 'CS11602FB00'(!)        = 'End of Design' | 'Comp-Approve'     | 'CS11602FB00'           |'R0402'| '(R0402-0201)'                 | '160'     | '1%'    | '1/16W'  | 'DISCRETE' | 'RES CHIP 160 1/16W +-1%(0402)'                    | 'CHIP0402'     | ''          | ''            | '20121122'
 '160'        | '1%'      | '1/16W'  | '0402LF'  | 'EMPTY'  | 'CS11602FB00'(!)        = 'End of Design' | 'Comp-Approve'     | 'CS11602FB00'           |'R0402'| '(R0402-0201)'                 | '160'     | '1%'    | '1/16W'  | 'IO'       | 'RES CHIP 160 1/16W +-1%(0402)'                    | 'CHIP0402'     | ''          | ''            | '20121122'
 '390'        | '1%'      | '1/10W'  | '0603LF'  | 'CHIP'   | 'CS13903F919'(!)        = ''              | ''                 | 'CS13903F919'           |'R0603'| '(SMR0603AW)'                  | '390'     | '1%'    | '1/10W'  | 'DISCRETE' | 'RES CHIP 390 1/10W +-1%(0603)'                    | 'CHIP0603'     | ''          | ''            | '20121128'
 '390'        | '1%'      | '1/10W'  | '0603LF'  | 'EMPTY'  | 'CS13903F919'(!)        = ''              | ''                 | 'CS13903F919'           |'R0603'| '(SMR0603AW)'                  | '390'     | '1%'    | '1/10W'  | 'IO'       | 'RES CHIP 390 1/10W +-1%(0603)'                    | 'CHIP0603'     | ''          | ''            | '20121128'
 '82.5K'      | '1%'      | '1/16W'  | '0402LF'  | 'CHIP'   | 'CS38252FB17'(!)        = 'End of Design' | 'Comp-Approve'     | 'CS38252FB17'           |'R0402'| '(R0402-0201)'                 | '82.5K'   | '1%'    | '1/16W'  | 'DISCRETE' | 'RES CHIP 82.5K 1/16W +-1%(0402)'                  | 'CHIP0402'     | ''          | ''            | '20121128'
 '82.5K'      | '1%'      | '1/16W'  | '0402LF'  | 'EMPTY'  | 'CS38252FB17'(!)        = 'End of Design' | 'Comp-Approve'     | 'CS38252FB17'           |'R0402'| '(R0402-0201)'                 | '82.5K'   | '1%'    | '1/16W'  | 'IO'       | 'RES CHIP 82.5K 1/16W +-1%(0402)'                  | 'CHIP0402'     | ''          | ''            | '20121128'
 '604K'       | '1%'      | '1/16W'  | '0402LF'  | 'CHIP'   | 'CS46042FB11'(!)        = 'End of Design' | 'Comp-Approve'     | 'CS46042FB11'           |'R0402'| '(R0402-0201)'                 | '604K'    | '1%'    | '1/16W'  | 'DISCRETE' | 'RES CHIP 604K 1/16W +-1%(0402)'                   | 'CHIP0402'     | ''          | ''            | '20121128'
 '604K'       | '1%'      | '1/16W'  | '0402LF'  | 'EMPTY'  | 'CS46042FB11'(!)        = 'End of Design' | 'Comp-Approve'     | 'CS46042FB11'           |'R0402'| '(R0402-0201)'                 | '604K'    | '1%'    | '1/16W'  | 'IO'       | 'RES CHIP 604K 1/16W +-1%(0402)'                   | 'CHIP0402'     | ''          | ''            | '20121128'
 '10.5K'      | '1%'      | '1/16W'  | '0402LF'  | 'CHIP'   | 'CS31052FB02'(!)        = 'End of Design' | 'Comp-Approve'     | 'CS31052FB02'           |'R0402'| '(R0402-0201)'                 | '10.5K'   | '1%'    | '1/16W'  | 'DISCRETE' | 'RES CHIP 10.5K 1/16W +-1%( 0402)'                 | 'CHIP0402'     | ''          | ''            | '20121204'
 '10.5K'      | '1%'      | '1/16W'  | '0402LF'  | 'EMPTY'  | 'CS31052FB02'(!)        = 'End of Design' | 'Comp-Approve'     | 'CS31052FB02'           |'R0402'| '(R0402-0201)'                 | '10.5K'   | '1%'    | '1/16W'  | 'IO'       | 'RES CHIP 10.5K 1/16W +-1%( 0402)'                 | 'CHIP0402'     | ''          | ''            | '20121204'
 '34.8K'      | '1%'      | '1/16W'  | '0402LF'  | 'CHIP'   | 'CS33482FB22'(!)        = 'End of Design' | 'Comp-Approve'     | 'CS33482FB22'           |'R0402'| '(R0402-0201)'                 | '34.8K'   | '1%'    | '1/16W'  | 'DISCRETE' | 'RES CHIP 34.8K 1/16W +-1% (0402)EP'               | 'CHIP0402'     | ''          | ''            | '20121204'
 '34.8K'      | '1%'      | '1/16W'  | '0402LF'  | 'EMPTY'  | 'CS33482FB22'(!)        = 'End of Design' | 'Comp-Approve'     | 'CS33482FB22'           |'R0402'| '(R0402-0201)'                 | '34.8K'   | '1%'    | '1/16W'  | 'IO'       | 'RES CHIP 34.8K 1/16W +-1% (0402)EP'               | 'CHIP0402'     | ''          | ''            | '20121204'
 '2.2'        | '5%'      | '1/2W'   | '1210LF'  | 'CHIP'   | 'CS-2207J311'(!)        = ''              | ''                 | 'CS-2207J311'           |'R1210'| '(SMR1210AW)'                  | '2.2'     | '5%'    | '1/2W'   | 'DISCRETE' | 'RES CHIP 2.2 1/2W +-5%(1210)'                     | 'CHIP1210'     | ''          | ''            | '20121210'
 '2.2'        | '5%'      | '1/2W'   | '1210LF'  | 'EMPTY'  | 'CS-2207J311'(!)        = ''              | ''                 | 'CS-2207J311'           |'R1210'| '(SMR1210AW)'                  | '2.2'     | '5%'    | '1/2W'   | 'IO'       | 'RES CHIP 2.2 1/2W +-5%(1210)'                     | 'CHIP1210'     | ''          | ''            | '20121210'
 '62'         | '1%'      | '1/16W'  | '0402LF'  | 'CHIP'   | 'CS06202FB13'(!)        = 'End of Design' | 'Comp-Approve'     | 'CS06202FB13'           |'R0402'| '(R0402-0201)'                 | '62'      | '1%'    | '1/16W'  | 'DISCRETE' | 'RES CHIP 62 1/16W +-1%(0402)'                     | 'CHIP0402'     | ''          | ''            | '20121216'
 '62'         | '1%'      | '1/16W'  | '0402LF'  | 'EMPTY'  | 'CS06202FB13'(!)        = 'End of Design' | 'Comp-Approve'     | 'CS06202FB13'           |'R0402'| '(R0402-0201)'                 | '62'      | '1%'    | '1/16W'  | 'IO'       | 'RES CHIP 62 1/16W +-1%(0402)'                     | 'CHIP0402'     | ''          | ''            | '20121216'
 '62'         | '5%'      | '1/16W'  | '0402LF'  | 'CHIP'   | 'CS06202JB15'(!)        = ''              | ''                 | 'CS06202JB15'           |'R0402'| '(R0402-0201)'                 | '62'      | '5%'    | '1/16W'  | 'DISCRETE' | 'RES CHIP 62 1/16W +-5%(0402)'                     | 'CHIP0402'     | ''          | ''            | '20121216'
 '62'         | '5%'      | '1/16W'  | '0402LF'  | 'EMPTY'  | 'CS06202JB15'(!)        = ''              | ''                 | 'CS06202JB15'           |'R0402'| '(R0402-0201)'                 | '62'      | '5%'    | '1/16W'  | 'IO'       | 'RES CHIP 62 1/16W +-5%(0402)'                     | 'CHIP0402'     | ''          | ''            | '20121216'
 '33.2K'      | '1%'      | '1/16W'  | '0402LF'  | 'CHIP'   | 'CS33322FB13'(!)        = 'End of Design' | 'Comp-Approve'     | 'CS33322FB13'           |'R0402'| '(R0402-0201)'                 | '33.2K'   | '1%'    | '1/16W'  | 'DISCRETE' | 'RES CHIP 33.2K 1/16W +-1% (0402)'                 | 'CHIP0402'     | ''          | ''            | '20121216'
 '33.2K'      | '1%'      | '1/16W'  | '0402LF'  | 'EMPTY'  | 'CS33322FB13'(!)        = 'End of Design' | 'Comp-Approve'     | 'CS33322FB13'           |'R0402'| '(R0402-0201)'                 | '33.2K'   | '1%'    | '1/16W'  | 'IO'       | 'RES CHIP 33.2K 1/16W +-1% (0402)'                 | 'CHIP0402'     | ''          | ''            | '20121216'
 '51'         | '5%'      | '1/8W'   | '0805LF'  | 'CHIP'   | 'CS05104JA12'(!)        = ''              | ''                 | 'CS05104JA12'           |'R0805'| '(SMR0805AW)'                  | '51'      | '5%'    | '1/8W'   | 'DISCRETE' | 'RES CHIP 51 1/8W +-5% (0805)'                     | 'CHIP0805'     | ''          | ''            | '20121216'
 '51'         | '5%'      | '1/8W'   | '0805LF'  | 'EMPTY'  | 'CS05104JA12'(!)        = ''              | ''                 | 'CS05104JA12'           |'R0805'| '(SMR0805AW)'                  | '51'      | '5%'    | '1/8W'   | 'IO'       | 'RES CHIP 51 1/8W +-5% (0805)'                     | 'CHIP0805'     | ''          | ''            | '20121216'
 '0.2'        | '1%'      | '1/10W'  | '0603LF'  | 'CHIP'   | 'CS+0203F900'(!)        = ''              | ''                 | 'CS+0203F900'           |'R0603'| '(SMR0603AW)'                  | '0.2'     | '1%'    | '1/10W'  | 'DISCRETE' | 'RES CHIP 0.2 1/10W +-1%(0603)'                    | 'CHIP0603'     | ''          | ''            | '20121216'
 '0.2'        | '1%'      | '1/10W'  | '0603LF'  | 'EMPTY'  | 'CS+0203F900'(!)        = ''              | ''                 | 'CS+0203F900'           |'R0603'| '(SMR0603AW)'                  | '0.2'     | '1%'    | '1/10W'  | 'IO'       | 'RES CHIP 0.2 1/10W +-1%(0603)'                    | 'CHIP0603'     | ''          | ''            | '20121216'
 '510'        | '5%'      | '1/10W'  | '0603LF'  | 'CHIP'   | 'CS15103J933'(!)        = ''              | ''                 | 'CS15103J933'           |'R0603'| '(SMR0603AW)'                  | '510'     | '5%'    | '1/10W'  | 'DISCRETE' | 'RES CHIP 510 1/10W +-5%(0603)'                    | 'CHIP0603'     | ''          | ''            | '20121218'
 '510'        | '5%'      | '1/10W'  | '0603LF'  | 'EMPTY'  | 'CS15103J933'(!)        = ''              | ''                 | 'CS15103J933'           |'R0603'| '(SMR0603AW)'                  | '510'     | '5%'    | '1/10W'  | 'IO'       | 'RES CHIP 510 1/10W +-5%(0603)'                    | 'CHIP0603'     | ''          | ''            | '20121218'
 '0.01'       | '1%'      | '1W'     | '2010LF'  | 'CHIP'   | 'CS+0108FJ00'(!)        = ''              | ''                 | 'CS+0108FJ00'           |'R2010'| '(SMR2010AW)'                  | '0.01'    | '1%'    | '1W'     | 'DISCRETE' | 'RES CHIP 0.01 1W +-1%(2010)'                      | 'CHIP2010'     | ''          | ''            | '20121221'
 '0.01'       | '1%'      | '1W'     | '2010LF'  | 'EMPTY'  | 'CS+0108FJ00'(!)        = ''              | ''                 | 'CS+0108FJ00'           |'R2010'| '(SMR2010AW)'                  | '0.01'    | '1%'    | '1W'     | 'IO'       | 'RES CHIP 0.01 1W +-1%(2010)'                      | 'CHIP2010'     | ''          | ''            | '20121221'
 '0.015'      | '1%'      | '3/4W'   | '2010LF'  | 'CHIP'   | 'CS+015BFJ21'(!)        = ''              | ''                 | 'CS+015BFJ21'           |'R2010'| '(SMR2010AW)'                  | '0.015'   | '1%'    | '3/4W'   | 'DISCRETE' | 'RES CHIP 0.015 3/4W +-1%(2010)'                   | 'CHIP2010'     | ''          | ''            | '20121221'
 '0.015'      | '1%'      | '3/4W'   | '2010LF'  | 'EMPTY'  | 'CS+015BFJ21'(!)        = ''              | ''                 | 'CS+015BFJ21'           |'R2010'| '(SMR2010AW)'                  | '0.015'   | '1%'    | '3/4W'   | 'IO'       | 'RES CHIP 0.015 3/4W +-1%(2010)'                   | 'CHIP2010'     | ''          | ''            | '20121221'
 '64.9'       | '1%'      | '1/16W'  | '0402LF'  | 'CHIP'   | 'CS06492FB03'(!)        = ''              | ''                 | 'CS06492FB03'           |'R0402'| '(R0402-0201)'                 | '64.9'    | '1%'    | '1/16W'  | 'DISCRETE' | 'RES CHIP 64.9 1/16W +-1%(0402)'                   | 'CHIP0402'     | ''          | ''            | '20121222'
 '64.9'       | '1%'      | '1/16W'  | '0402LF'  | 'EMPTY'  | 'CS06492FB03'(!)        = ''              | ''                 | 'CS06492FB03'           |'R0402'| '(R0402-0201)'                 | '64.9'    | '1%'    | '1/16W'  | 'IO'       | 'RES CHIP 64.9 1/16W +-1%(0402)'                   | 'CHIP0402'     | ''          | ''            | '20121222'
 '665'        | '1%'      | '1/16W'  | '0402LF'  | 'CHIP'   | 'CS16652FB04'(!)        = 'End of Design' | 'Comp-Approve'     | 'CS16652FB04'           |'R0402'| '(R0402-0201)'                 | '665'     | '1%'    | '1/16W'  | 'DISCRETE' | 'RES CHIP 665 1/16W +-1%(0402) L-F'                | 'CHIP0402'     | ''          | ''            | '20121222'
 '665'        | '1%'      | '1/16W'  | '0402LF'  | 'EMPTY'  | 'CS16652FB04'(!)        = 'End of Design' | 'Comp-Approve'     | 'CS16652FB04'           |'R0402'| '(R0402-0201)'                 | '665'     | '1%'    | '1/16W'  | 'IO'       | 'RES CHIP 665 1/16W +-1%(0402) L-F'                | 'CHIP0402'     | ''          | ''            | '20121222'
 '30.1'       | '1%'      | '1/16W'  | '0402LF'  | 'CHIP'   | 'CS03012FB21'(!)        = 'End of Design' | 'Comp-Approve'     | 'CS03012FB21'           |'R0402'| '(R0402-0201)'                 | '30.1'    | '1%'    | '1/16W'  | 'DISCRETE' | 'RES CHIP 30.1 1/16W +-1%(0402)'                   | 'CHIP0402'     | ''          | ''            | '20121224'
 '30.1'       | '1%'      | '1/16W'  | '0402LF'  | 'EMPTY'  | 'CS03012FB21'(!)        = 'End of Design' | 'Comp-Approve'     | 'CS03012FB21'           |'R0402'| '(R0402-0201)'                 | '30.1'    | '1%'    | '1/16W'  | 'IO'       | 'RES CHIP 30.1 1/16W +-1%(0402)'                   | 'CHIP0402'     | ''          | ''            | '20121224'
 '0.002'      | '1%'      | '1W'     | '2512LF'  | 'CHIP'   | 'CS+0028F115'(!)        = ''              | ''                 | 'CS+0028F115'           |'R2512XC'| '(SMR2512AW)'                  | '0.002'   | '1%'    | '1W'     | 'DISCRETE' | 'RES CHIP 0.002 1W +-1%(2512)'                     | 'CHIP2512'     | ''          | ''            | '20121225'
 '0.002'      | '1%'      | '1W'     | '2512LF'  | 'EMPTY'  | 'CS+0028F115'(!)        = ''              | ''                 | 'CS+0028F115'           |'R2512XC'| '(SMR2512AW)'                  | '0.002'   | '1%'    | '1W'     | 'IO'       | 'RES CHIP 0.002 1W +-1%(2512)'                     | 'CHIP2512'     | ''          | ''            | '20121225'
 '4.99'       | '1%'      | '1/16W'  | '0402LF'  | 'CHIP'   | 'CS-4992FB25'(!)        = 'End of Design' | 'Comp-Approve'     | 'CS-4992FB25'           |'R0402'| '(R0402-0201)'                 | '4.99'    | '1%'    | '1/16W'  | 'DISCRETE' | 'RES CHIP 4.99 1/16W +-1% (0402)'                  | 'CHIP0402'     | ''          | ''            | '20121228'
 '4.99'       | '1%'      | '1/16W'  | '0402LF'  | 'EMPTY'  | 'CS-4992FB25'(!)        = 'End of Design' | 'Comp-Approve'     | 'CS-4992FB25'           |'R0402'| '(R0402-0201)'                 | '4.99'    | '1%'    | '1/16W'  | 'IO'       | 'RES CHIP 4.99 1/16W +-1% (0402)'                  | 'CHIP0402'     | ''          | ''            | '20121228'
 '64.9'       | '1%'      | '1/16W'  | '0402LF'  | 'CHIP'   | 'CS06492FB11'(!)        = 'End of Design' | 'Comp-Approve'     | 'CS06492FB11'           |'R0402'| '(R0402-0201)'                 | '64.9'    | '1%'    | '1/16W'  | 'DISCRETE' | 'RES CHIP 64.9 1/16W +-1% (0402)'                  | 'CHIP0402'     | ''          | ''            | '20130105'
 '64.9'       | '1%'      | '1/16W'  | '0402LF'  | 'EMPTY'  | 'CS06492FB11'(!)        = 'End of Design' | 'Comp-Approve'     | 'CS06492FB11'           |'R0402'| '(R0402-0201)'                 | '64.9'    | '1%'    | '1/16W'  | 'IO'       | 'RES CHIP 64.9 1/16W +-1% (0402)'                  | 'CHIP0402'     | ''          | ''            | '20130105'
 '160K'       | '1%'      | '1/16W'  | '0402LF'  | 'CHIP'   | 'CS41602FB00'(!)        = 'End of Design' | 'Comp-Approve'     | 'CS41602FB00'           |'R0402'| '(R0402-0201)'                 | '160K'    | '1%'    | '1/16W'  | 'DISCRETE' | 'RES CHIP 160K (1/16W,+-1%,0402)'                  | 'CHIP0402'     | ''          | ''            | '20130108'
 '160K'       | '1%'      | '1/16W'  | '0402LF'  | 'EMPTY'  | 'CS41602FB00'(!)        = 'End of Design' | 'Comp-Approve'     | 'CS41602FB00'           |'R0402'| '(R0402-0201)'                 | '160K'    | '1%'    | '1/16W'  | 'IO'       | 'RES CHIP 160K (1/16W,+-1%,0402)'                  | 'CHIP0402'     | ''          | ''            | '20130108'
 '35.7'       | '1%'      | '1/16W'  | '0402LF'  | 'CHIP'   | 'CS03572FB01'(!)        = 'End of Design' | 'Comp-Approve'     | 'CS03572FB01'           |'R0402'| '(R0402-0201)'                 | '35.7'    | '1%'    | '1/16W'  | 'DISCRETE' | 'RES CHIP 35.7 1/16W +-1%(0402)'                   | 'CHIP0402'     | ''          | ''            | '20130108'
 '35.7'       | '1%'      | '1/16W'  | '0402LF'  | 'EMPTY'  | 'CS03572FB01'(!)        = 'End of Design' | 'Comp-Approve'     | 'CS03572FB01'           |'R0402'| '(R0402-0201)'                 | '35.7'    | '1%'    | '1/16W'  | 'IO'       | 'RES CHIP 35.7 1/16W +-1%(0402)'                   | 'CHIP0402'     | ''          | ''            | '20130108'
 '140K'       | '1%'      | '1/16W'  | '0402LF'  | 'CHIP'   | 'CS41402FB14'(!)        = 'End of Design' | 'Comp-Approve'     | 'CS41402FB14'           |'R0402'| '(R0402-0201)'                 | '140K'    | '1%'    | '1/16W'  | 'DISCRETE' | 'RES CHIP 140K 1/16W +-1%(0402)'                   | 'CHIP0402'     | ''          | ''            | '20130108'
 '140K'       | '1%'      | '1/16W'  | '0402LF'  | 'EMPTY'  | 'CS41402FB14'(!)        = 'End of Design' | 'Comp-Approve'     | 'CS41402FB14'           |'R0402'| '(R0402-0201)'                 | '140K'    | '1%'    | '1/16W'  | 'IO'       | 'RES CHIP 140K 1/16W +-1%(0402)'                   | 'CHIP0402'     | ''          | ''            | '20130108'
 '69.8K'      | '1%'      | '1/10W'  | '0603LF'  | 'CHIP'   | 'CS36983F917'(!)        = 'End of Design' | 'Comp-Approve'     | 'CS36983F917'           |'R0603'| '(SMR0603AW)'                  | '69.8K'   | '1%'    | '1/10W'  | 'DISCRETE' | 'RESISTOR CHIP 69.8K 1/10W +-1% (0603)'            | 'CHIP0603'     | ''          | ''            | '20130114'
 '69.8K'      | '1%'      | '1/10W'  | '0603LF'  | 'EMPTY'  | 'CS36983F917'(!)        = 'End of Design' | 'Comp-Approve'     | 'CS36983F917'           |'R0603'| '(SMR0603AW)'                  | '69.8K'   | '1%'    | '1/10W'  | 'IO'       | 'RESISTOR CHIP 69.8K 1/10W +-1% (0603)'            | 'CHIP0603'     | ''          | ''            | '20130114'
 '6.65K'      | '1%'      | '1/16W'  | '0402LF'  | 'CHIP'   | 'TMP_QCS26652FB06'(!)   = 'End of Design' | 'Comp-Approve'     | 'CS26652FB06'           |'R0402'| '(R0402-0201)'                 | '6.65K'   | '1%'    | '1/16W'  | 'DISCRETE' | '6.65Kohm 0402'                                    | 'CHIP0402'     | ''          | ''            | ''        
 '6.65K'      | '1%'      | '1/16W'  | '0402LF'  | 'EMPTY'  | 'TMP_QCS26652FB06'(!)   = 'End of Design' | 'Comp-Approve'     | 'CS26652FB06'           |'R0402'| '(R0402-0201)'                 | '6.65K'   | '1%'    | '1/16W'  | 'DISCRETE' | '6.65Kohm 0402'                                    | 'CHIP0402'     | ''          | ''            | ''        
 '5.23K'      | '1%'      | '1/16W'  | '0402LF'  | 'CHIP'   | 'CS25232FB18'(!)        = 'End of Design' | 'Comp-Approve'     | 'CS25232FB18'           |'R0402'| '(R0402-0201)'                 | '5.23K'   | '1%'    | '1/16W'  | 'DISCRETE' | 'RES CHIP 5.23K 1/16W +-1%(0402)'                  | 'CHIP0402'     | ''          | ''            | '20130123'
 '5.23K'      | '1%'      | '1/16W'  | '0402LF'  | 'EMPTY'  | 'CS25232FB18'(!)        = 'End of Design' | 'Comp-Approve'     | 'CS25232FB18'           |'R0402'| '(R0402-0201)'                 | '5.23K'   | '1%'    | '1/16W'  | 'IO'       | 'RES CHIP 5.23K 1/16W +-1%(0402)'                  | 'CHIP0402'     | ''          | ''            | '20130123'
 '120K'       | '1%'      | '1/16W'  | '0402LF'  | 'CHIP'   | 'CS41202FB17'(!)        = 'End of Design' | 'Comp-Approve'     | 'CS41202FB17'           |'R0402'| '(R0402-0201)'                 | '120K'    | '1%'    | '1/16W'  | 'DISCRETE' | 'RES CHIP 120K 1/16W +-1%( 0402)'                  | 'CHIP0402'     | ''          | ''            | '20130218'
 '120K'       | '1%'      | '1/16W'  | '0402LF'  | 'EMPTY'  | 'CS41202FB17'(!)        = 'End of Design' | 'Comp-Approve'     | 'CS41202FB17'           |'R0402'| '(R0402-0201)'                 | '120K'    | '1%'    | '1/16W'  | 'IO'       | 'RES CHIP 120K 1/16W +-1%( 0402)'                  | 'CHIP0402'     | ''          | ''            | '20130218'
 '2.2K'       | '1%'      | '1/10W'  | '0603LF'  | 'CHIP'   | 'CS22203F912'(!)        = 'End of Design' | 'Comp-Approve'     | 'CS22203F912'           |'R0603'| '(SMR0603AW)'                  | '2.2K'    | '1%'    | '1/10W'  | 'DISCRETE' | 'RES CHIP 2.2K 1/10W.+-1%(0603)'                   | 'CHIP0603'     | ''          | ''            | '20130228'
 '2.2K'       | '1%'      | '1/10W'  | '0603LF'  | 'EMPTY'  | 'CS22203F912'(!)        = 'End of Design' | 'Comp-Approve'     | 'CS22203F912'           |'R0603'| '(SMR0603AW)'                  | '2.2K'    | '1%'    | '1/10W'  | 'IO'       | 'RES CHIP 2.2K 1/10W.+-1%(0603)'                   | 'CHIP0603'     | ''          | ''            | '20130228'
 '2.26K'      | '1%'      | '1/10W'  | '0603LF'  | 'CHIP'   | 'CS22263F928'(!)        = 'End of Design' | 'Comp-Approve'     | 'CS22263F928'           |'R0603'| '(SMR0603AW)'                  | '2.26K'   | '1%'    | '1/10W'  | 'DISCRETE' | 'RES CHIP 2.26K 1/10W +-1%(0603)'                  | 'CHIP0603'     | ''          | ''            | '20130228'
 '2.26K'      | '1%'      | '1/10W'  | '0603LF'  | 'EMPTY'  | 'CS22263F928'(!)        = 'End of Design' | 'Comp-Approve'     | 'CS22263F928'           |'R0603'| '(SMR0603AW)'                  | '2.26K'   | '1%'    | '1/10W'  | 'IO'       | 'RES CHIP 2.26K 1/10W +-1%(0603)'                  | 'CHIP0603'     | ''          | ''            | '20130228'
 '1.43K'      | '1%'      | '1/16W'  | '0402LF'  | 'CHIP'   | 'CS21432FB00'(!)        = 'End of Design' | 'Comp-Approve'     | 'CS21432FB00'           |'R0402'| '(R0402-0201)'                 | '1.43K'   | '1%'    | '1/16W'  | 'DISCRETE' | 'RES CHIP 1.43K 1/16W +-1%(0402)'                  | 'CHIP0402'     | ''          | ''            | '20130306'
 '1.43K'      | '1%'      | '1/16W'  | '0402LF'  | 'EMPTY'  | 'CS21432FB00'(!)        = 'End of Design' | 'Comp-Approve'     | 'CS21432FB00'           |'R0402'| '(R0402-0201)'                 | '1.43K'   | '1%'    | '1/16W'  | 'IO'       | 'RES CHIP 1.43K 1/16W +-1%(0402)'                  | 'CHIP0402'     | ''          | ''            | '20130306'
 '60.4'       | '1%'      | '1/16W'  | '0402LF'  | 'CHIP'   | 'CS06042FB14'(!)        = 'End of Design' | 'Comp-Approve'     | 'CS06042FB14'           |'R0402'| '(R0402-0201)'                 | '60.4'    | '1%'    | '1/16W'  | 'DISCRETE' | 'RES CHIP 1.43K 1/16W +-1%(0402)'                  | 'CHIP0402'     | ''          | ''            | '20130319'
 '60.4'       | '1%'      | '1/16W'  | '0402LF'  | 'EMPTY'  | 'CS06042FB14'(!)        = 'End of Design' | 'Comp-Approve'     | 'CS06042FB14'           |'R0402'| '(R0402-0201)'                 | '60.4'    | '1%'    | '1/16W'  | 'IO'       | 'RES CHIP 1.43K 1/16W +-1%(0402)'                  | 'CHIP0402'     | ''          | ''            | '20130319'
 '0.0002'     | '1%'      | '5W'     | '5931LF'  | 'CHIP'   | 'TMP_TU1J_LJ_0322_1'(!) = ''              | ''                 | 'TMP_TU1J_LJ_0322_1'    |'R5931'| '(SMR5931AW)'                  | '0.0002'  | '1%'    | '5W'     | 'DISCRETE' | 'RES CHIP 0.0002 5W +-1%(5931)'                    | 'CHIP5931'     | ''          | ''            | '20130322'
 '0.0002'     | '1%'      | '5W'     | '5931LF'  | 'EMPTY'  | 'TMP_TU1J_LJ_0322_1'(!) = ''              | ''                 | 'TMP_TU1J_LJ_0322_1'    |'R5931'| '(SMR5931AW)'                  | '0.0002'  | '1%'    | '5W'     | 'IO'       | 'RES CHIP 0.0002 5W +-1%(5931)'                    | 'CHIP5931'     | ''          | ''            | '20130322'
 '221'        | '1%'      | '1/16W'  | '0402LF'  | 'CHIP'   | 'CS12212FB19'(!)        = 'End of Design' | 'Comp-Approve'     | 'CS12212FB19'           |'R0402'| '(R0402-0201)'                 | '221'     | '1%'    | '1/16W'  | 'DISCRETE' | 'RES CHIP 221 1/16W +-1%(0402)'                    | 'CHIP0402'     | ''          | ''            | '20130323'
 '221'        | '1%'      | '1/16W'  | '0402LF'  | 'EMPTY'  | 'CS12212FB19'(!)        = 'End of Design' | 'Comp-Approve'     | 'CS12212FB19'           |'R0402'| '(R0402-0201)'                 | '221'     | '1%'    | '1/16W'  | 'IO'       | 'RES CHIP 221 1/16W +-1%(0402)'                    | 'CHIP0402'     | ''          | ''            | '20130323'
 '243'        | '1%'      | '1/16W'  | '0402LF'  | 'CHIP'   | 'CS12432FB15'(!)        = 'End of Design' | 'Comp-Approve'     | 'CS12432FB15'           |'R0402'| '(R0402-0201)'                 | '243'     | '1%'    | '1/16W'  | 'DISCRETE' | 'RES CHIP 243 1/16W +-1% (0402)'                   | 'CHIP0402'     | ''          | ''            | '20130327'
 '243'        | '1%'      | '1/16W'  | '0402LF'  | 'EMPTY'  | 'CS12432FB15'(!)        = 'End of Design' | 'Comp-Approve'     | 'CS12432FB15'           |'R0402'| '(R0402-0201)'                 | '243'     | '1%'    | '1/16W'  | 'IO'       | 'RES CHIP 243 1/16W +-1% (0402)'                   | 'CHIP0402'     | ''          | ''            | '20130327'
 '10'         | '5%'      | '1/8W'   | '0805LF'  | 'CHIP'   | 'CS01004JA42'(!)        = ''              | ''                 | 'CS01004JA42'           |'R0805'| '(SMR0805AW)'                  | '10'      | '5%'    | '1/8W'   | 'DISCRETE' | 'RES CHIP 10 1/8W +-5%(0805)'                      | 'CHIP0805'     | ''          | ''            | '20130401'
 '10'         | '5%'      | '1/8W'   | '0805LF'  | 'EMPTY'  | 'CS01004JA42'(!)        = ''              | ''                 | 'CS01004JA42'           |'R0805'| '(SMR0805AW)'                  | '10'      | '5%'    | '1/8W'   | 'IO'       | 'RES CHIP 10 1/8W +-5%(0805)'                      | 'CHIP0805'     | ''          | ''            | '20130401'
 '1.5K'       | '5%'      | '1/8W'   | '0805LF'  | 'CHIP'   | 'CS21504JA10'(!)        = 'End of Design' | 'End of Life'      | 'CS21504JA10'           |'R0805_EOL'| '(SMR0805AW)'                  | '1.5K'    | '5%'    | '1/8W'   | 'DISCRETE' | 'RES CHIP 1.5K 1/8W +-5%(0805)'                    | 'CHIP0805'     | ''          | ''            | '20130401'
 '1.5K'       | '5%'      | '1/8W'   | '0805LF'  | 'EMPTY'  | 'CS21504JA10'(!)        = 'End of Design' | 'End of Life'      | 'CS21504JA10'           |'R0805_EOL'| '(SMR0805AW)'                  | '1.5K'    | '5%'    | '1/8W'   | 'IO'       | 'RES CHIP 1.5K 1/8W +-5%(0805)'                    | 'CHIP0805'     | ''          | ''            | '20130401'
 '1.5M'       | '1%'      | '1/16W'  | '0402LF'  | 'CHIP'   | 'CS51502FB00'(!)        = 'End of Design' | 'Comp-Approve'     | 'CS51502FB00'           |'R0402'| '(R0402-0201)'                 | '1.5M'    | '1%'    | '1/16W'  | 'DISCRETE' | 'RES CHIP 1.5M 1/16W +-1%(0402)'                   | 'CHIP0402'     | ''          | ''            | '20130411'
 '1.5M'       | '1%'      | '1/16W'  | '0402LF'  | 'EMPTY'  | 'CS51502FB00'(!)        = 'End of Design' | 'Comp-Approve'     | 'CS51502FB00'           |'R0402'| '(R0402-0201)'                 | '1.5M'    | '1%'    | '1/16W'  | 'IO'       | 'RES CHIP 1.5M 1/16W +-1%(0402)'                   | 'CHIP0402'     | ''          | ''            | '20130411'
 '3.0M'       | '1%'      | '1/16W'  | '0402LF'  | 'CHIP'   | 'CS53002FB00'(!)        = 'End of Design' | 'Comp-Release Qty' | 'CS53002FB00'           |'R0402'| '(R0402-0201)'                 | '3.0M'    | '1%'    | '1/16W'  | 'DISCRETE' | 'RES CHIP 3.0M 1/16W +-1%(0402)'                   | 'CHIP0402'     | ''          | ''            | '20130411'
 '3.0M'       | '1%'      | '1/16W'  | '0402LF'  | 'EMPTY'  | 'CS53002FB00'(!)        = 'End of Design' | 'Comp-Release Qty' | 'CS53002FB00'           |'R0402'| '(R0402-0201)'                 | '3.0M'    | '1%'    | '1/16W'  | 'IO'       | 'RES CHIP 3.0M 1/16W +-1%(0402)'                   | 'CHIP0402'     | ''          | ''            | '20130411'
 '2.94K'      | '1%'      | '1/16W'  | '0402LF'  | 'CHIP'   | 'CS22942FB01'(!)        = 'End of Design' | 'Comp-Approve'     | 'CS22942FB01'           |'R0402'| '(R0402-0201)'                 | '2.94K'   | '1%'    | '1/16W'  | 'DISCRETE' | 'RES CHIP 2.94K 1/16W +-1%(0402)'                  | 'CHIP0402'     | ''          | ''            | '20130411'
 '2.94K'      | '1%'      | '1/16W'  | '0402LF'  | 'EMPTY'  | 'CS22942FB01'(!)        = 'End of Design' | 'Comp-Approve'     | 'CS22942FB01'           |'R0402'| '(R0402-0201)'                 | '2.94K'   | '1%'    | '1/16W'  | 'IO'       | 'RES CHIP 2.94K 1/16W +-1%(0402)'                  | 'CHIP0402'     | ''          | ''            | '20130411'
 '44.2'       | '1%'      | '1/16W'  | '0402LF'  | 'CHIP'   | 'CS04422FB14'(!)        = 'End of Design' | 'Comp-Approve'     | 'CS04422FB14'           |'R0402'| '(R0402-0201)'                 | '44.2'    | '1%'    | '1/16W'  | 'DISCRETE' | 'RES CHIP 44.2 1/16W +-1%(0402)'                   | 'CHIP0402'     | ''          | ''            | '20130425'
 '44.2'       | '1%'      | '1/16W'  | '0402LF'  | 'EMPTY'  | 'CS04422FB14'(!)        = 'End of Design' | 'Comp-Approve'     | 'CS04422FB14'           |'R0402'| '(R0402-0201)'                 | '44.2'    | '1%'    | '1/16W'  | 'IO'       | 'RES CHIP 44.2 1/16W +-1%(0402)'                   | 'CHIP0402'     | ''          | ''            | '20130425'
 '3'          | '5%'      | '3/4W'   | '2010LF'  | 'CHIP'   | 'CS0030BJJ00'(!)        = ''              | ''                 | 'CS0030BJJ00'           |'R2010'| '(SMR2010AW)'                  | '3'       | '5%'    | '3/4W'   | 'DISCRETE' | 'RES CHIP 3 3/4W.+-5%(2010)'                       | 'CHIP2010'     | ''          | ''            | '20130429'
 '3'          | '5%'      | '3/4W'   | '2010LF'  | 'EMPTY'  | 'CS0030BJJ00'(!)        = ''              | ''                 | 'CS0030BJJ00'           |'R2010'| '(SMR2010AW)'                  | '3'       | '5%'    | '3/4W'   | 'IO'       | 'RES CHIP 3 3/4W.+-5%(2010)'                       | 'CHIP2010'     | ''          | ''            | '20130429'
 '1'          | '5%'      | '3/4W'   | '2010LF'  | 'CHIP'   | 'CS-100BJJ04'(!)        = ''              | ''                 | 'CS-100BJJ04'           |'R2010'| '(SMR2010AW)'                  | '1'       | '5%'    | '3/4W'   | 'DISCRETE' | 'RES CHIP 1 3/4W +5%(2010)L-F'                     | 'CHIP2010'     | ''          | ''            | '20130429'
 '1'          | '5%'      | '3/4W'   | '2010LF'  | 'EMPTY'  | 'CS-100BJJ04'(!)        = ''              | ''                 | 'CS-100BJJ04'           |'R2010'| '(SMR2010AW)'                  | '1'       | '5%'    | '3/4W'   | 'IO'       | 'RES CHIP 1 3/4W +5%(2010)L-F'                     | 'CHIP2010'     | ''          | ''            | '20130429'
 '432'        | '1%'      | '1/16W'  | '0402LF'  | 'CHIP'   | 'CS14322FB00'(!)        = 'End of Design' | 'Comp-Approve'     | 'CS14322FB00'           |'R0402'| '(R0402-0201)'                 | '432'     | '1%'    | '1/16W'  | 'DISCRETE' | 'RES CHIP 432 1/16W +-1%(0402)'                    | 'CHIP0402'     | ''          | ''            | '20130503'
 '432'        | '1%'      | '1/16W'  | '0402LF'  | 'EMPTY'  | 'CS14322FB00'(!)        = 'End of Design' | 'Comp-Approve'     | 'CS14322FB00'           |'R0402'| '(R0402-0201)'                 | '432'     | '1%'    | '1/16W'  | 'IO'       | 'RES CHIP 432 1/16W +-1%(0402)'                    | 'CHIP0402'     | ''          | ''            | '20130503'
 '348'        | '1%'      | '1/16W'  | '0402LF'  | 'CHIP'   | 'CS13482FB00'(!)        = 'End of Design' | 'Comp-Approve'     | 'CS13482FB00'           |'R0402'| '(R0402-0201)'                 | '348'     | '1%'    | '1/16W'  | 'DISCRETE' | 'RES CHIP 348 1/16W +-1%(0402)'                    | 'CHIP0402'     | ''          | ''            | '20130509'
 '348'        | '1%'      | '1/16W'  | '0402LF'  | 'EMPTY'  | 'CS13482FB00'(!)        = 'End of Design' | 'Comp-Approve'     | 'CS13482FB00'           |'R0402'| '(R0402-0201)'                 | '348'     | '1%'    | '1/16W'  | 'IO'       | 'RES CHIP 348 1/16W +-1%(0402)'                    | 'CHIP0402'     | ''          | ''            | '20130509'
 '2.7K'       | '5%'      | '1/16W'  | '0402LF'  | 'CHIP'   | 'CS22702JB16'(!)        = 'End of Design' | 'Comp-Approve'     | 'CS22702JB16'           |'R0402'| '(R0402-0201)'                 | '2.7K'    | '5%'    | '1/16W'  | 'DISCRETE' | 'RES CHIP 2.7K 1/16W +-5%(0402)'                   | 'CHIP0402'     | ''          | ''            | '20130509'
 '2.7K'       | '5%'      | '1/16W'  | '0402LF'  | 'EMPTY'  | 'CS22702JB16'(!)        = 'End of Design' | 'Comp-Approve'     | 'CS22702JB16'           |'R0402'| '(R0402-0201)'                 | '2.7K'    | '5%'    | '1/16W'  | 'IO'       | 'RES CHIP 2.7K 1/16W +-5%(0402)'                   | 'CHIP0402'     | ''          | ''            | '20130509'
 '3.01'       | '1%'      | '1/4W'   | '1206LF'  | 'CHIP'   | 'CS-3016F200'(!)        = ''              | ''                 | 'CS-3016F200'           |'R1206'| '(SMR1206AW)'                  | '3.01'    | '1%'    | '1/4W'   | 'DISCRETE' | 'RES CHIP 3.01 OHM 1/4W +-1%(1206)'                | 'CHIP1206'     | ''          | ''            | '20130521'
 '3.01'       | '1%'      | '1/4W'   | '1206LF'  | 'EMPTY'  | 'CS-3016F200'(!)        = ''              | ''                 | 'CS-3016F200'           |'R1206'| '(SMR1206AW)'                  | '3.01'    | '1%'    | '1/4W'   | 'IO'       | 'RES CHIP 3.01 OHM 1/4W +-1%(1206)'                | 'CHIP1206'     | ''          | ''            | '20130521'
 '196'        | '1%'      | '1/10W'  | '0603LF'  | 'CHIP'   | 'CS11963F911'(!)        = 'End of Design' | 'Comp-Approve'     | 'CS11963F911'           |'R0603'| '(SMR0603AW)'                  | '196'     | '1%'    | '1/10W'  | 'DISCRETE' | 'RES CHIP 196 1/10W +-1% (0603)'                   | 'CHIP0603'     | ''          | ''            | '20130529'
 '196'        | '1%'      | '1/10W'  | '0603LF'  | 'EMPTY'  | 'CS11963F911'(!)        = 'End of Design' | 'Comp-Approve'     | 'CS11963F911'           |'R0603'| '(SMR0603AW)'                  | '196'     | '1%'    | '1/10W'  | 'IO'       | 'RES CHIP 196 1/10W +-1% (0603)'                   | 'CHIP0603'     | ''          | ''            | '20130529'
 '0.001'      | '1%'      | '4W'     | '2725LF'  | 'CHIP'   | 'CS+001FFT00'(!)        = 'End of Design' | 'P/N Release'      | 'CS+001FFT00'           |'R2725'| '(SMR2725AW)'                  | '0.001'   | '1%'    | '4W'     | 'DISCRETE' | 'RES CHIP 0.001OHM 4W +-1% (2725)'                 | 'CHIP2725'     | ''          | ''            | '20130606'
 '0.001'      | '1%'      | '4W'     | '2725LF'  | 'EMPTY'  | 'CS+001FFT00'(!)        = 'End of Design' | 'P/N Release'      | 'CS+001FFT00'           |'R2725'| '(SMR2725AW)'                  | '0.001'   | '1%'    | '4W'     | 'IO'       | 'RES CHIP 0.001OHM 4W +-1% (2725)'                 | 'CHIP2725'     | ''          | ''            | '20130606'
 '240K'       | '1%'      | '1/16W'  | '0402LF'  | 'CHIP'   | 'CS42402FB17'(!)        = 'End of Design' | 'Comp-Approve'     | 'CS42402FB17'           |'R0402'| '(R0402-0201)'                 | '240K'    | '1%'    | '1/16W'  | 'DISCRETE' | 'RES CHIP 240K 1/16W +-1%(0402)'                   | 'CHIP0402'     | ''          | ''            | '20130611'
 '240K'       | '1%'      | '1/16W'  | '0402LF'  | 'EMPTY'  | 'CS42402FB17'(!)        = 'End of Design' | 'Comp-Approve'     | 'CS42402FB17'           |'R0402'| '(R0402-0201)'                 | '240K'    | '1%'    | '1/16W'  | 'IO'       | 'RES CHIP 240K 1/16W +-1%(0402)'                   | 'CHIP0402'     | ''          | ''            | '20130611'
 '1'          | '1%'      | '1/4W'   | '1206LF'  | 'CHIP'   | 'CS-1006F217'(!)        = ''              | ''                 | 'CS-1006F217'           |'R1206'| '(SMR1206AW)'                  | '1'       | '1%'    | '1/4W'   | 'DISCRETE' | 'RES CHIP 1 1/4W +-1%(1206) L-F'                   | 'CHIP1206'     | ''          | ''            | '20130611'
 '1'          | '1%'      | '1/4W'   | '1206LF'  | 'EMPTY'  | 'CS-1006F217'(!)        = ''              | ''                 | 'CS-1006F217'           |'R1206'| '(SMR1206AW)'                  | '1'       | '1%'    | '1/4W'   | 'IO'       | 'RES CHIP 1 1/4W +-1%(1206) L-F'                   | 'CHIP1206'     | ''          | ''            | '20130611'
 '0.0002'     | '1%'      | '4W'     | '2725LF'  | 'CHIP'   | 'CS0000FFT01'(!)        = ''              | ''                 | 'CS0000FFT01'           |'R2725'| '(SMR2725AW)'                  | '0.0002'  | '1%'    | '4W'     | 'DISCRETE' | 'RES CHIP 0.0002 4W +-1%(2725)H1.131'              | 'CHIP2725'     | ''          | ''            | '20130627'
 '0.0002'     | '1%'      | '4W'     | '2725LF'  | 'EMPTY'  | 'CS0000FFT01'(!)        = ''              | ''                 | 'CS0000FFT01'           |'R2725'| '(SMR2725AW)'                  | '0.0002'  | '1%'    | '4W'     | 'IO'       | 'RES CHIP 0.0002 4W +-1%(2725)H1.131'              | 'CHIP2725'     | ''          | ''            | '20130627'
 '91'         | '1%'      | '1/16W'  | '0402LF'  | 'CHIP'   | 'CS09102FB00'(!)        = 'End of Design' | 'Comp-Approve'     | 'CS09102FB00'           |'R0402'| '(R0402-0201)'                 | '91'      | '1%'    | '1/16W'  | 'DISCRETE' | 'RES CHIP 91 1/16W +-1%(0402)'                     | 'CHIP0402'     | ''          | ''            | '20130702'
 '91'         | '1%'      | '1/16W'  | '0402LF'  | 'EMPTY'  | 'CS09102FB00'(!)        = 'End of Design' | 'Comp-Approve'     | 'CS09102FB00'           |'R0402'| '(R0402-0201)'                 | '91'      | '1%'    | '1/16W'  | 'IO'       | 'RES CHIP 91 1/16W +-1%(0402)'                     | 'CHIP0402'     | ''          | ''            | '20130702'
 '499'        | '1%'      | '1/8W'   | '0805LF'  | 'CHIP'   | 'CS14994FA00'(!)        = ''              | ''                 | 'CS14994FA00'           |'R0805'| '(SMR0805AW)'                  | '499'     | '1%'    | '1/8W'   | 'DISCRETE' | 'RES CHIP 499 1/8W +-1%(0805)'                     | 'CHIP0805'     | ''          | ''            | '20130705'
 '499'        | '1%'      | '1/8W'   | '0805LF'  | 'EMPTY'  | 'CS14994FA00'(!)        = ''              | ''                 | 'CS14994FA00'           |'R0805'| '(SMR0805AW)'                  | '499'     | '1%'    | '1/8W'   | 'IO'       | 'RES CHIP 499 1/8W +-1%(0805)'                     | 'CHIP0805'     | ''          | ''            | '20130705'
 '510'        | '1%'      | '1/8W'   | '0805LF'  | 'CHIP'   | 'CS15104FA00'(!)        = 'End of Design' | 'Comp-Approve'     | 'CS15104FA00'           |'R0805'| '(SMR0805AW)'                  | '510'     | '1%'    | '1/8W'   | 'DISCRETE' | 'RES CHIP 510 1/8W +-1%(0805)'                     | 'CHIP0805'     | ''          | ''            | '20130705'
 '510'        | '1%'      | '1/8W'   | '0805LF'  | 'EMPTY'  | 'CS15104FA00'(!)        = 'End of Design' | 'Comp-Approve'     | 'CS15104FA00'           |'R0805'| '(SMR0805AW)'                  | '510'     | '1%'    | '1/8W'   | 'IO'       | 'RES CHIP 510 1/8W +-1%(0805)'                     | 'CHIP0805'     | ''          | ''            | '20130705'
 '137K'       | '1%'      | '1/16W'  | '0402LF'  | 'CHIP'   | 'CS41372FB12'(!)        = 'End of Design' | 'Comp-Approve'     | 'CS41372FB12'           |'R0402'| '(R0402-0201)'                 | '137K'    | '1%'    | '1/16W'  | 'DISCRETE' | 'RES CHIP 137K 1/16W +-1% (0402)'                  | 'CHIP0402'     | ''          | ''            | '20130729'
 '137K'       | '1%'      | '1/16W'  | '0402LF'  | 'EMPTY'  | 'CS41372FB12'(!)        = 'End of Design' | 'Comp-Approve'     | 'CS41372FB12'           |'R0402'| '(R0402-0201)'                 | '137K'    | '1%'    | '1/16W'  | 'IO'       | 'RES CHIP 137K 1/16W +-1% (0402)'                  | 'CHIP0402'     | ''          | ''            | '20130729'
 '162K'       | '1%'      | '1/16W'  | '0402LF'  | 'CHIP'   | 'CS41622FB11'(!)        = 'End of Design' | 'Comp-Approve'     | 'CS41622FB11'           |'R0402'| '(R0402-0201)'                 | '162K'    | '1%'    | '1/16W'  | 'DISCRETE' | 'RES CHIP 162K 1/16W +-1% (0402)'                  | 'CHIP0402'     | ''          | ''            | '20130729'
 '162K'       | '1%'      | '1/16W'  | '0402LF'  | 'EMPTY'  | 'CS41622FB11'(!)        = 'End of Design' | 'Comp-Approve'     | 'CS41622FB11'           |'R0402'| '(R0402-0201)'                 | '162K'    | '1%'    | '1/16W'  | 'IO'       | 'RES CHIP 162K 1/16W +-1% (0402)'                  | 'CHIP0402'     | ''          | ''            | '20130729'
 '14.3K'      | '1%'      | '1/16W'  | '0402LF'  | 'CHIP'   | 'CS31432FB08'(!)        = 'End of Design' | 'Comp-Approve'     | 'CS31432FB08'           |'R0402'| '(R0402-0201)'                 | '14.3K'   | '1%'    | '1/16W'  | 'DISCRETE' | 'RES CHIP 14.3K 1/16W +-1%(0402)'                  | 'CHIP0402'     | ''          | ''            | '20130729'
 '14.3K'      | '1%'      | '1/16W'  | '0402LF'  | 'EMPTY'  | 'CS31432FB08'(!)        = 'End of Design' | 'Comp-Approve'     | 'CS31432FB08'           |'R0402'| '(R0402-0201)'                 | '14.3K'   | '1%'    | '1/16W'  | 'IO'       | 'RES CHIP 14.3K 1/16W +-1%(0402)'                  | 'CHIP0402'     | ''          | ''            | '20130729'
 '5.11'       | '1%'      | '1/10W'  | '0603LF'  | 'CHIP'   | 'CS-5113F900'(!)        = 'End of Design' | 'Comp-Approve'     | 'CS-5113F900'           |'R0603'| '(SMR0603AW)'                  | '5.11'    | '1%'    | '1/10W'  | 'DISCRETE' | 'RES CHIP 5.11 1/10W +-1%(0603)'                   | 'CHIP0603'     | ''          | ''            | '20130731'
 '5.11'       | '1%'      | '1/10W'  | '0603LF'  | 'EMPTY'  | 'CS-5113F900'(!)        = 'End of Design' | 'Comp-Approve'     | 'CS-5113F900'           |'R0603'| '(SMR0603AW)'                  | '5.11'    | '1%'    | '1/10W'  | 'IO'       | 'RES CHIP 5.11 1/10W +-1%(0603)'                   | 'CHIP0603'     | ''          | ''            | '20130731'
 '232'        | '1%'      | '1/16W'  | '0402LF'  | 'CHIP'   | 'CS12322FB09'(!)        = 'End of Design' | 'Comp-Release Qty' | 'CS12322FB09'           |'R0402'| '(R0402-0201)'                 | '232'     | '1%'    | '1/16W'  | 'DISCRETE' | 'RES CHIP 232 1/16W +-1%(0402)'                    | 'CHIP0402'     | ''          | ''            | '20130731'
 '232'        | '1%'      | '1/16W'  | '0402LF'  | 'EMPTY'  | 'CS12322FB09'(!)        = 'End of Design' | 'Comp-Release Qty' | 'CS12322FB09'           |'R0402'| '(R0402-0201)'                 | '232'     | '1%'    | '1/16W'  | 'IO'       | 'RES CHIP 232 1/16W +-1%(0402)'                    | 'CHIP0402'     | ''          | ''            | '20130731'
 '511K'       | '1%'      | '1/16W'  | '0402LF'  | 'CHIP'   | 'CS45112FB19'(!)        = 'End of Design' | 'Comp-Approve'     | 'CS45112FB19'           |'R0402'| '(R0402-0201)'                 | '511K'    | '1%'    | '1/16W'  | 'DISCRETE' | 'RES CHIP 511K 1/16W +-1%(0402)'                   | 'CHIP0402'     | ''          | ''            | '20130808'
 '511K'       | '1%'      | '1/16W'  | '0402LF'  | 'EMPTY'  | 'CS45112FB19'(!)        = 'End of Design' | 'Comp-Approve'     | 'CS45112FB19'           |'R0402'| '(R0402-0201)'                 | '511K'    | '1%'    | '1/16W'  | 'IO'       | 'RES CHIP 511K 1/16W +-1%(0402)'                   | 'CHIP0402'     | ''          | ''            | '20130808'
 '140'        | '1%'      | '1/10W'  | '0603LF'  | 'CHIP'   | 'CS11403F915'(!)        = 'End of Design' | 'Comp-Approve'     | 'CS11403F915'           |'R0603'| '(SMR0603AW)'                  | '140'     | '1%'    | '1/10W'  | 'DISCRETE' | 'RESISTOR CHIP 140 1/10W +-1%(0603)'               | 'CHIP0603'     | ''          | ''            | '20130815'
 '140'        | '1%'      | '1/10W'  | '0603LF'  | 'EMPTY'  | 'CS11403F915'(!)        = 'End of Design' | 'Comp-Approve'     | 'CS11403F915'           |'R0603'| '(SMR0603AW)'                  | '140'     | '1%'    | '1/10W'  | 'IO'       | 'RESISTOR CHIP 140 1/10W +-1%(0603)'               | 'CHIP0603'     | ''          | ''            | '20130815'
 '4.75K'      | '0.1%'    | '1/16W'  | '0402LF'  | 'CHIP'   | 'CS24752BB00'(!)        = ''              | ''                 | 'CS24752BB00'           |'R0402'| '(R0402-0201)'                 | '4.75K'   | '0.1%'  | '1/16W'  | 'DISCRETE' | 'RES CHIP 4.75K 1/16W +-0.1%(0402)'                | 'CHIP0402'     | ''          | ''            | '20130826'
 '4.75K'      | '0.1%'    | '1/16W'  | '0402LF'  | 'EMPTY'  | 'CS24752BB00'(!)        = ''              | ''                 | 'CS24752BB00'           |'R0402'| '(R0402-0201)'                 | '4.75K'   | '0.1%'  | '1/16W'  | 'IO'       | 'RES CHIP 4.75K 1/16W +-0.1%(0402)'                | 'CHIP0402'     | ''          | ''            | '20130826'
 '137'        | '1%'      | '1/16W'  | '0402LF'  | 'CHIP'   | 'CS11372FB25'(!)        = 'End of Design' | 'Comp-Approve'     | 'CS11372FB25'           |'R0402'| '(R0402-0201)'                 | '137'     | '1%'    | '1/16W'  | 'DISCRETE' | 'RES CHIP 137 1/16W +-1%(0402)'                    | 'CHIP0402'     | ''          | ''            | '20131007'
 '137'        | '1%'      | '1/16W'  | '0402LF'  | 'EMPTY'  | 'CS11372FB25'(!)        = 'End of Design' | 'Comp-Approve'     | 'CS11372FB25'           |'R0402'| '(R0402-0201)'                 | '137'     | '1%'    | '1/16W'  | 'IO'       | 'RES CHIP 137 1/16W +-1%(0402)'                    | 'CHIP0402'     | ''          | ''            | '20131007'
 '1'          | '1%'      | '1/10W'  | '0603LF'  | 'CHIP'   | 'CS-1003F920'(!)        = ''              | ''                 | 'CS-1003F920'           |'R0603'| '(SMR0603AW)'                  | '1'       | '1%'    | '1/10W'  | 'DISCRETE' | 'RES CHIP 1 1/10W +-1%(0603)'                      | 'CHIP0603'     | ''          | ''            | '20131007'
 '1'          | '1%'      | '1/10W'  | '0603LF'  | 'EMPTY'  | 'CS-1003F920'(!)        = ''              | ''                 | 'CS-1003F920'           |'R0603'| '(SMR0603AW)'                  | '1'       | '1%'    | '1/10W'  | 'IO'       | 'RES CHIP 1 1/10W +-1%(0603)'                      | 'CHIP0603'     | ''          | ''            | '20131007'
 '137'        | '1%'      | '1/10W'  | '0603LF'  | 'CHIP'   | 'CS11373F921'(!)        = ''              | ''                 | 'CS11373F921'           |'R0603'| '(SMR0603AW)'                  | '137'     | '1%'    | '1/10W'  | 'DISCRETE' | 'RES CHIP 137 1/10W +-1%(0603)'                    | 'CHIP0603'     | ''          | ''            | '20131007'
 '137'        | '1%'      | '1/10W'  | '0603LF'  | 'EMPTY'  | 'CS11373F921'(!)        = ''              | ''                 | 'CS11373F921'           |'R0603'| '(SMR0603AW)'                  | '137'     | '1%'    | '1/10W'  | 'IO'       | 'RES CHIP 137 1/10W +-1%(0603)'                    | 'CHIP0603'     | ''          | ''            | '20131007'
 '442'        | '1%'      | '1/16W'  | '0402LF'  | 'CHIP'   | 'CS14422FB16'(!)        = 'End of Design' | 'Comp-Approve'     | 'CS14422FB16'           |'R0402'| '(R0402-0201)'                 | '442'     | '1%'    | '1/16W'  | 'DISCRETE' | 'RES CHIP 442 1/16W +-1% (0402)'                   | 'CHIP0402'     | ''          | ''            | '20131022'
 '442'        | '1%'      | '1/16W'  | '0402LF'  | 'EMPTY'  | 'CS14422FB16'(!)        = 'End of Design' | 'Comp-Approve'     | 'CS14422FB16'           |'R0402'| '(R0402-0201)'                 | '442'     | '1%'    | '1/16W'  | 'IO'       | 'RES CHIP 442 1/16W +-1% (0402)'                   | 'CHIP0402'     | ''          | ''            | '20131022'
 '0.005'      | '1%'      | '1W'     | '2010LF'  | 'CHIP'   | 'CS+0058FJ03'(!)        = ''              | ''                 | 'CS+0058FJ03'           |'R2010'| '(SMR2010AW)'                  | '0.005'   | '1%'    | '1W'     | 'DISCRETE' | 'RES CHIP 0.005 1W +-1%(2010)'                     | 'CHIP2010'     | ''          | ''            | '20131031'
 '0.005'      | '1%'      | '1W'     | '2010LF'  | 'EMPTY'  | 'CS+0058FJ03'(!)        = ''              | ''                 | 'CS+0058FJ03'           |'R2010'| '(SMR2010AW)'                  | '0.005'   | '1%'    | '1W'     | 'IO'       | 'RES CHIP 0.005 1W +-1%(2010)'                     | 'CHIP2010'     | ''          | ''            | '20131031'
 '1.3K'       | '1%'      | '1/16W'  | '0402LF'  | 'CHIP'   | 'CS21302FB17'(!)        = 'End of Design' | 'Comp-Approve'     | 'CS21302FB17'           |'R0402'| '(R0402-0201)'                 | '1.3K'    | '1%'    | '1/16W'  | 'DISCRETE' | 'RES CHIP 1.3K 1/16W +-1%(0402) L-F'               | 'CHIP0402'     | ''          | ''            | '20131122'
 '1.3K'       | '1%'      | '1/16W'  | '0402LF'  | 'EMPTY'  | 'CS21302FB17'(!)        = 'End of Design' | 'Comp-Approve'     | 'CS21302FB17'           |'R0402'| '(R0402-0201)'                 | '1.3K'    | '1%'    | '1/16W'  | 'IO'       | 'RES CHIP 1.3K 1/16W +-1%(0402) L-F'               | 'CHIP0402'     | ''          | ''            | '20131122'
 '2.4K'       | '1%'      | '1/16W'  | '0402LF'  | 'CHIP'   | 'CS22402FB00'(!)        = 'End of Design' | 'Comp-Approve'     | 'CS22402FB00'           |'R0402'| '(R0402-0201)'                 | '2.4K'    | '1%'    | '1/16W'  | 'DISCRETE' | 'RES CHIP 2.4K 1/16W+-1%(0402)'                    | 'CHIP0402'     | ''          | ''            | '20131202'
 '2.4K'       | '1%'      | '1/16W'  | '0402LF'  | 'EMPTY'  | 'CS22402FB00'(!)        = 'End of Design' | 'Comp-Approve'     | 'CS22402FB00'           |'R0402'| '(R0402-0201)'                 | '2.4K'    | '1%'    | '1/16W'  | 'IO'       | 'RES CHIP 2.4K 1/16W+-1%(0402)'                    | 'CHIP0402'     | ''          | ''            | '20131202'
 '1.33K'      | '1%'      | '1/16W'  | '0402LF'  | 'CHIP'   | 'CS21332FB11'(!)        = 'End of Design' | 'Comp-Approve'     | 'CS21332FB11'           |'R0402'| '(R0402-0201)'                 | '1.33K'   | '1%'    | '1/16W'  | 'DISCRETE' | 'RES CHIP 1.33K 1/16W +-1%( 0402)EP'               | 'CHIP0402'     | ''          | ''            | '20131203'
 '1.33K'      | '1%'      | '1/16W'  | '0402LF'  | 'EMPTY'  | 'CS21332FB11'(!)        = 'End of Design' | 'Comp-Approve'     | 'CS21332FB11'           |'R0402'| '(R0402-0201)'                 | '1.33K'   | '1%'    | '1/16W'  | 'IO'       | 'RES CHIP 1.33K 1/16W +-1%( 0402)EP'               | 'CHIP0402'     | ''          | ''            | '20131203'
 '1.78K'      | '1%'      | '1/16W'  | '0402LF'  | 'CHIP'   | 'CS21782FB18'(!)        = 'End of Design' | 'Comp-Approve'     | 'CS21782FB18'           |'R0402'| '(R0402-0201)'                 | '1.78K'   | '1%'    | '1/16W'  | 'DISCRETE' | 'RES CHIP 1.78K 1/16W +-1% (0402)'                 | 'CHIP0402'     | ''          | ''            | '20131205'
 '1.78K'      | '1%'      | '1/16W'  | '0402LF'  | 'EMPTY'  | 'CS21782FB18'(!)        = 'End of Design' | 'Comp-Approve'     | 'CS21782FB18'           |'R0402'| '(R0402-0201)'                 | '1.78K'   | '1%'    | '1/16W'  | 'IO'       | 'RES CHIP 1.78K 1/16W +-1% (0402)'                 | 'CHIP0402'     | ''          | ''            | '20131205'
 '8.45K'      | '1%'      | '1/16W'  | '0402LF'  | 'CHIP'   | 'CS28452FB12'(!)        = 'End of Design' | 'Comp-Approve'     | 'CS28452FB12'           |'R0402'| '(R0402-0201)'                 | '8.45K'   | '1%'    | '1/16W'  | 'DISCRETE' | 'RES CHIP 8.45K 1/16W +-1%( 0402)'                 | 'CHIP0402'     | ''          | ''            | '20131211'
 '8.45K'      | '1%'      | '1/16W'  | '0402LF'  | 'EMPTY'  | 'CS28452FB12'(!)        = 'End of Design' | 'Comp-Approve'     | 'CS28452FB12'           |'R0402'| '(R0402-0201)'                 | '8.45K'   | '1%'    | '1/16W'  | 'IO'       | 'RES CHIP 8.45K 1/16W +-1%( 0402)'                 | 'CHIP0402'     | ''          | ''            | '20131211'
 '1.58K'      | '1%'      | '1/16W'  | '0402LF'  | 'CHIP'   | 'CS21582FB00'(!)        = 'End of Design' | 'Comp-Approve'     | 'CS21582FB00'           |'R0402'| '(R0402-0201)'                 | '1.58K'   | '1%'    | '1/16W'  | 'DISCRETE' | 'RES CHIP 1.58K 1/16W +-1%(0402)'                  | 'CHIP0402'     | ''          | ''            | '20140116'
 '1.58K'      | '1%'      | '1/16W'  | '0402LF'  | 'EMPTY'  | 'CS21582FB00'(!)        = 'End of Design' | 'Comp-Approve'     | 'CS21582FB00'           |'R0402'| '(R0402-0201)'                 | '1.58K'   | '1%'    | '1/16W'  | 'IO'       | 'RES CHIP 1.58K 1/16W +-1%(0402)'                  | 'CHIP0402'     | ''          | ''            | '20140116'
 '18'         | '1%'      | '1/16W'  | '0402LF'  | 'CHIP'   | 'CS01802FB11'(!)        = 'End of Design' | 'Comp-Release Qty' | 'CS01802FB11'           |'R0402'| '(R0402-0201)'                 | '18'      | '1%'    | '1/16W'  | 'DISCRETE' | 'RES CHIP 18 1/16W +-1% (0402)'                    | 'CHIP0402'     | ''          | ''            | '20140128'
 '18'         | '1%'      | '1/16W'  | '0402LF'  | 'EMPTY'  | 'CS01802FB11'(!)        = 'End of Design' | 'Comp-Release Qty' | 'CS01802FB11'           |'R0402'| '(R0402-0201)'                 | '18'      | '1%'    | '1/16W'  | 'IO'       | 'RES CHIP 18 1/16W +-1% (0402)'                    | 'CHIP0402'     | ''          | ''            | '20140128'
 '1.2K'       | '1%'      | '1/8W'   | '0805LF'  | 'CHIP'   | 'CS21204FA17'(!)        = 'End of Design' | 'Comp-Approve'     | 'CS21204FA17'           |'R0805'| '(SMR0805AW)'                  | '1.2K'    | '1%'    | '1/8W'   | 'DISCRETE' | 'RES CHIP 1.2K 1/8W +-1%(0805)'                    | 'CHIP0805'     | ''          | ''            | '20140310'
 '1.2K'       | '1%'      | '1/8W'   | '0805LF'  | 'EMPTY'  | 'CS21204FA17'(!)        = 'End of Design' | 'Comp-Approve'     | 'CS21204FA17'           |'R0805'| '(SMR0805AW)'                  | '1.2K'    | '1%'    | '1/8W'   | 'IO'       | 'RES CHIP 1.2K 1/8W +-1%(0805)'                    | 'CHIP0805'     | ''          | ''            | '20140310'
 '68'         | '5%'      | '1/4W'   | '0805LF'  | 'CHIP'   | 'CS06806JA00'(!)        = ''              | ''                 | 'CS06806JA00'           |'R0805'| '(SMR0805AW)'                  | '68'      | '5%'    | '1/4W'   | 'DISCRETE' | 'RES CHIP 68 1/4W +-5%(0805)'                      | 'CHIP0805'     | ''          | ''            | '20140415'
 '68'         | '5%'      | '1/4W'   | '0805LF'  | 'EMPTY'  | 'CS06806JA00'(!)        = ''              | ''                 | 'CS06806JA00'           |'R0805'| '(SMR0805AW)'                  | '68'      | '5%'    | '1/4W'   | 'IO'       | 'RES CHIP 68 1/4W +-5%(0805)'                      | 'CHIP0805'     | ''          | ''            | '20140415'
 '33'         | '5%'      | '1/2W'   | '1206LF'  | 'CHIP'   | 'CS03307J200'(!)        = ''              | ''                 | 'CS03307J200'           |'R1206'| '(SMR1206AW)'                  | '33'      | '5%'    | '1/2W'   | 'DISCRETE' | 'RES CHIP 33 1/2W +-5%(1206)'                      | 'CHIP1206'     | ''          | ''            | '20140415'
 '33'         | '5%'      | '1/2W'   | '1206LF'  | 'EMPTY'  | 'CS03307J200'(!)        = ''              | ''                 | 'CS03307J200'           |'R1206'| '(SMR1206AW)'                  | '33'      | '5%'    | '1/2W'   | 'IO'       | 'RES CHIP 33 1/2W +-5%(1206)'                      | 'CHIP1206'     | ''          | ''            | '20140415'
 '1K'         | '1%'      | '1/20W'  | '0201LF'  | 'CHIP'   | 'CS21001FE04'(!)        = ''              | ''                 | 'CS21001FE04'           |'R0201'| '(SMR0201AW)'                  | '1K'      | '1%'    | '1/20W'  | 'DISCRETE' | 'RES CHIP 1K 1/20W +-1%(0201)'                     | 'CHIP0201'     | ''          | ''            | '20140424'
 '1K'         | '1%'      | '1/20W'  | '0201LF'  | 'EMPTY'  | 'CS21001FE04'(!)        = ''              | ''                 | 'CS21001FE04'           |'R0201'| '(SMR0201AW)'                  | '1K'      | '1%'    | '1/20W'  | 'IO'       | 'RES CHIP 1K 1/20W +-1%(0201)'                     | 'CHIP0201'     | ''          | ''            | '20140424'
 '150K'       | '1%'      | '1/10W'  | '0603LF'  | 'CHIP'   | 'CS41503F914'(!)        = 'End of Design' | 'Comp-Approve'     | 'CS41503F914'           |'R0603'| '(SMR0603AW)'                  | '150K'    | '1%'    | '1/10W'  | 'DISCRETE' | 'RES CHIP 150K 1/10W +-1%(0603)'                   | 'CHIP0603'     | ''          | ''            | '20140429'
 '150K'       | '1%'      | '1/10W'  | '0603LF'  | 'EMPTY'  | 'CS41503F914'(!)        = 'End of Design' | 'Comp-Approve'     | 'CS41503F914'           |'R0603'| '(SMR0603AW)'                  | '150K'    | '1%'    | '1/10W'  | 'IO'       | 'RES CHIP 150K 1/10W +-1%(0603)'                   | 'CHIP0603'     | ''          | ''            | '20140429'
 '0.015'      | '1%'      | '1W'     | '2512LF'  | 'CHIP'   | 'CS+0158FR00'(!)        = 'End of Design' | 'Comp-Approve'     | 'CS+0158FR00'           |'R2512'| '(SMR2512AW)'                  | '0.015'   | '1%'    | '1W'     | 'DISCRETE' | 'RES CHIP 0.015 1W +-1%(2512)'                     | 'CHIP2512'     | ''          | ''            | '20140505'
 '0.015'      | '1%'      | '1W'     | '2512LF'  | 'EMPTY'  | 'CS+0158FR00'(!)        = 'End of Design' | 'Comp-Approve'     | 'CS+0158FR00'           |'R2512'| '(SMR2512AW)'                  | '0.015'   | '1%'    | '1W'     | 'IO'       | 'RES CHIP 0.015 1W +-1%(2512)'                     | 'CHIP2512'     | ''          | ''            | '20140505'
 '2.2K'       | '1%'      | '1/10W'  | '0603LF'  | 'CHIP'   | 'CS22203F904'(!)        = ''              | ''                 | 'CS22203F904'           |'R0603'| '(SMR0603AW)'                  | '2.2K'    | '1%'    | '1/10W'  | 'DISCRETE' | 'RES CHIP 2.2K 1/10W.+-1%(0603)'                   | 'CHIP0603'     | ''          | ''            | '20140505'
 '2.2K'       | '1%'      | '1/10W'  | '0603LF'  | 'EMPTY'  | 'CS22203F904'(!)        = ''              | ''                 | 'CS22203F904'           |'R0603'| '(SMR0603AW)'                  | '2.2K'    | '1%'    | '1/10W'  | 'IO'       | 'RES CHIP 2.2K 1/10W.+-1%(0603)'                   | 'CHIP0603'     | ''          | ''            | '20140505'
 '200K'       | '1%'      | '1/8W'   | '0805LF'  | 'CHIP'   | 'CS42004FA00'(!)        = ''              | ''                 | 'CS42004FA00'           |'R0805'| '(SMR0805AW)'                  | '200K'    | '1%'    | '1/8W'   | 'DISCRETE' | 'RES CHIP 200K 1/8W +-1%(0805)'                    | 'CHIP0805'     | ''          | ''            | '20140527'
 '200K'       | '1%'      | '1/8W'   | '0805LF'  | 'EMPTY'  | 'CS42004FA00'(!)        = ''              | ''                 | 'CS42004FA00'           |'R0805'| '(SMR0805AW)'                  | '200K'    | '1%'    | '1/8W'   | 'IO'       | 'RES CHIP 200K 1/8W +-1%(0805)'                    | 'CHIP0805'     | ''          | ''            | '20140527'
 '23.2K'      | '1%'      | '1/10W'  | '0603LF'  | 'CHIP'   | 'CS32323F917'(!)        = ''              | ''                 | 'CS32323F917'           |'R0603'| '(SMR0603AW)'                  | '23.2K'   | '1%'    | '1/10W'  | 'DISCRETE' | 'RES CHIP 23.2K 1/10W +-1%(0603)'                  | 'CHIP0603'     | ''          | ''            | '20140529'
 '23.2K'      | '1%'      | '1/10W'  | '0603LF'  | 'EMPTY'  | 'CS32323F917'(!)        = ''              | ''                 | 'CS32323F917'           |'R0603'| '(SMR0603AW)'                  | '23.2K'   | '1%'    | '1/10W'  | 'IO'       | 'RES CHIP 23.2K 1/10W +-1%(0603)'                  | 'CHIP0603'     | ''          | ''            | '20140529'
 '470'        | '1%'      | '1/16W'  | '0402LF'  | 'CHIP'   | 'CS14702FB18'(!)        = 'End of Design' | 'Comp-Approve'     | 'CS14702FB18'           |'R0402'| '(R0402-0201)'                 | '470'     | '1%'    | '1/16W'  | 'DISCRETE' | 'RES CHIP 470 1/16W +-1%(0402)'                    | 'CHIP0402'     | ''          | ''            | '20140605'
 '470'        | '1%'      | '1/16W'  | '0402LF'  | 'EMPTY'  | 'CS14702FB18'(!)        = 'End of Design' | 'Comp-Approve'     | 'CS14702FB18'           |'R0402'| '(R0402-0201)'                 | '470'     | '1%'    | '1/16W'  | 'IO'       | 'RES CHIP 470 1/16W +-1%(0402)'                    | 'CHIP0402'     | ''          | ''            | '20140605'
 '12K'        | '0.5%'    | '1/16W'  | '0402LF'  | 'CHIP'   | 'CS31202DB00'(!)        = ''              | ''                 | 'CS31202DB00'           |'R0402'| '(R0402-0201)'                 | '12K'     | '0.5%'  | '1/16W'  | 'DISCRETE' | 'RES CHIP 12K 1/16W +-0.5%(0402)'                  | 'CHIP0402'     | ''          | ''            | '20140613'
 '12K'        | '0.5%'    | '1/16W'  | '0402LF'  | 'EMPTY'  | 'CS31202DB00'(!)        = ''              | ''                 | 'CS31202DB00'           |'R0402'| '(R0402-0201)'                 | '12K'     | '0.5%'  | '1/16W'  | 'IO'       | 'RES CHIP 12K 1/16W +-0.5%(0402)'                  | 'CHIP0402'     | ''          | ''            | '20140613'
 '2.8K'       | '1%'      | '1/16W'  | '0402LF'  | 'CHIP'   | 'CS22802FB02'(!)        = ''              | 'End of Life'      | 'CS22802FB02'           |'R0402_EOL'| '(R0402-0201)'                 | '2.8K'    | '1%'    | '1/16W'  | 'DISCRETE' | 'RES CHIP 2.8K 1/16W +-1%(0402)'                   | 'CHIP0402'     | ''          | ''            | '20140616'
 '2.8K'       | '1%'      | '1/16W'  | '0402LF'  | 'EMPTY'  | 'CS22802FB02'(!)        = ''              | 'End of Life'      | 'CS22802FB02'           |'R0402_EOL'| '(R0402-0201)'                 | '2.8K'    | '1%'    | '1/16W'  | 'IO'       | 'RES CHIP 2.8K 1/16W +-1%(0402)'                   | 'CHIP0402'     | ''          | ''            | '20140616'
 '1.69K'      | '1%'      | '1/16W'  | '0402LF'  | 'CHIP'   | 'CS21692FB01'(!)        = 'End of Design' | 'Comp-Approve'     | 'CS21692FB01'           |'R0402'| '(R0402-0201)'                 | '1.69K'   | '1%'    | '1/16W'  | 'DISCRETE' | 'RES CHIP 1.69K 1/16W +-1%(0402)'                  | 'CHIP0402'     | ''          | ''            | '20140616'
 '1.69K'      | '1%'      | '1/16W'  | '0402LF'  | 'EMPTY'  | 'CS21692FB01'(!)        = 'End of Design' | 'Comp-Approve'     | 'CS21692FB01'           |'R0402'| '(R0402-0201)'                 | '1.69K'   | '1%'    | '1/16W'  | 'IO'       | 'RES CHIP 1.69K 1/16W +-1%(0402)'                  | 'CHIP0402'     | ''          | ''            | '20140616'
 '40.2'       | '1%'      | '1/16W'  | '0402LF'  | 'CHIP'   | 'CS04022FB28'(!)        = 'End of Design' | 'Comp-Approve'     | 'CS04022FB28'           |'R0402'| '(R0402-0201)'                 | '40.2'    | '1%'    | '1/16W'  | 'DISCRETE' | 'RES CHIP 40.2 1/16W +-1%(0402)'                   | 'CHIP0402'     | ''          | ''            | '20140630'
 '40.2'       | '1%'      | '1/16W'  | '0402LF'  | 'EMPTY'  | 'CS04022FB28'(!)        = 'End of Design' | 'Comp-Approve'     | 'CS04022FB28'           |'R0402'| '(R0402-0201)'                 | '40.2'    | '1%'    | '1/16W'  | 'IO'       | 'RES CHIP 40.2 1/16W +-1%(0402)'                   | 'CHIP0402'     | ''          | ''            | '20140630'
 '1.8K'       | '1%'      | '1/16W'  | '0402LF'  | 'CHIP'   | 'CS21802FB10'(!)        = 'End of Design' | 'Comp-Approve'     | 'CS21802FB10'           |'R0402'| '(R0402-0201)'                 | '1.8K'    | '1%'    | '1/16W'  | 'DISCRETE' | 'RES CHIP 1.8K 1/16W +-1%(0402)'                   | 'CHIP0402'     | ''          | ''            | '20140630'
 '1.8K'       | '1%'      | '1/16W'  | '0402LF'  | 'EMPTY'  | 'CS21802FB10'(!)        = 'End of Design' | 'Comp-Approve'     | 'CS21802FB10'           |'R0402'| '(R0402-0201)'                 | '1.8K'    | '1%'    | '1/16W'  | 'IO'       | 'RES CHIP 1.8K 1/16W +-1%(0402)'                   | 'CHIP0402'     | ''          | ''            | '20140630'
 '1.74K'      | '1%'      | '1/10W'  | '0603LF'  | 'CHIP'   | 'CS21743F916'(!)        = ''              | ''                 | 'CS21743F916'           |'R0603'| '(SMR0603AW)'                  | '1.74K'   | '1%'    | '1/10W'  | 'DISCRETE' | 'RESISTER CHIP 1.74K 1/10W +-1%(0603)L-F'          | 'CHIP0603'     | ''          | ''            | '20140724'
 '1.74K'      | '1%'      | '1/10W'  | '0603LF'  | 'EMPTY'  | 'CS21743F916'(!)        = ''              | ''                 | 'CS21743F916'           |'R0603'| '(SMR0603AW)'                  | '1.74K'   | '1%'    | '1/10W'  | 'IO'       | 'RESISTER CHIP 1.74K 1/10W +-1%(0603)L-F'          | 'CHIP0603'     | ''          | ''            | '20140724'
 '113K'       | '1%'      | '1/16W'  | '0402LF'  | 'CHIP'   | 'CS41132FB17'(!)        = 'End of Design' | 'Comp-Approve'     | 'CS41132FB17'           |'R0402'| '(R0402-0201)'                 | '113K'    | '1%'    | '1/16W'  | 'DISCRETE' | 'RES CHIP 113K 1/16W +-1%(0402)'                   | 'CHIP0402'     | ''          | ''            | '20140729'
 '113K'       | '1%'      | '1/16W'  | '0402LF'  | 'EMPTY'  | 'CS41132FB17'(!)        = 'End of Design' | 'Comp-Approve'     | 'CS41132FB17'           |'R0402'| '(R0402-0201)'                 | '113K'    | '1%'    | '1/16W'  | 'IO'       | 'RES CHIP 113K 1/16W +-1%(0402)'                   | 'CHIP0402'     | ''          | ''            | '20140729'
 '82'         | '1%'      | '1/16W'  | '0402LF'  | 'CHIP'   | 'CS08202FB01'(!)        = 'End of Design' | 'Comp-Approve'     | 'CS08202FB01'           |'R0402'| '(R0402-0201)'                 | '82'      | '1%'    | '1/16W'  | 'DISCRETE' | 'RES CHIP 82(1/16W,+-1%,0402)EP'                   | 'CHIP0402'     | ''          | ''            | '20140729'
 '82'         | '1%'      | '1/16W'  | '0402LF'  | 'EMPTY'  | 'CS08202FB01'(!)        = 'End of Design' | 'Comp-Approve'     | 'CS08202FB01'           |'R0402'| '(R0402-0201)'                 | '82'      | '1%'    | '1/16W'  | 'IO'       | 'RES CHIP 82(1/16W,+-1%,0402)EP'                   | 'CHIP0402'     | ''          | ''            | '20140729'
 '42.2K'      | '1%'      | '1/8W'   | '0805LF'  | 'CHIP'   | 'CS34224FA00'(!)        = ''              | ''                 | 'CS34224FA00'           |'R0805'| '(SMR0805AW)'                  | '42.2K'   | '1%'    | '1/8W'   | 'DISCRETE' | 'RES CHIP 42.2K 1/8W +-1%(0805)'                   | 'CHIP0805'     | ''          | ''            | '20140806'
 '42.2K'      | '1%'      | '1/8W'   | '0805LF'  | 'EMPTY'  | 'CS34224FA00'(!)        = ''              | ''                 | 'CS34224FA00'           |'R0805'| '(SMR0805AW)'                  | '42.2K'   | '1%'    | '1/8W'   | 'IO'       | 'RES CHIP 42.2K 1/8W +-1%(0805)'                   | 'CHIP0805'     | ''          | ''            | '20140806'
 '0.3'        | '1%'      | '1/2W'   | '1206LF'  | 'CHIP'   | 'CS+3007F200'(!)        = ''              | ''                 | 'CS+3007F200'           |'R1206'| '(SMR1206AW)'                  | '0.3'     | '1%'    | '1/2W'   | 'DISCRETE' | 'RES CHIP 0.3 1/2W +-1%(1206)'                     | 'CHIP1206'     | ''          | ''            | '20140806'
 '0.3'        | '1%'      | '1/2W'   | '1206LF'  | 'EMPTY'  | 'CS+3007F200'(!)        = ''              | ''                 | 'CS+3007F200'           |'R1206'| '(SMR1206AW)'                  | '0.3'     | '1%'    | '1/2W'   | 'IO'       | 'RES CHIP 0.3 1/2W +-1%(1206)'                     | 'CHIP1206'     | ''          | ''            | '20140806'
 '1.21'       | '1%'      | '1/16W'  | '0402LF'  | 'CHIP'   | 'CS-1212FB00'(!)        = ''              | ''                 | 'CS-1212FB00'           |'R0402'| '(R0402-0201)'                 | '1.21'    | '1%'    | '1/16W'  | 'DISCRETE' | 'RES CHIP 1.21 1/16W +-1%(0402)'                   | 'CHIP0402'     | ''          | ''            | '20140807'
 '1.21'       | '1%'      | '1/16W'  | '0402LF'  | 'EMPTY'  | 'CS-1212FB00'(!)        = ''              | ''                 | 'CS-1212FB00'           |'R0402'| '(R0402-0201)'                 | '1.21'    | '1%'    | '1/16W'  | 'IO'       | 'RES CHIP 1.21 1/16W +-1%(0402)'                   | 'CHIP0402'     | ''          | ''            | '20140807'
 '0.004'      | '1%'      | '3W'     | '2512LF'  | 'CHIP'   | 'CS+004DFR00'(!)        = ''              | ''                 | 'CS+004DFR00'           |'R2512XF'| '(SMR2512AW)'                  | '0.004'   | '1%'    | '3W'     | 'DISCRETE' | 'RES CHIP 0.004 3W +-1%(2512)'                     | 'CHIP2512'     | ''          | ''            | '20140808'
 '0.004'      | '1%'      | '3W'     | '2512LF'  | 'EMPTY'  | 'CS+004DFR00'(!)        = ''              | ''                 | 'CS+004DFR00'           |'R2512XF'| '(SMR2512AW)'                  | '0.004'   | '1%'    | '3W'     | 'IO'       | 'RES CHIP 0.004 3W +-1%(2512)'                     | 'CHIP2512'     | ''          | ''            | '20140808'
 '68.1'       | '1%'      | '1/16W'  | '0402LF'  | 'CHIP'   | 'CS06812FB00'(!)        = 'End of Design' | 'Comp-Approve'     | 'CS06812FB00'           |'R0402'| '(R0402-0201)'                 | '68.1'    | '1%'    | '1/16W'  | 'DISCRETE' | 'RES CHIP 68.1 1/16W +-1% (0402)'                  | 'CHIP0402'     | ''          | ''            | '20140808'
 '68.1'       | '1%'      | '1/16W'  | '0402LF'  | 'EMPTY'  | 'CS06812FB00'(!)        = 'End of Design' | 'Comp-Approve'     | 'CS06812FB00'           |'R0402'| '(R0402-0201)'                 | '68.1'    | '1%'    | '1/16W'  | 'IO'       | 'RES CHIP 68.1 1/16W +-1% (0402)'                  | 'CHIP0402'     | ''          | ''            | '20140808'
 '332'        | '1%'      | '1/16W'  | '0402LF'  | 'CHIP'   | 'CS13322FB10'(!)        = 'End of Design' | 'Comp-Approve'     | 'CS13322FB10'           |'R0402'| '(R0402-0201)'                 | '332'     | '1%'    | '1/16W'  | 'DISCRETE' | 'RES CHIP 332 1/16W +-1%(0402)'                    | 'CHIP0402'     | ''          | ''            | '20140808'
 '332'        | '1%'      | '1/16W'  | '0402LF'  | 'EMPTY'  | 'CS13322FB10'(!)        = 'End of Design' | 'Comp-Approve'     | 'CS13322FB10'           |'R0402'| '(R0402-0201)'                 | '332'     | '1%'    | '1/16W'  | 'IO'       | 'RES CHIP 332 1/16W +-1%(0402)'                    | 'CHIP0402'     | ''          | ''            | '20140808'
 '5.62K'      | '1%'      | '1/16W'  | '0402LF'  | 'CHIP'   | 'CS25622FB18'(!)        = 'End of Design' | 'Comp-Approve'     | 'CS25622FB18'           |'R0402'| '(R0402-0201)'                 | '5.62K'   | '1%'    | '1/16W'  | 'DISCRETE' | 'RES CHIP 5.62K 1/16W +-1%( 0402)'                 | 'CHIP0402'     | ''          | ''            | '20140808'
 '5.62K'      | '1%'      | '1/16W'  | '0402LF'  | 'EMPTY'  | 'CS25622FB18'(!)        = 'End of Design' | 'Comp-Approve'     | 'CS25622FB18'           |'R0402'| '(R0402-0201)'                 | '5.62K'   | '1%'    | '1/16W'  | 'IO'       | 'RES CHIP 5.62K 1/16W +-1%( 0402)'                 | 'CHIP0402'     | ''          | ''            | '20140808'
 '205K'       | '1%'      | '1/8W'   | '0805LF'  | 'CHIP'   | 'CS42054FA00'(!)        = ''              | ''                 | 'CS42054FA00'           |'R0805'| '(SMR0805AW)'                  | '205K'    | '1%'    | '1/8W'   | 'DISCRETE' | 'RES CHIP 205K 1/8W +-1%(0805)'                    | 'CHIP0805'     | ''          | ''            | '20140808'
 '205K'       | '1%'      | '1/8W'   | '0805LF'  | 'EMPTY'  | 'CS42054FA00'(!)        = ''              | ''                 | 'CS42054FA00'           |'R0805'| '(SMR0805AW)'                  | '205K'    | '1%'    | '1/8W'   | 'IO'       | 'RES CHIP 205K 1/8W +-1%(0805)'                    | 'CHIP0805'     | ''          | ''            | '20140808'
 '150K'       | '1%'      | '1/8W'   | '0805LF'  | 'CHIP'   | 'CS41504FA00'(!)        = ''              | ''                 | 'CS41504FA00'           |'R0805'| '(SMR0805AW)'                  | '150K'    | '1%'    | '1/8W'   | 'DISCRETE' | 'RES CHIP 150K 1/8W +-1%(0805)'                    | 'CHIP0805'     | ''          | ''            | '20140808'
 '150K'       | '1%'      | '1/8W'   | '0805LF'  | 'EMPTY'  | 'CS41504FA00'(!)        = ''              | ''                 | 'CS41504FA00'           |'R0805'| '(SMR0805AW)'                  | '150K'    | '1%'    | '1/8W'   | 'IO'       | 'RES CHIP 150K 1/8W +-1%(0805)'                    | 'CHIP0805'     | ''          | ''            | '20140808'
 '221K'       | '1%'      | '1/16W'  | '0402LF'  | 'CHIP'   | 'CS42212FB22'(!)        = 'End of Design' | 'Comp-Approve'     | 'CS42212FB22'           |'R0402'| '(R0402-0201)'                 | '221K'    | '1%'    | '1/16W'  | 'DISCRETE' | 'RES CHIP 221K 1/16W +-1% (0402)'                  | 'CHIP0402'     | ''          | ''            | '20140812'
 '221K'       | '1%'      | '1/16W'  | '0402LF'  | 'EMPTY'  | 'CS42212FB22'(!)        = 'End of Design' | 'Comp-Approve'     | 'CS42212FB22'           |'R0402'| '(R0402-0201)'                 | '221K'    | '1%'    | '1/16W'  | 'IO'       | 'RES CHIP 221K 1/16W +-1% (0402)'                  | 'CHIP0402'     | ''          | ''            | '20140812'
 '10K'        | '0.10%'   | '1/16W'  | '0402LF'  | 'CHIP'   | 'CS31002BB00'(!)        = ''              | ''                 | 'CS31002BB00'           |'R0402'| '(R0402-0201)'                 | '10K'     | '0.10%' | '1/16W'  | 'DISCRETE' | 'RES CHIP 10K 1/16W +-0.1%(0402)'                  | 'CHIP0402'     | ''          | ''            | '20140812'
 '10K'        | '0.10%'   | '1/16W'  | '0402LF'  | 'EMPTY'  | 'CS31002BB00'(!)        = ''              | ''                 | 'CS31002BB00'           |'R0402'| '(R0402-0201)'                 | '10K'     | '0.10%' | '1/16W'  | 'IO'       | 'RES CHIP 10K 1/16W +-0.1%(0402)'                  | 'CHIP0402'     | ''          | ''            | '20140812'
 '470'        | '5%'      | '1/8W'   | '0805LF'  | 'CHIP'   | 'CS14704JA13'(!)        = ''              | ''                 | 'CS14704JA13'           |'R0805'| '(SMR0805AW)'                  | '470'     | '5%'    | '1/8W'   | 'DISCRETE' | 'RES CHIP 470 1/8W +-5%(0805)'                     | 'CHIP0805'     | ''          | ''            | '20140812'
 '470'        | '5%'      | '1/8W'   | '0805LF'  | 'EMPTY'  | 'CS14704JA13'(!)        = ''              | ''                 | 'CS14704JA13'           |'R0805'| '(SMR0805AW)'                  | '470'     | '5%'    | '1/8W'   | 'IO'       | 'RES CHIP 470 1/8W +-5%(0805)'                     | 'CHIP0805'     | ''          | ''            | '20140812'
 '26.7K'      | '0.1%'    | '1/16W'  | '0402LF'  | 'CHIP'   | 'CS32672BB00'(!)        = ''              | ''                 | 'CS32672BB00'           |'R0402'| '(R0402-0201)'                 | '26.7K'   | '0.1%'  | '1/16W'  | 'DISCRETE' | 'RES CHIP 26.7K 1/16W +-0.1%(0402)'                | 'CHIP0402'     | ''          | ''            | '20140813'
 '26.7K'      | '0.1%'    | '1/16W'  | '0402LF'  | 'EMPTY'  | 'CS32672BB00'(!)        = ''              | ''                 | 'CS32672BB00'           |'R0402'| '(R0402-0201)'                 | '26.7K'   | '0.1%'  | '1/16W'  | 'IO'       | 'RES CHIP 26.7K 1/16W +-0.1%(0402)'                | 'CHIP0402'     | ''          | ''            | '20140813'
 '4.64K'      | '0.5%'    | '1/16W'  | '0402LF'  | 'CHIP'   | 'CS24642DB00'(!)        = ''              | ''                 | 'CS24642DB00'           |'R0402'| '(R0402-0201)'                 | '4.64K'   | '0.5%'  | '1/16W'  | 'DISCRETE' | 'RES CHIP 4.64K 1/16W +-0.5%(0402)'                | 'CHIP0402'     | ''          | ''            | '20140813'
 '4.64K'      | '0.5%'    | '1/16W'  | '0402LF'  | 'EMPTY'  | 'CS24642DB00'(!)        = ''              | ''                 | 'CS24642DB00'           |'R0402'| '(R0402-0201)'                 | '4.64K'   | '0.5%'  | '1/16W'  | 'IO'       | 'RES CHIP 4.64K 1/16W +-0.5%(0402)'                | 'CHIP0402'     | ''          | ''            | '20140813'
 '1.78K'      | '0.1%'    | '1/16W'  | '0402LF'  | 'CHIP'   | 'CS21782BB00'(!)        = ''              | ''                 | 'CS21782BB00'           |'R0402'| '(R0402-0201)'                 | '1.78K'   | '0.1%'  | '1/16W'  | 'DISCRETE' | 'RES CHIP 1.78K 1/16W +-0.1%(0402)'                | 'CHIP0402'     | ''          | ''            | '20140813'
 '1.78K'      | '0.1%'    | '1/16W'  | '0402LF'  | 'EMPTY'  | 'CS21782BB00'(!)        = ''              | ''                 | 'CS21782BB00'           |'R0402'| '(R0402-0201)'                 | '1.78K'   | '0.1%'  | '1/16W'  | 'IO'       | 'RES CHIP 1.78K 1/16W +-0.1%(0402)'                | 'CHIP0402'     | ''          | ''            | '20140813'
 '2.37K'      | '0.1%'    | '1/16W'  | '0402LF'  | 'CHIP'   | 'CS22372BB00'(!)        = ''              | ''                 | 'CS22372BB00'           |'R0402'| '(R0402-0201)'                 | '2.37K'   | '0.1%'  | '1/16W'  | 'DISCRETE' | 'RES CHIP 2.37K 1/16W +-0.1%(0402)'                | 'CHIP0402'     | ''          | ''            | '20140813'
 '2.37K'      | '0.1%'    | '1/16W'  | '0402LF'  | 'EMPTY'  | 'CS22372BB00'(!)        = ''              | ''                 | 'CS22372BB00'           |'R0402'| '(R0402-0201)'                 | '2.37K'   | '0.1%'  | '1/16W'  | 'IO'       | 'RES CHIP 2.37K 1/16W +-0.1%(0402)'                | 'CHIP0402'     | ''          | ''            | '20140813'
 '11.3K'      | '0.1%'    | '1/16W'  | '0402LF'  | 'CHIP'   | 'CS31132BB00'(!)        = ''              | ''                 | 'CS31132BB00'           |'R0402'| '(R0402-0201)'                 | '11.3K'   | '0.1%'  | '1/16W'  | 'DISCRETE' | 'RES CHIP 11.3K 1/16W +-0.1%(0402)'                | 'CHIP0402'     | ''          | ''            | '20140813'
 '11.3K'      | '0.1%'    | '1/16W'  | '0402LF'  | 'EMPTY'  | 'CS31132BB00'(!)        = ''              | ''                 | 'CS31132BB00'           |'R0402'| '(R0402-0201)'                 | '11.3K'   | '0.1%'  | '1/16W'  | 'IO'       | 'RES CHIP 11.3K 1/16W +-0.1%(0402)'                | 'CHIP0402'     | ''          | ''            | '20140813'
 '18.2K'      | '0.1%'    | '1/16W'  | '0402LF'  | 'CHIP'   | 'CS31822BB00'(!)        = ''              | ''                 | 'CS31822BB00'           |'R0402'| '(R0402-0201)'                 | '18.2K'   | '0.1%'  | '1/16W'  | 'DISCRETE' | 'RES CHIP 18.2K 1/16W +-0.1%(0402)'                | 'CHIP0402'     | ''          | ''            | '20140813'
 '18.2K'      | '0.1%'    | '1/16W'  | '0402LF'  | 'EMPTY'  | 'CS31822BB00'(!)        = ''              | ''                 | 'CS31822BB00'           |'R0402'| '(R0402-0201)'                 | '18.2K'   | '0.1%'  | '1/16W'  | 'IO'       | 'RES CHIP 18.2K 1/16W +-0.1%(0402)'                | 'CHIP0402'     | ''          | ''            | '20140813'
 '4.99K'      | '1%'      | '1/8W'   | '0805LF'  | 'CHIP'   | 'CS24994FA00'(!)        = ''              | ''                 | 'CS24994FA00'           |'R0805'| '(SMR0805AW)'                  | '4.99K'   | '1%'    | '1/8W'   | 'DISCRETE' | 'RES CHIP 4.99K 1/8W +-1%(0805)'                   | 'CHIP0805'     | ''          | ''            | '20140813'
 '4.99K'      | '1%'      | '1/8W'   | '0805LF'  | 'EMPTY'  | 'CS24994FA00'(!)        = ''              | ''                 | 'CS24994FA00'           |'R0805'| '(SMR0805AW)'                  | '4.99K'   | '1%'    | '1/8W'   | 'IO'       | 'RES CHIP 4.99K 1/8W +-1%(0805)'                   | 'CHIP0805'     | ''          | ''            | '20140813'
 '3.65K'      | '1%'      | '1/10W'  | '0603LF'  | 'CHIP'   | 'CS23653F912'(!)        = ''              | ''                 | 'CS23653F912'           |'R0603'| '(SMR0603AW)'                  | '3.65K'   | '1%'    | '1/10W'  | 'DISCRETE' | 'RES CHIP 3.65K 1/10W(+-1%.0603)'                  | 'CHIP0603'     | ''          | ''            | '20140813'
 '3.65K'      | '1%'      | '1/10W'  | '0603LF'  | 'EMPTY'  | 'CS23653F912'(!)        = ''              | ''                 | 'CS23653F912'           |'R0603'| '(SMR0603AW)'                  | '3.65K'   | '1%'    | '1/10W'  | 'IO'       | 'RES CHIP 3.65K 1/10W(+-1%.0603)'                  | 'CHIP0603'     | ''          | ''            | '20140813'
 '2.21K'      | '1%'      | '1/10W'  | '0603LF'  | 'CHIP'   | 'CS22213F925'(!)        = ''              | ''                 | 'CS22213F925'           |'R0603'| '(SMR0603AW)'                  | '2.21K'   | '1%'    | '1/10W'  | 'DISCRETE' | 'RESISTOR CHIP 2.21K 1/10W +-1%(0603)'             | 'CHIP0603'     | ''          | ''            | '20140813'
 '2.21K'      | '1%'      | '1/10W'  | '0603LF'  | 'EMPTY'  | 'CS22213F925'(!)        = ''              | ''                 | 'CS22213F925'           |'R0603'| '(SMR0603AW)'                  | '2.21K'   | '1%'    | '1/10W'  | 'IO'       | 'RESISTOR CHIP 2.21K 1/10W +-1%(0603)'             | 'CHIP0603'     | ''          | ''            | '20140813'
 '0.003'      | '1%'      | '1W'     | '3720LF'  | 'CHIP'   | 'CS+0038FL00'(!)        = ''              | ''                 | 'CS+0038FL00'           |'R3720XA'| '(SMR3720AW)'                  | '0.003'   | '1%'    | '1W'     | 'DISCRETE' | 'RES CHIP 0.003 1W +-1% (3720)'                    | 'CHIP3720'     | ''          | ''            | '20140814'
 '0.003'      | '1%'      | '1W'     | '3720LF'  | 'EMPTY'  | 'CS+0038FL00'(!)        = ''              | ''                 | 'CS+0038FL00'           |'R3720XA'| '(SMR3720AW)'                  | '0.003'   | '1%'    | '1W'     | 'IO'       | 'RES CHIP 0.003 1W +-1% (3720)'                    | 'CHIP3720'     | ''          | ''            | '20140814'
 '43.2K'      | '1%'      | '1/16W'  | '0402LF'  | 'CHIP'   | 'CS34322FB16'(!)        = ''              | 'End of Life'      | 'CS34322FB16'           |'R0402_EOL'| '(R0402-0201)'                 | '43.2K'   | '1%'    | '1/16W'  | 'DISCRETE' | 'RES CHIP 43.2K 1/16W +-1%(0402)'                  | 'CHIP0402'     | ''          | ''            | '20140817'
 '43.2K'      | '1%'      | '1/16W'  | '0402LF'  | 'EMPTY'  | 'CS34322FB16'(!)        = ''              | 'End of Life'      | 'CS34322FB16'           |'R0402_EOL'| '(R0402-0201)'                 | '43.2K'   | '1%'    | '1/16W'  | 'IO'       | 'RES CHIP 43.2K 1/16W +-1%(0402)'                  | 'CHIP0402'     | ''          | ''            | '20140817'
 '147'        | '0.5%'    | '1/16W'  | '0402LF'  | 'CHIP'   | 'CS11472DB00'(!)        = ''              | ''                 | 'CS11472DB00'           |'R0402'| '(R0402-0201)'                 | '147'     | '0.5%'  | '1/16W'  | 'DISCRETE' | 'RES CHIP 147 1/16W +-0.5%(0402)'                  | 'CHIP0402'     | ''          | ''            | '20140817'
 '147'        | '0.5%'    | '1/16W'  | '0402LF'  | 'EMPTY'  | 'CS11472DB00'(!)        = ''              | ''                 | 'CS11472DB00'           |'R0402'| '(R0402-0201)'                 | '147'     | '0.5%'  | '1/16W'  | 'IO'       | 'RES CHIP 147 1/16W +-0.5%(0402)'                  | 'CHIP0402'     | ''          | ''            | '20140817'
 '2.61K'      | '0.5%'    | '1/16W'  | '0402LF'  | 'CHIP'   | 'CS22612DB00'(!)        = ''              | ''                 | 'CS22612DB00'           |'R0402'| '(R0402-0201)'                 | '2.61K'   | '0.5%'  | '1/16W'  | 'DISCRETE' | 'RES CHIP 2.61K 1/16W +-0.5%(0402)'                | 'CHIP0402'     | ''          | ''            | '20140817'
 '2.61K'      | '0.5%'    | '1/16W'  | '0402LF'  | 'EMPTY'  | 'CS22612DB00'(!)        = ''              | ''                 | 'CS22612DB00'           |'R0402'| '(R0402-0201)'                 | '2.61K'   | '0.5%'  | '1/16W'  | 'IO'       | 'RES CHIP 2.61K 1/16W +-0.5%(0402)'                | 'CHIP0402'     | ''          | ''            | '20140817'
 '2.74'       | '1%'      | '1/16W'  | '0402LF'  | 'CHIP'   | 'CS-2742FB00'(!)        = ''              | ''                 | 'CS-2742FB00'           |'R0402'| '(R0402-0201)'                 | '2.74'    | '1%'    | '1/16W'  | 'DISCRETE' | 'RES CHIP 2.74 1/16W +-1%(0402)'                   | 'CHIP0402'     | ''          | ''            | '20140817'
 '2.74'       | '1%'      | '1/16W'  | '0402LF'  | 'EMPTY'  | 'CS-2742FB00'(!)        = ''              | ''                 | 'CS-2742FB00'           |'R0402'| '(R0402-0201)'                 | '2.74'    | '1%'    | '1/16W'  | 'IO'       | 'RES CHIP 2.74 1/16W +-1%(0402)'                   | 'CHIP0402'     | ''          | ''            | '20140817'
 '10K'        | '1%'      | '1W'     | '2010LF'  | 'CHIP'   | 'CS31008FJ00'(!)        = ''              | ''                 | 'CS31008FJ00'           |'R2010XB'| '(SMR2010AW)'                  | '10K'     | '1%'    | '1W'     | 'DISCRETE' | 'RES CHIP 10K 1W +-1%(2010)'                       | 'CHIP2010'     | ''          | ''            | '20140817'
 '10K'        | '1%'      | '1W'     | '2010LF'  | 'EMPTY'  | 'CS31008FJ00'(!)        = ''              | ''                 | 'CS31008FJ00'           |'R2010XB'| '(SMR2010AW)'                  | '10K'     | '1%'    | '1W'     | 'IO'       | 'RES CHIP 10K 1W +-1%(2010)'                       | 'CHIP2010'     | ''          | ''            | '20140817'
 '158'        | '1%'      | '1/16W'  | '0402LF'  | 'CHIP'   | 'CS11582FB00'(!)        = ''              | ''                 | 'CS11582FB00'           |'R0402'| '(R0402-0201)'                 | '158'     | '1%'    | '1/16W'  | 'DISCRETE' | 'RES CHIP 158 1/16W +-1%(0402)'                    | 'CHIP0402'     | ''          | ''            | '20140817'
 '158'        | '1%'      | '1/16W'  | '0402LF'  | 'EMPTY'  | 'CS11582FB00'(!)        = ''              | ''                 | 'CS11582FB00'           |'R0402'| '(R0402-0201)'                 | '158'     | '1%'    | '1/16W'  | 'IO'       | 'RES CHIP 158 1/16W +-1%(0402)'                    | 'CHIP0402'     | ''          | ''            | '20140817'
 '0.007'      | '1%'      | '1W'     | '3720LF'  | 'CHIP'   | 'CS+0078FL00'(!)        = 'End of Design' | 'Comp-Approve'     | 'CS+0078FL00'           |'R3720XA'| '(SMR3720AW)'                  | '0.007'   | '1%'    | '1W'     | 'DISCRETE' | 'RES CHIP 0.007 1W +-1%(3720)'                     | 'CHIP3720'     | ''          | ''            | '20140817'
 '0.007'      | '1%'      | '1W'     | '3720LF'  | 'EMPTY'  | 'CS+0078FL00'(!)        = 'End of Design' | 'Comp-Approve'     | 'CS+0078FL00'           |'R3720XA'| '(SMR3720AW)'                  | '0.007'   | '1%'    | '1W'     | 'IO'       | 'RES CHIP 0.007 1W +-1%(3720)'                     | 'CHIP3720'     | ''          | ''            | '20140817'
 '2.49K'      | '1%'      | '1/2W'   | '1206LF'  | 'CHIP'   | 'CS22497F200'(!)        = ''              | ''                 | 'CS22497F200'           |'R1206'| '(SMR1206AW)'                  | '2.49K'   | '1%'    | '1/2W'   | 'DISCRETE' | 'RES CHIP 2.49K 1/2W +-1%(1206)'                   | 'CHIP1206'     | ''          | ''            | '20140818'
 '2.49K'      | '1%'      | '1/2W'   | '1206LF'  | 'EMPTY'  | 'CS22497F200'(!)        = ''              | ''                 | 'CS22497F200'           |'R1206'| '(SMR1206AW)'                  | '2.49K'   | '1%'    | '1/2W'   | 'IO'       | 'RES CHIP 2.49K 1/2W +-1%(1206)'                   | 'CHIP1206'     | ''          | ''            | '20140818'
 '1.1K'       | '0.1%'    | '1/16W'  | '0402LF'  | 'CHIP'   | 'CS21102BB00'(!)        = ''              | ''                 | 'CS21102BB00'           |'R0402'| '(R0402-0201)'                 | '1.1K'    | '0.1%'  | '1/16W'  | 'DISCRETE' | 'RES CHIP 1.1K 1/16W +-0.1%(0402)'                 | 'CHIP0402'     | ''          | ''            | '20140818'
 '1.1K'       | '0.1%'    | '1/16W'  | '0402LF'  | 'EMPTY'  | 'CS21102BB00'(!)        = ''              | ''                 | 'CS21102BB00'           |'R0402'| '(R0402-0201)'                 | '1.1K'    | '0.1%'  | '1/16W'  | 'IO'       | 'RES CHIP 1.1K 1/16W +-0.1%(0402)'                 | 'CHIP0402'     | ''          | ''            | '20140818'
 '52.3K'      | '1%'      | '1/16W'  | '0402LF'  | 'CHIP'   | 'CS35232FB10'(!)        = 'End of Design' | 'Comp-Approve'     | 'CS35232FB10'           |'R0402'| '(R0402-0201)'                 | '52.3K'   | '1%'    | '1/16W'  | 'DISCRETE' | 'RES CHIP 52.3K 1/16W +-1% (0402)'                 | 'CHIP0402'     | ''          | ''            | '20140818'
 '52.3K'      | '1%'      | '1/16W'  | '0402LF'  | 'EMPTY'  | 'CS35232FB10'(!)        = 'End of Design' | 'Comp-Approve'     | 'CS35232FB10'           |'R0402'| '(R0402-0201)'                 | '52.3K'   | '1%'    | '1/16W'  | 'IO'       | 'RES CHIP 52.3K 1/16W +-1% (0402)'                 | 'CHIP0402'     | ''          | ''            | '20140818'
 '1'          | '1%'      | '1/16W'  | '0402LF'  | 'CHIP'   | 'CS-1002FB23'(!)        = 'End of Design' | 'Comp-Approve'     | 'CS-1002FB23'           |'R0402'| '(R0402-0201)'                 | '1'       | '1%'    | '1/16W'  | 'DISCRETE' | 'RES CHIP 1 1/16W +-1%(0402)'                      | 'CHIP0402'     | ''          | ''            | '20140818'
 '1'          | '1%'      | '1/16W'  | '0402LF'  | 'EMPTY'  | 'CS-1002FB23'(!)        = 'End of Design' | 'Comp-Approve'     | 'CS-1002FB23'           |'R0402'| '(R0402-0201)'                 | '1'       | '1%'    | '1/16W'  | 'IO'       | 'RES CHIP 1 1/16W +-1%(0402)'                      | 'CHIP0402'     | ''          | ''            | '20140818'
 '0.5'        | '1%'      | '1/10W'  | '0603LF'  | 'CHIP'   | 'CS+5003F911'(!)        = ''              | ''                 | 'CS+5003F911'           |'R0603'| '(SMR0603AW)'                  | '0.5'     | '1%'    | '1/10W'  | 'DISCRETE' | 'RES CHIP 0.5 1/10W +-1%(0603)'                    | 'CHIP0603'     | ''          | ''            | '20140818'
 '0.5'        | '1%'      | '1/10W'  | '0603LF'  | 'EMPTY'  | 'CS+5003F911'(!)        = ''              | ''                 | 'CS+5003F911'           |'R0603'| '(SMR0603AW)'                  | '0.5'     | '1%'    | '1/10W'  | 'IO'       | 'RES CHIP 0.5 1/10W +-1%(0603)'                    | 'CHIP0603'     | ''          | ''            | '20140818'
 '1.91K'      | '1%'      | '1/10W'  | '0603LF'  | 'CHIP'   | 'CS21913F910'(!)        = ''              | ''                 | 'CS21913F910'           |'R0603'| '(SMR0603AW)'                  | '1.91K'   | '1%'    | '1/10W'  | 'DISCRETE' | 'RESISTER CHIP 1.91K 1/10W +-1%(0603)'             | 'CHIP0603'     | ''          | ''            | '20140818'
 '1.91K'      | '1%'      | '1/10W'  | '0603LF'  | 'EMPTY'  | 'CS21913F910'(!)        = ''              | ''                 | 'CS21913F910'           |'R0603'| '(SMR0603AW)'                  | '1.91K'   | '1%'    | '1/10W'  | 'IO'       | 'RESISTER CHIP 1.91K 1/10W +-1%(0603)'             | 'CHIP0603'     | ''          | ''            | '20140818'
 '30K'        | '1%'      | '1/10W'  | '0603LF'  | 'CHIP'   | 'CS33003F910'(!)        = ''              | ''                 | 'CS33003F910'           |'R0603'| '(SMR0603AW)'                  | '30K'     | '1%'    | '1/10W'  | 'DISCRETE' | 'RESISTOR CHIP 30K.1/10W.+-1%(0603)'               | 'CHIP0603'     | ''          | ''            | '20140818'
 '30K'        | '1%'      | '1/10W'  | '0603LF'  | 'EMPTY'  | 'CS33003F910'(!)        = ''              | ''                 | 'CS33003F910'           |'R0603'| '(SMR0603AW)'                  | '30K'     | '1%'    | '1/10W'  | 'IO'       | 'RESISTOR CHIP 30K.1/10W.+-1%(0603)'               | 'CHIP0603'     | ''          | ''            | '20140818'
 '0'          | '5%'      | '1W'     | '2512LF'  | 'CHIP'   | 'CS00008J125'(!)        = ''              | ''                 | 'CS00008J125'           |'R2512'| '(SMR2512AW)'                  | '0'       | '5%'    | '1W'     | 'DISCRETE' | 'RESISTOR CHIP 0 1W +-5% (2512)'                   | 'CHIP2512'     | ''          | ''            | '20140818'
 '0'          | '5%'      | '1W'     | '2512LF'  | 'EMPTY'  | 'CS00008J125'(!)        = ''              | ''                 | 'CS00008J125'           |'R2512'| '(SMR2512AW)'                  | '0'       | '5%'    | '1W'     | 'IO'       | 'RESISTOR CHIP 0 1W +-5% (2512)'                   | 'CHIP2512'     | ''          | ''            | '20140818'
 '39.2'       | '1%'      | '1/16W'  | '0402LF'  | 'CHIP'   | 'CS03922FB10'(!)        = 'End of Design' | 'Comp-Approve'     | 'CS03922FB10'           |'R0402'| '(R0402-0201)'                 | '39.2'    | '1%'    | '1/16W'  | 'DISCRETE' | 'RES CHIP 39.2 1/16W +-1%(0402)'                   | 'CHIP0402'     | ''          | ''            | '20140818'
 '39.2'       | '1%'      | '1/16W'  | '0402LF'  | 'EMPTY'  | 'CS03922FB10'(!)        = 'End of Design' | 'Comp-Approve'     | 'CS03922FB10'           |'R0402'| '(R0402-0201)'                 | '39.2'    | '1%'    | '1/16W'  | 'IO'       | 'RES CHIP 39.2 1/16W +-1%(0402)'                   | 'CHIP0402'     | ''          | ''            | '20140818'
 '191K'       | '1%'      | '1/8W'   | '0805LF'  | 'CHIP'   | 'CS41914FA00'(!)        = ''              | ''                 | 'CS41914FA00'           |'R0805'| '(SMR0805AW)'                  | '191K'    | '1%'    | '1/8W'   | 'DISCRETE' | 'RES CHIP 191K 1/8W +-1%(0805)'                    | 'CHIP0805'     | ''          | ''            | '20140819'
 '191K'       | '1%'      | '1/8W'   | '0805LF'  | 'EMPTY'  | 'CS41914FA00'(!)        = ''              | ''                 | 'CS41914FA00'           |'R0805'| '(SMR0805AW)'                  | '191K'    | '1%'    | '1/8W'   | 'IO'       | 'RES CHIP 191K 1/8W +-1%(0805)'                    | 'CHIP0805'     | ''          | ''            | '20140819'
 '28'         | '1%'      | '1/10W'  | '0603LF'  | 'CHIP'   | 'CS02803F900'(!)        = ''              | ''                 | 'CS02803F900'           |'R0603'| '(SMR0603AW)'                  | '28'      | '1%'    | '1/10W'  | 'DISCRETE' | 'RES CHIP 28 1/10W +-1%(0603)'                     | 'CHIP0603'     | ''          | ''            | '20140819'
 '28'         | '1%'      | '1/10W'  | '0603LF'  | 'EMPTY'  | 'CS02803F900'(!)        = ''              | ''                 | 'CS02803F900'           |'R0603'| '(SMR0603AW)'                  | '28'      | '1%'    | '1/10W'  | 'IO'       | 'RES CHIP 28 1/10W +-1%(0603)'                     | 'CHIP0603'     | ''          | ''            | '20140819'
 '52.3'       | '1%'      | '1/10W'  | '0603LF'  | 'CHIP'   | 'CS05233F900'(!)        = ''              | ''                 | 'CS05233F900'           |'R0603'| '(SMR0603AW)'                  | '52.3'    | '1%'    | '1/10W'  | 'DISCRETE' | 'RES CHIP 52.3 1/10W +-1%(0603)'                   | 'CHIP0603'     | ''          | ''            | '20140819'
 '52.3'       | '1%'      | '1/10W'  | '0603LF'  | 'EMPTY'  | 'CS05233F900'(!)        = ''              | ''                 | 'CS05233F900'           |'R0603'| '(SMR0603AW)'                  | '52.3'    | '1%'    | '1/10W'  | 'IO'       | 'RES CHIP 52.3 1/10W +-1%(0603)'                   | 'CHIP0603'     | ''          | ''            | '20140819'
 '0.008'      | '1%'      | '3W'     | '2512LF'  | 'CHIP'   | 'CS+008DFR00'(!)        = ''              | ''                 | 'CS+008DFR00'           |'R2512XA'| '(SMR2512AW)'                  | '0.008'   | '1%'    | '3W'     | 'DISCRETE' | 'RES CHIP 0.008 3W +-1%(2512)'                     | 'CHIP2512'     | ''          | ''            | '20140819'
 '0.008'      | '1%'      | '3W'     | '2512LF'  | 'EMPTY'  | 'CS+008DFR00'(!)        = ''              | ''                 | 'CS+008DFR00'           |'R2512XA'| '(SMR2512AW)'                  | '0.008'   | '1%'    | '3W'     | 'IO'       | 'RES CHIP 0.008 3W +-1%(2512)'                     | 'CHIP2512'     | ''          | ''            | '20140819'
 '0.002'      | '1%'      | '3W'     | '2512LF'  | 'CHIP'   | 'CS+002DFR00'(!)        = ''              | ''                 | 'CS+002DFR00'           |'R2512XJ'| '(SMR2512AW)'                  | '0.002'   | '1%'    | '3W'     | 'DISCRETE' | 'RES CHIP 0.002 3W +-1%(2512)'                     | 'CHIP2512'     | ''          | ''            | '20140819'
 '0.002'      | '1%'      | '3W'     | '2512LF'  | 'EMPTY'  | 'CS+002DFR00'(!)        = ''              | ''                 | 'CS+002DFR00'           |'R2512XJ'| '(SMR2512AW)'                  | '0.002'   | '1%'    | '3W'     | 'IO'       | 'RES CHIP 0.002 3W +-1%(2512)'                     | 'CHIP2512'     | ''          | ''            | '20140819'
 '180'        | '1%'      | '1/4W'   | '1206LF'  | 'CHIP'   | 'CS11806F215'(!)        = ''              | ''                 | 'CS11806F215'           |'R1206'| '(SMR1206AW)'                  | '180'     | '1%'    | '1/4W'   | 'DISCRETE' | 'RES CHIP 180 1/4W(+-1%,3216)'                     | 'CHIP1206'     | ''          | ''            | '20140819'
 '180'        | '1%'      | '1/4W'   | '1206LF'  | 'EMPTY'  | 'CS11806F215'(!)        = ''              | ''                 | 'CS11806F215'           |'R1206'| '(SMR1206AW)'                  | '180'     | '1%'    | '1/4W'   | 'IO'       | 'RES CHIP 180 1/4W(+-1%,3216)'                     | 'CHIP1206'     | ''          | ''            | '20140819'
 '1'          | '5%'      | '1/2W'   | '2010LF'  | 'CHIP'   | 'CS-1007JJ01'(!)        = ''              | ''                 | 'CS-1007JJ01'           |'R2010'| '(SMR2010AW)'                  | '1'       | '5%'    | '1/2W'   | 'DISCRETE' | 'RES CHIP 1 1/2W +-5%(2010)'                       | 'CHIP2010'     | ''          | ''            | '20140826'
 '1'          | '5%'      | '1/2W'   | '2010LF'  | 'EMPTY'  | 'CS-1007JJ01'(!)        = ''              | ''                 | 'CS-1007JJ01'           |'R2010'| '(SMR2010AW)'                  | '1'       | '5%'    | '1/2W'   | 'IO'       | 'RES CHIP 1 1/2W +-5%(2010)'                       | 'CHIP2010'     | ''          | ''            | '20140826'
 '28'         | '1%'      | '1/16W'  | '0402LF'  | 'CHIP'   | 'CS02802FB00'(!)        = ''              | ''                 | 'CS02802FB00'           |'R0402'| '(R0402-0201)'                 | '28'      | '1%'    | '1/16W'  | 'DISCRETE' | 'RES CHIP 28 1/16W +-1%(0402)'                     | 'CHIP0402'     | ''          | ''            | '20140826'
 '28'         | '1%'      | '1/16W'  | '0402LF'  | 'EMPTY'  | 'CS02802FB00'(!)        = ''              | ''                 | 'CS02802FB00'           |'R0402'| '(R0402-0201)'                 | '28'      | '1%'    | '1/16W'  | 'IO'       | 'RES CHIP 28 1/16W +-1%(0402)'                     | 'CHIP0402'     | ''          | ''            | '20140826'
 '3.32K'      | '1%'      | '1/16W'  | '0402LF'  | 'CHIP'   | 'CS23322FB20'(!)        = 'End of Design' | 'Comp-Approve'     | 'CS23322FB20'           |'R0402'| '(R0402-0201)'                 | '3.32K'   | '1%'    | '1/16W'  | 'DISCRETE' | 'RES CHIP 3.32K 1/16W +-1% (0402)'                 | 'CHIP0402'     | ''          | ''            | '20140826'
 '3.32K'      | '1%'      | '1/16W'  | '0402LF'  | 'EMPTY'  | 'CS23322FB20'(!)        = 'End of Design' | 'Comp-Approve'     | 'CS23322FB20'           |'R0402'| '(R0402-0201)'                 | '3.32K'   | '1%'    | '1/16W'  | 'IO'       | 'RES CHIP 3.32K 1/16W +-1% (0402)'                 | 'CHIP0402'     | ''          | ''            | '20140826'
 '200'        | '5%'      | '1W'     | '2512LF'  | 'CHIP'   | 'CS12008JR00'(!)        = ''              | ''                 | 'CS12008JR00'           |'R2512'| '(SMR2512AW)'                  | '200'     | '5%'    | '1W'     | 'DISCRETE' | 'RES CHIP 200 1W +-5%(2512)'                       | 'CHIP2512'     | ''          | ''            | '20140826'
 '200'        | '5%'      | '1W'     | '2512LF'  | 'EMPTY'  | 'CS12008JR00'(!)        = ''              | ''                 | 'CS12008JR00'           |'R2512'| '(SMR2512AW)'                  | '200'     | '5%'    | '1W'     | 'IO'       | 'RES CHIP 200 1W +-5%(2512)'                       | 'CHIP2512'     | ''          | ''            | '20140826'
 '300'        | '5%'      | '1/16W'  | '0402LF'  | 'CHIP'   | 'CS13002JB20'(!)        = 'End of Design' | 'Comp-Approve'     | 'CS13002JB20'           |'R0402'| '(R0402-0201)'                 | '300'     | '5%'    | '1/16W'  | 'DISCRETE' | 'RES CHIP 300 1/16W +-5% (0402)'                   | 'CHIP0402'     | ''          | ''            | '20140902'
 '300'        | '5%'      | '1/16W'  | '0402LF'  | 'EMPTY'  | 'CS13002JB20'(!)        = 'End of Design' | 'Comp-Approve'     | 'CS13002JB20'           |'R0402'| '(R0402-0201)'                 | '300'     | '5%'    | '1/16W'  | 'IO'       | 'RES CHIP 300 1/16W +-5% (0402)'                   | 'CHIP0402'     | ''          | ''            | '20140902'
 '10'         | '5%'      | '1/2W'   | '1210LF'  | 'CHIP'   | 'CS01007J300'(!)        = ''              | ''                 | 'CS01007J300'           |'R1210'| '(SMR1210AW)'                  | '10'      | '5%'    | '1/2W'   | 'DISCRETE' | 'RES CHIP 10 1/2W +-5%(1210)'                      | 'CHIP1210'     | ''          | ''            | '20140910'
 '10'         | '5%'      | '1/2W'   | '1210LF'  | 'EMPTY'  | 'CS01007J300'(!)        = ''              | ''                 | 'CS01007J300'           |'R1210'| '(SMR1210AW)'                  | '10'      | '5%'    | '1/2W'   | 'IO'       | 'RES CHIP 10 1/2W +-5%(1210)'                      | 'CHIP1210'     | ''          | ''            | '20140910'
 '2.1K'       | '0.1%'    | '1/16W'  | '0402LF'  | 'CHIP'   | 'CS22102BB00'(!)        = ''              | ''                 | 'CS22102BB00'           |'R0402'| '(R0402-0201)'                 | '2.1K'    | '0.1%'  | '1/16W'  | 'DISCRETE' | 'RES CHIP 2.1K 1/16W +/-0.1%(0402)'                | 'CHIP0402'     | ''          | ''            | '20140918'
 '2.1K'       | '0.1%'    | '1/16W'  | '0402LF'  | 'EMPTY'  | 'CS22102BB00'(!)        = ''              | ''                 | 'CS22102BB00'           |'R0402'| '(R0402-0201)'                 | '2.1K'    | '0.1%'  | '1/16W'  | 'IO'       | 'RES CHIP 2.1K 1/16W +/-0.1%(0402)'                | 'CHIP0402'     | ''          | ''            | '20140918'
 '1.2K'       | '1%'      | '1/16W'  | '0402LF'  | 'CHIP'   | 'CS21202FB13'(!)        = 'End of Design' | 'Comp-Approve'     | 'CS21202FB13'           |'R0402'| '(R0402-0201)'                 | '1.2K'    | '1%'    | '1/16W'  | 'DISCRETE' | 'RES CHIP 1.2K 1/16W+-1%(0402)'                    | 'CHIP0402'     | ''          | ''            | '20141003'
 '1.2K'       | '1%'      | '1/16W'  | '0402LF'  | 'EMPTY'  | 'CS21202FB13'(!)        = 'End of Design' | 'Comp-Approve'     | 'CS21202FB13'           |'R0402'| '(R0402-0201)'                 | '1.2K'    | '1%'    | '1/16W'  | 'IO'       | 'RES CHIP 1.2K 1/16W+-1%(0402)'                    | 'CHIP0402'     | ''          | ''            | '20141003'
 '10M'        | '1%'      | '1/10W'  | '0603LF'  | 'CHIP'   | 'CS61003F900'(!)        = ''              | ''                 | 'CS61003F900'           |'R0603'| '(SMR0603AW)'                  | '10M'     | '1%'    | '1/10W'  | 'DISCRETE' | 'RES CHIP 10M 1/10W +-1%(0603)'                    | 'CHIP0603'     | ''          | ''            | '20141008'
 '10M'        | '1%'      | '1/10W'  | '0603LF'  | 'EMPTY'  | 'CS61003F900'(!)        = ''              | ''                 | 'CS61003F900'           |'R0603'| '(SMR0603AW)'                  | '10M'     | '1%'    | '1/10W'  | 'IO'       | 'RES CHIP 10M 1/10W +-1%(0603)'                    | 'CHIP0603'     | ''          | ''            | '20141008'
 '200K'       | '0.1%'    | '1/10W'  | '0603LF'  | 'CHIP'   | 'CS42003B901'(!)        = ''              | ''                 | 'CS42003B901'           |'R0603'| '(SMR0603AW)'                  | '200K'    | '0.1%'  | '1/10W'  | 'DISCRETE' | 'RESISTOR CHIP 200K 1/10W +-0.1%(0603)'            | 'CHIP0603'     | ''          | ''            | '20141013'
 '200K'       | '0.1%'    | '1/10W'  | '0603LF'  | 'EMPTY'  | 'CS42003B901'(!)        = ''              | ''                 | 'CS42003B901'           |'R0603'| '(SMR0603AW)'                  | '200K'    | '0.1%'  | '1/10W'  | 'IO'       | 'RESISTOR CHIP 200K 1/10W +-0.1%(0603)'            | 'CHIP0603'     | ''          | ''            | '20141013'
 '0.01'       | '1%'      | '3W'     | '2512LF'  | 'CHIP'   | 'CS+100DFR00'(!)        = ''              | ''                 | 'CS+100DFR00'           |'R2512XA'| '(SMR2512AW)'                  | '0.01'    | '1%'    | '3W'     | 'DISCRETE' | 'RES CHIP 0.01 3W +-1%(2512)'                      | 'CHIP2512'     | ''          | ''            | '20141013'
 '0.01'       | '1%'      | '3W'     | '2512LF'  | 'EMPTY'  | 'CS+100DFR00'(!)        = ''              | ''                 | 'CS+100DFR00'           |'R2512XA'| '(SMR2512AW)'                  | '0.01'    | '1%'    | '3W'     | 'IO'       | 'RES CHIP 0.01 3W +-1%(2512)'                      | 'CHIP2512'     | ''          | ''            | '20141013'
 '113'        | '1%'      | '1/16W'  | '0402LF'  | 'CHIP'   | 'CS11132FB01'(!)        = 'End of Design' | 'Comp-Approve'     | 'CS11132FB01'           |'R0402'| '(R0402-0201)'                 | '113'     | '1%'    | '1/16W'  | 'DISCRETE' | 'RES CHIP 113 1/16W +-1%(0402)'                    | 'CHIP0402'     | ''          | ''            | '20141016'
 '113'        | '1%'      | '1/16W'  | '0402LF'  | 'EMPTY'  | 'CS11132FB01'(!)        = 'End of Design' | 'Comp-Approve'     | 'CS11132FB01'           |'R0402'| '(R0402-0201)'                 | '113'     | '1%'    | '1/16W'  | 'IO'       | 'RES CHIP 113 1/16W +-1%(0402)'                    | 'CHIP0402'     | ''          | ''            | '20141016'
 '249'        | '1%'      | '1/10W'  | '0603LF'  | 'CHIP'   | 'CS12493F935'(!)        = 'End of Design' | 'Comp-Approve'     | 'CS12493F935'           |'R0603'| '(SMR0603AW)'                  | '249'     | '1%'    | '1/10W'  | 'DISCRETE' | 'RES CHIP 249 1/10W +-1%(0603)EP'                  | 'CHIP0603'     | ''          | ''            | '20141016'
 '249'        | '1%'      | '1/10W'  | '0603LF'  | 'EMPTY'  | 'CS12493F935'(!)        = 'End of Design' | 'Comp-Approve'     | 'CS12493F935'           |'R0603'| '(SMR0603AW)'                  | '249'     | '1%'    | '1/10W'  | 'IO'       | 'RES CHIP 249 1/10W +-1%(0603)EP'                  | 'CHIP0603'     | ''          | ''            | '20141016'
 '249'        | '0.1%'    | '1/10W'  | '0603LF'  | 'CHIP'   | 'CS12493B900'(!)        = ''              | ''                 | 'CS12493B900'           |'R0603'| '(SMR0603AW)'                  | '249'     | '0.1%'  | '1/10W'  | 'DISCRETE' | 'RES CHIP 249 1/10W +-0.1%(0603)'                  | 'CHIP0603'     | ''          | ''            | '20141016'
 '249'        | '0.1%'    | '1/10W'  | '0603LF'  | 'EMPTY'  | 'CS12493B900'(!)        = ''              | ''                 | 'CS12493B900'           |'R0603'| '(SMR0603AW)'                  | '249'     | '0.1%'  | '1/10W'  | 'IO'       | 'RES CHIP 249 1/10W +-0.1%(0603)'                  | 'CHIP0603'     | ''          | ''            | '20141016'
 '0.008'      | '1%'      | '1/2W'   | '2010LF'  | 'CHIP'   | 'CS+0087FJ00'(!)        = ''              | ''                 | 'CS+0087FJ00'           |'R2010XC'| '(SMR2010AW)'                  | '0.008'   | '1%'    | '1/2W'   | 'DISCRETE' | 'RES CHIP 0.008 1/2W +-1%(2010)'                   | 'CHIP2010'     | ''          | ''            | '20141020'
 '0.008'      | '1%'      | '1/2W'   | '2010LF'  | 'EMPTY'  | 'CS+0087FJ00'(!)        = ''              | ''                 | 'CS+0087FJ00'           |'R2010XC'| '(SMR2010AW)'                  | '0.008'   | '1%'    | '1/2W'   | 'IO'       | 'RES CHIP 0.008 1/2W +-1%(2010)'                   | 'CHIP2010'     | ''          | ''            | '20141020'
 '0.005'      | '1%'      | '1W'     | '2512LF'  | 'CHIP'   | 'CS+0058F127'(!)        = ''              | ''                 | 'CS+0058F127'           |'R2512'| '(SMR2512AW)'                  | '0.005'   | '1%'    | '1W'     | 'DISCRETE' | 'RES CHIP 0.005 1W +-1%(2512)'                     | 'CHIP2512'     | ''          | ''            | '20141021'
 '0.005'      | '1%'      | '1W'     | '2512LF'  | 'EMPTY'  | 'CS+0058F127'(!)        = ''              | ''                 | 'CS+0058F127'           |'R2512'| '(SMR2512AW)'                  | '0.005'   | '1%'    | '1W'     | 'IO'       | 'RES CHIP 0.005 1W +-1%(2512)'                     | 'CHIP2512'     | ''          | ''            | '20141021'
 '36'         | '1%'      | '1/16W'  | '0402LF'  | 'CHIP'   | 'CS03602FB10'(!)        = 'End of Design' | 'Comp-Approve'     | 'CS03602FB10'           |'R0402'| '(R0402-0201)'                 | '36'      | '1%'    | '1/16W'  | 'DISCRETE' | 'RES CHIP 36 1/16W +-1%(0402)'                     | 'CHIP0402'     | ''          | ''            | '20141021'
 '36'         | '1%'      | '1/16W'  | '0402LF'  | 'EMPTY'  | 'CS03602FB10'(!)        = 'End of Design' | 'Comp-Approve'     | 'CS03602FB10'           |'R0402'| '(R0402-0201)'                 | '36'      | '1%'    | '1/16W'  | 'IO'       | 'RES CHIP 36 1/16W +-1%(0402)'                     | 'CHIP0402'     | ''          | ''            | '20141021'
 '100'        | '0.1%'    | '1/16W'  | '0402LF'  | 'CHIP'   | 'CS11002BB00'(!)        = ''              | ''                 | 'CS11002BB00'           |'R0402'| '(R0402-0201)'                 | '100'     | '0.1%'  | '1/16W'  | 'DISCRETE' | 'RES CHIP 100 1/16W +-0.1%(0402)'                  | 'CHIP0402'     | ''          | ''            | '20141021'
 '100'        | '0.1%'    | '1/16W'  | '0402LF'  | 'EMPTY'  | 'CS11002BB00'(!)        = ''              | ''                 | 'CS11002BB00'           |'R0402'| '(R0402-0201)'                 | '100'     | '0.1%'  | '1/16W'  | 'IO'       | 'RES CHIP 100 1/16W +-0.1%(0402)'                  | 'CHIP0402'     | ''          | ''            | '20141021'
 '0'          | '5%'      | '1/4W'   | '1206LF'  | 'CHIP'   | 'CS00006J248'(!)        = ''              | ''                 | 'CS00006J248'           |'R1206'| '(SMR1206AW)'                  | '0'       | '5%'    | '1/4W'   | 'DISCRETE' | 'RES CHIP 0 1/4W +-5%(1206)'                       | 'CHIP1206'     | ''          | ''            | '20141023'
 '0'          | '5%'      | '1/4W'   | '1206LF'  | 'EMPTY'  | 'CS00006J248'(!)        = ''              | ''                 | 'CS00006J248'           |'R1206'| '(SMR1206AW)'                  | '0'       | '5%'    | '1/4W'   | 'IO'       | 'RES CHIP 0 1/4W +-5%(1206)'                       | 'CHIP1206'     | ''          | ''            | '20141023'
 '7.5K'       | '0.1%'    | '1/16W'  | '0402LF'  | 'CHIP'   | 'CS27502BB00'(!)        = 'End of Design' | 'Comp-Approve'     | 'CS27502BB00'           |'R0402'| '(R0402-0201)'                 | '7.5K'    | '0.1%'  | '1/16W'  | 'DISCRETE' | 'RES CHIP 7.5K 1/16W +-0.1% (0402)'                | 'CHIP0402'     | ''          | ''            | '20141023'
 '7.5K'       | '0.1%'    | '1/16W'  | '0402LF'  | 'EMPTY'  | 'CS27502BB00'(!)        = 'End of Design' | 'Comp-Approve'     | 'CS27502BB00'           |'R0402'| '(R0402-0201)'                 | '7.5K'    | '0.1%'  | '1/16W'  | 'IO'       | 'RES CHIP 7.5K 1/16W +-0.1% (0402)'                | 'CHIP0402'     | ''          | ''            | '20141023'
 '3'          | '5%'      | '1W'     | '2512LF'  | 'CHIP'   | 'CS-3008JR00'(!)        = 'End of Design' | 'P/N Release'      | 'CS-3008JR00'           |'R2512'| '(SMR2512)'                    | '3'       | '5%'    | '1W'     | 'DISCRETE' | 'RESISTOR CHIP 3 1W +-5%(2512)'                    | 'CHIP2512'     | ''          | ''            | '20141028'
 '3'          | '5%'      | '1W'     | '2512LF'  | 'EMPTY'  | 'CS-3008JR00'(!)        = 'End of Design' | 'P/N Release'      | 'CS-3008JR00'           |'R2512'| '(SMR2512)'                    | '3'       | '5%'    | '1W'     | 'IO'       | 'RESISTOR CHIP 3 1W +-5%(2512)'                    | 'CHIP2512'     | ''          | ''            | '20141028'
 '8.25K'      | '0.1%'    | '1/16W'  | '0402LF'  | 'CHIP'   | 'CS28252BB00'(!)        = ''              | ''                 | 'CS28252BB00'           |'R0402'| '(R0402-0201)'                 | '8.25K'   | '0.1%'  | '1/16W'  | 'DISCRETE' | 'RES CHIP 8.25K 1/16W +-0.1%(0402)'                | 'CHIP0402'     | ''          | ''            | '20141029'
 '8.25K'      | '0.1%'    | '1/16W'  | '0402LF'  | 'EMPTY'  | 'CS28252BB00'(!)        = ''              | ''                 | 'CS28252BB00'           |'R0402'| '(R0402-0201)'                 | '8.25K'   | '0.1%'  | '1/16W'  | 'IO'       | 'RES CHIP 8.25K 1/16W +-0.1%(0402)'                | 'CHIP0402'     | ''          | ''            | '20141029'
 '28K'        | '0.1%'    | '1/16W'  | '0402LF'  | 'CHIP'   | 'CS32802BB00'(!)        = ''              | ''                 | 'CS32802BB00'           |'R0402'| '(R0402-0201)'                 | '28K'     | '0.1%'  | '1/16W'  | 'DISCRETE' | 'RES CHIP 28K 1/16W +-0.1%(0402)'                  | 'CHIP0402'     | ''          | ''            | '20141029'
 '28K'        | '0.1%'    | '1/16W'  | '0402LF'  | 'EMPTY'  | 'CS32802BB00'(!)        = ''              | ''                 | 'CS32802BB00'           |'R0402'| '(R0402-0201)'                 | '28K'     | '0.1%'  | '1/16W'  | 'IO'       | 'RES CHIP 28K 1/16W +-0.1%(0402)'                  | 'CHIP0402'     | ''          | ''            | '20141029'
 '22.9K'      | '0.1%'    | '1/16W'  | '0402LF'  | 'CHIP'   | 'CS32292BB00'(!)        = ''              | ''                 | 'CS32292BB00'           |'R0402'| '(R0402-0201)'                 | '22.9K'   | '0.1%'  | '1/16W'  | 'DISCRETE' | 'RES CHIP 22.9K 1/16W +-0.1%(0402)'                | 'CHIP0402'     | ''          | ''            | '20141029'
 '22.9K'      | '0.1%'    | '1/16W'  | '0402LF'  | 'EMPTY'  | 'CS32292BB00'(!)        = ''              | ''                 | 'CS32292BB00'           |'R0402'| '(R0402-0201)'                 | '22.9K'   | '0.1%'  | '1/16W'  | 'IO'       | 'RES CHIP 22.9K 1/16W +-0.1%(0402)'                | 'CHIP0402'     | ''          | ''            | '20141029'
 '22.1K'      | '0.1%'    | '1/16W'  | '0402LF'  | 'CHIP'   | 'CS32212BB00'(!)        = ''              | ''                 | 'CS32212BB00'           |'R0402'| '(R0402-0201)'                 | '22.1K'   | '0.1%'  | '1/16W'  | 'DISCRETE' | 'RES CHIP 22.1K 1/16W +-0.1%(0402)'                | 'CHIP0402'     | ''          | ''            | '20141029'
 '22.1K'      | '0.1%'    | '1/16W'  | '0402LF'  | 'EMPTY'  | 'CS32212BB00'(!)        = ''              | ''                 | 'CS32212BB00'           |'R0402'| '(R0402-0201)'                 | '22.1K'   | '0.1%'  | '1/16W'  | 'IO'       | 'RES CHIP 22.1K 1/16W +-0.1%(0402)'                | 'CHIP0402'     | ''          | ''            | '20141029'
 '12K'        | '0.1%'    | '1/16W'  | '0402LF'  | 'CHIP'   | 'CS31202BB00'(!)        = ''              | ''                 | 'CS31202BB00'           |'R0402'| '(R0402-0201)'                 | '12K'     | '0.1%'  | '1/16W'  | 'DISCRETE' | 'RES CHIP 12K 1/16W +-0.1%(0402)'                  | 'CHIP0402'     | ''          | ''            | '20141029'
 '12K'        | '0.1%'    | '1/16W'  | '0402LF'  | 'EMPTY'  | 'CS31202BB00'(!)        = ''              | ''                 | 'CS31202BB00'           |'R0402'| '(R0402-0201)'                 | '12K'     | '0.1%'  | '1/16W'  | 'IO'       | 'RES CHIP 12K 1/16W +-0.1%(0402)'                  | 'CHIP0402'     | ''          | ''            | '20141029'
 '1.87K'      | '0.1%'    | '1/16W'  | '0402LF'  | 'CHIP'   | 'CS21872B100'(!)        = ''              | ''                 | 'CS21872B100'           |'R0402'| '(R0402-0201)'                 | '1.87K'   | '0.1%'  | '1/16W'  | 'DISCRETE' | 'RES CHIP 1.87K(1/16W,+-0.1%,0402)'                | 'CHIP0402'     | ''          | ''            | '20141111'
 '1.87K'      | '0.1%'    | '1/16W'  | '0402LF'  | 'EMPTY'  | 'CS21872B100'(!)        = ''              | ''                 | 'CS21872B100'           |'R0402'| '(R0402-0201)'                 | '1.87K'   | '0.1%'  | '1/16W'  | 'IO'       | 'RES CHIP 1.87K(1/16W,+-0.1%,0402)'                | 'CHIP0402'     | ''          | ''            | '20141111'
 '10.4K'      | '0.1%'    | '1/16W'  | '0402LF'  | 'CHIP'   | 'CS31042B100'(!)        = ''              | ''                 | 'CS31042B100'           |'R0402'| '(R0402-0201)'                 | '10.4K'   | '0.1%'  | '1/16W'  | 'DISCRETE' | 'RES CHIP 10.4K(1/16W,+-0.1%,0402)'                | 'CHIP0402'     | ''          | ''            | '20141111'
 '10.4K'      | '0.1%'    | '1/16W'  | '0402LF'  | 'EMPTY'  | 'CS31042B100'(!)        = ''              | ''                 | 'CS31042B100'           |'R0402'| '(R0402-0201)'                 | '10.4K'   | '0.1%'  | '1/16W'  | 'IO'       | 'RES CHIP 10.4K(1/16W,+-0.1%,0402)'                | 'CHIP0402'     | ''          | ''            | '20141111'
 '12.7K'      | '0.1%'    | '1/16W'  | '0402LF'  | 'CHIP'   | 'CS31272B100'(!)        = ''              | ''                 | 'CS31272B100'           |'R0402'| '(R0402-0201)'                 | '12.7K'   | '0.1%'  | '1/16W'  | 'DISCRETE' | 'RES CHIP 12.7K(1/16W,+-0.1%,0402)'                | 'CHIP0402'     | ''          | ''            | '20141111'
 '12.7K'      | '0.1%'    | '1/16W'  | '0402LF'  | 'EMPTY'  | 'CS31272B100'(!)        = ''              | ''                 | 'CS31272B100'           |'R0402'| '(R0402-0201)'                 | '12.7K'   | '0.1%'  | '1/16W'  | 'IO'       | 'RES CHIP 12.7K(1/16W,+-0.1%,0402)'                | 'CHIP0402'     | ''          | ''            | '20141111'
 '47K'        | '0.1%'    | '1/16W'  | '0402LF'  | 'CHIP'   | 'CS34702B100'(!)        = ''              | ''                 | 'CS34702B100'           |'R0402'| '(R0402-0201)'                 | '47K'     | '0.1%'  | '1/16W'  | 'DISCRETE' | 'RES CHIP 47K(1/16W,+-0.1%,0402)'                  | 'CHIP0402'     | ''          | ''            | '20141111'
 '47K'        | '0.1%'    | '1/16W'  | '0402LF'  | 'EMPTY'  | 'CS34702B100'(!)        = ''              | ''                 | 'CS34702B100'           |'R0402'| '(R0402-0201)'                 | '47K'     | '0.1%'  | '1/16W'  | 'IO'       | 'RES CHIP 47K(1/16W,+-0.1%,0402)'                  | 'CHIP0402'     | ''          | ''            | '20141111'
 '115K'       | '0.1%'    | '1/16W'  | '0402LF'  | 'CHIP'   | 'CS41152B100'(!)        = ''              | ''                 | 'CS41152B100'           |'R0402'| '(R0402-0201)'                 | '115K'    | '0.1%'  | '1/16W'  | 'DISCRETE' | 'RES CHIP 115K(1/16W,+-0.1%,0402)'                 | 'CHIP0402'     | ''          | ''            | '20141111'
 '115K'       | '0.1%'    | '1/16W'  | '0402LF'  | 'EMPTY'  | 'CS41152B100'(!)        = ''              | ''                 | 'CS41152B100'           |'R0402'| '(R0402-0201)'                 | '115K'    | '0.1%'  | '1/16W'  | 'IO'       | 'RES CHIP 115K(1/16W,+-0.1%,0402)'                 | 'CHIP0402'     | ''          | ''            | '20141111'
 '1.3K'       | '1%'      | '1/8W'   | '0805LF'  | 'CHIP'   | 'CS21304FA00'(!)        = ''              | ''                 | 'CS21304FA00'           |'R0805'| '(SMR0805AW)'                  | '1.3K'    | '1%'    | '1/8W'   | 'DISCRETE' | 'RES CHIP 1.3K 1/8W +-1%(0805)'                    | 'CHIP0805'     | ''          | ''            | '20141128'
 '1.3K'       | '1%'      | '1/8W'   | '0805LF'  | 'EMPTY'  | 'CS21304FA00'(!)        = ''              | ''                 | 'CS21304FA00'           |'R0805'| '(SMR0805AW)'                  | '1.3K'    | '1%'    | '1/8W'   | 'IO'       | 'RES CHIP 1.3K 1/8W +-1%(0805)'                    | 'CHIP0805'     | ''          | ''            | '20141128'
 '249'        | '0.1%'    | '1/16W'  | '0402LF'  | 'CHIP'   | 'CS12492BB00'(!)        = ''              | ''                 | 'CS12492BB00'           |'R0402'| '(R0402-0201)'                 | '249'     | '0.1%'  | '1/16W'  | 'DISCRETE' | 'RES CHIP 249 1/16W +-0.1%(0402)'                  | 'CHIP0402'     | ''          | ''            | '20150106'
 '249'        | '0.1%'    | '1/16W'  | '0402LF'  | 'EMPTY'  | 'CS12492BB00'(!)        = ''              | ''                 | 'CS12492BB00'           |'R0402'| '(R0402-0201)'                 | '249'     | '0.1%'  | '1/16W'  | 'IO'       | 'RES CHIP 249 1/16W +-0.1%(0402)'                  | 'CHIP0402'     | ''          | ''            | '20150106'
 '0.001'      | '1%'      | '3W'     | '2512LF'  | 'CHIP'   | 'CS0000DFR01'(!)        = 'Potential'     | 'End of Life'      | 'CS0000DFR01'           |'R2512XG_EOL'| '(SMR2512AW)'                  | '0.001'   | '1%'    | '3W'     | 'DISCRETE' | 'RES CHIP 0.001 3W(+-1%,2512)'                     | 'CHIP2512'     | ''          | ''            | '20150107'
 '0.001'      | '1%'      | '3W'     | '2512LF'  | 'EMPTY'  | 'CS0000DFR01'(!)        = 'Potential'     | 'End of Life'      | 'CS0000DFR01'           |'R2512XG_EOL'| '(SMR2512AW)'                  | '0.001'   | '1%'    | '3W'     | 'IO'       | 'RES CHIP 0.001 3W(+-1%,2512)'                     | 'CHIP2512'     | ''          | ''            | '20150107'
 '45.3'       | '1%'      | '1/16W'  | '0402LF'  | 'CHIP'   | 'CS04532FB12'(!)        = 'End of Design' | 'Comp-Approve'     | 'CS04532FB12'           |'R0402'| '(R0402-0201)'                 | '45.3'    | '1%'    | '1/16W'  | 'DISCRETE' | 'RES CHIP 45.3 1/16W +-1%( 0402)'                  | 'CHIP0402'     | ''          | ''            | '20150114'
 '45.3'       | '1%'      | '1/16W'  | '0402LF'  | 'EMPTY'  | 'CS04532FB12'(!)        = 'End of Design' | 'Comp-Approve'     | 'CS04532FB12'           |'R0402'| '(R0402-0201)'                 | '45.3'    | '1%'    | '1/16W'  | 'IO'       | 'RES CHIP 45.3 1/16W +-1%( 0402)'                  | 'CHIP0402'     | ''          | ''            | '20150114'
 '270K'       | '1%'      | '1/16W'  | '0402LF'  | 'CHIP'   | 'CS42702FB00'(!)        = ''              | ''                 | 'CS42702FB00'           |'R0402'| '(R0402-0201)'                 | '270K'    | '1%'    | '1/16W'  | 'DISCRETE' | 'RES CHIP 270K 1/16W +-1%(0402)'                   | 'CHIP0402'     | ''          | ''            | '20150127'
 '270K'       | '1%'      | '1/16W'  | '0402LF'  | 'EMPTY'  | 'CS42702FB00'(!)        = ''              | ''                 | 'CS42702FB00'           |'R0402'| '(R0402-0201)'                 | '270K'    | '1%'    | '1/16W'  | 'IO'       | 'RES CHIP 270K 1/16W +-1%(0402)'                   | 'CHIP0402'     | ''          | ''            | '20150127'
 '36'         | '5%'      | '1/16W'  | '0402LF'  | 'CHIP'   | 'CS03602JB00'(!)        = 'End of Design' | 'Comp-Approve'     | 'CS03602JB00'           |'R0402'| '(R0402-0201)'                 | '36'      | '5%'    | '1/16W'  | 'DISCRETE' | 'RES CHIP 36 1/16W +-5%(0402)'                     | 'CHIP0402'     | ''          | ''            | '20150130'
 '36'         | '5%'      | '1/16W'  | '0402LF'  | 'EMPTY'  | 'CS03602JB00'(!)        = 'End of Design' | 'Comp-Approve'     | 'CS03602JB00'           |'R0402'| '(R0402-0201)'                 | '36'      | '5%'    | '1/16W'  | 'IO'       | 'RES CHIP 36 1/16W +-5%(0402)'                     | 'CHIP0402'     | ''          | ''            | '20150130'
 '0.62'       | '5%'      | '15W'    | 'THLF'    | 'CHIP'   | 'CL+620AJ000'(!)        = ''              | ''                 | 'CL+620AJ000'           |'R18949D'| '(R18949D)'                    | '0.62'    | '5%'    | '15W'    | 'DISCRETE' | 'RESISTOR CEMENT 0.62 15W +-5%(SQP)'               | 'R18949D'      | ''          | ''            | '20150130'
 '0.62'       | '5%'      | '15W'    | 'THLF'    | 'EMPTY'  | 'CL+620AJ000'(!)        = ''              | ''                 | 'CL+620AJ000'           |'R18949D'| '(R18949D)'                    | '0.62'    | '5%'    | '15W'    | 'IO'       | 'RESISTOR CEMENT 0.62 15W +-5%(SQP)'               | 'R18949D'      | ''          | ''            | '20150130'
 '0.39'       | '5%'      | '15W'    | 'THLF'    | 'CHIP'   | 'CL+390AJ000'(!)        = ''              | ''                 | 'CL+390AJ000'           |'R18949D'| '(R18949D)'                    | '0.39'    | '5%'    | '15W'    | 'DISCRETE' | 'RESISTOR CEMENT 0.39 15W +-5%(SQP)'               | 'R18949D'      | ''          | ''            | '20150130'
 '0.39'       | '5%'      | '15W'    | 'THLF'    | 'EMPTY'  | 'CL+390AJ000'(!)        = ''              | ''                 | 'CL+390AJ000'           |'R18949D'| '(R18949D)'                    | '0.39'    | '5%'    | '15W'    | 'IO'       | 'RESISTOR CEMENT 0.39 15W +-5%(SQP)'               | 'R18949D'      | ''          | ''            | '20150130'
 '3.16K'      | '1%'      | '1/10W'  | '0603LF'  | 'CHIP'   | 'CS23163F901'(!)        = ''              | ''                 | 'CS23163F901'           |'R0603'| '(SMR0603AW)'                  | '3.16K'   | '1%'    | '1/10W'  | 'DISCRETE' | 'RES CHIP 3.16K 1/10W +-1%(0603)'                  | 'CHIP0603'     | ''          | ''            | '20150203'
 '3.16K'      | '1%'      | '1/10W'  | '0603LF'  | 'EMPTY'  | 'CS23163F901'(!)        = ''              | ''                 | 'CS23163F901'           |'R0603'| '(SMR0603AW)'                  | '3.16K'   | '1%'    | '1/10W'  | 'IO'       | 'RES CHIP 3.16K 1/10W +-1%(0603)'                  | 'CHIP0603'     | ''          | ''            | '20150203'
 '866'        | '1%'      | '1/16W'  | '0402LF'  | 'CHIP'   | 'CS18662FB00'(!)        = 'End of Design' | 'Comp-Approve'     | 'CS18662FB00'           |'R0402'| '(R0402-0201)'                 | '866'     | '1%'    | '1/16W'  | 'DISCRETE' | 'RES CHIP 866 1/16W +-1%(0402)'                    | 'CHIP0402'     | ''          | ''            | '20150203'
 '866'        | '1%'      | '1/16W'  | '0402LF'  | 'EMPTY'  | 'CS18662FB00'(!)        = 'End of Design' | 'Comp-Approve'     | 'CS18662FB00'           |'R0402'| '(R0402-0201)'                 | '866'     | '1%'    | '1/16W'  | 'IO'       | 'RES CHIP 866 1/16W +-1%(0402)'                    | 'CHIP0402'     | ''          | ''            | '20150203'
 '45.3K'      | '1%'      | '1/8W'   | '0805LF'  | 'CHIP'   | 'CS34534FA00'(!)        = ''              | ''                 | 'CS34534FA00'           |'R0805'| '(SMR0805AW)'                  | '45.3K'   | '1%'    | '1/8W'   | 'DISCRETE' | 'RES CHIP 45.3K 1/8W +-1%(0805)'                   | 'CHIP0805'     | ''          | ''            | '20150210'
 '45.3K'      | '1%'      | '1/8W'   | '0805LF'  | 'EMPTY'  | 'CS34534FA00'(!)        = ''              | ''                 | 'CS34534FA00'           |'R0805'| '(SMR0805AW)'                  | '45.3K'   | '1%'    | '1/8W'   | 'IO'       | 'RES CHIP 45.3K 1/8W +-1%(0805)'                   | 'CHIP0805'     | ''          | ''            | '20150210'
 '220K'       | '1%'      | '1/16W'  | '0402LF'  | 'CHIP'   | 'CS42202FB10'(!)        = 'End of Design' | 'Comp-Approve'     | 'CS42202FB10'           |'R0402'| '(R0402-0201)'                 | '220K'    | '1%'    | '1/16W'  | 'DISCRETE' | 'RES CHIP 220K 1/16W +-1%(0402)'                   | 'CHIP0402'     | ''          | ''            | '20150302'
 '220K'       | '1%'      | '1/16W'  | '0402LF'  | 'EMPTY'  | 'CS42202FB10'(!)        = 'End of Design' | 'Comp-Approve'     | 'CS42202FB10'           |'R0402'| '(R0402-0201)'                 | '220K'    | '1%'    | '1/16W'  | 'IO'       | 'RES CHIP 220K 1/16W +-1%(0402)'                   | 'CHIP0402'     | ''          | ''            | '20150302'
 '3.16K'      | '1%'      | '1/10W'  | '0603LF'  | 'CHIP'   | 'CS23163F919'(!)        = ''              | ''                 | 'CS23163F919'           |'R0603'| '(SMR0603AW)'                  | '3.16K'   | '1%'    | '1/10W'  | 'DISCRETE' | 'RESISTER CHIP 3.16K 1/10W +-1%(0603)EP'           | 'CHIP0603'     | ''          | ''            | '20150302'
 '3.16K'      | '1%'      | '1/10W'  | '0603LF'  | 'EMPTY'  | 'CS23163F919'(!)        = ''              | ''                 | 'CS23163F919'           |'R0603'| '(SMR0603AW)'                  | '3.16K'   | '1%'    | '1/10W'  | 'IO'       | 'RESISTER CHIP 3.16K 1/10W +-1%(0603)EP'           | 'CHIP0603'     | ''          | ''            | '20150302'
 '3.9K'       | '5%'      | '1/16W'  | '0402LF'  | 'CHIP'   | 'CS23902JB00'(!)        = 'End of Design' | 'Comp-Approve'     | 'CS23902JB00'           |'R0402'| '(R0402-0201)'                 | '3.9K'    | '5%'    | '1/16W'  | 'DISCRETE' | 'RES CHIP 3.9K 1/16W +-5%(0402)'                   | 'CHIP0402'     | ''          | ''            | '20150303'
 '3.9K'       | '5%'      | '1/16W'  | '0402LF'  | 'EMPTY'  | 'CS23902JB00'(!)        = 'End of Design' | 'Comp-Approve'     | 'CS23902JB00'           |'R0402'| '(R0402-0201)'                 | '3.9K'    | '5%'    | '1/16W'  | 'IO'       | 'RES CHIP 3.9K 1/16W +-5%(0402)'                   | 'CHIP0402'     | ''          | ''            | '20150303'
 '68K'        | '1%'      | '1/16W'  | '0402LF'  | 'CHIP'   | 'CS36802FB00'(!)        = 'End of Design' | 'Comp-Approve'     | 'CS36802FB00'           |'R0402'| '(R0402-0201)'                 | '68K'     | '1%'    | '1/16W'  | 'DISCRETE' | 'RES CHIP 68K 1/16W +-1%(0402)'                    | 'CHIP0402'     | ''          | ''            | '20150303'
 '68K'        | '1%'      | '1/16W'  | '0402LF'  | 'EMPTY'  | 'CS36802FB00'(!)        = 'End of Design' | 'Comp-Approve'     | 'CS36802FB00'           |'R0402'| '(R0402-0201)'                 | '68K'     | '1%'    | '1/16W'  | 'IO'       | 'RES CHIP 68K 1/16W +-1%(0402)'                    | 'CHIP0402'     | ''          | ''            | '20150303'
 '787'        | '1%'      | '1/16W'  | '0402LF'  | 'CHIP'   | 'CS17872FB00'(!)        = 'End of Design' | 'Comp-Approve'     | 'CS17872FB00'           |'R0402'| '(R0402-0201)'                 | '787'     | '1%'    | '1/16W'  | 'DISCRETE' | 'RES CHIP 787 1/16W +-1%(0402)'                    | 'CHIP0402 '    | ''          | ''            | '20150310'
 '787'        | '1%'      | '1/16W'  | '0402LF'  | 'EMPTY'  | 'CS17872FB00'(!)        = 'End of Design' | 'Comp-Approve'     | 'CS17872FB00'           |'R0402'| '(R0402-0201)'                 | '787'     | '1%'    | '1/16W'  | 'IO'       | 'RES CHIP 787 1/16W +-1%(0402)'                    | 'CHIP0402 '    | ''          | ''            | '20150310'
 '787'        | '1%'      | '1/10W'  | '0603LF'  | 'CHIP'   | 'CS17873F901'(!)        = ''              | ''                 | 'CS17873F901'           |'R0603'| '(SMR0603AW)'                  | '787'     | '1%'    | '1/10W'  | 'DISCRETE' | 'RES CHIP 787 1/10W +-1%(0603)'                    | 'CHIP0603'     | ''          | ''            | '20150312'
 '787'        | '1%'      | '1/10W'  | '0603LF'  | 'EMPTY'  | 'CS17873F901'(!)        = ''              | ''                 | 'CS17873F901'           |'R0603'| '(SMR0603AW)'                  | '787'     | '1%'    | '1/10W'  | 'IO'       | 'RES CHIP 787 1/10W +-1%(0603)'                    | 'CHIP0603'     | ''          | ''            | '20150312'
 '866K'       | '1%'      | '1/16W'  | '0402LF'  | 'CHIP'   | 'CS48662FB00'(!)        = 'End of Design' | 'Comp-Approve'     | 'CS48662FB00'           |'R0402'| '(R0402-0201)'                 | '866K'    | '1%'    | '1/16W'  | 'DISCRETE' | 'RES CHIP 866K 1/16W +-1%(0402)'                   | 'CHIP0402'     | ''          | ''            | '20150316'
 '866K'       | '1%'      | '1/16W'  | '0402LF'  | 'EMPTY'  | 'CS48662FB00'(!)        = 'End of Design' | 'Comp-Approve'     | 'CS48662FB00'           |'R0402'| '(R0402-0201)'                 | '866K'    | '1%'    | '1/16W'  | 'IO'       | 'RES CHIP 866K 1/16W +-1%(0402)'                   | 'CHIP0402'     | ''          | ''            | '20150316'
 '2.94K'      | '0.1%'    | '1/16W'  | '0402LF'  | 'CHIP'   | 'CS22942BB00'(!)        = ''              | ''                 | 'CS22942BB00'           |'R0402'| '(R0402-0201)'                 | '2.94K'   | '0.1%'  | '1/16W'  | 'DISCRETE' | 'RES CHIP 2.94K 1/16W +-0.1%(0402)'                | 'CHIP0402 '    | ''          | ''            | '20150324'
 '2.94K'      | '0.1%'    | '1/16W'  | '0402LF'  | 'EMPTY'  | 'CS22942BB00'(!)        = ''              | ''                 | 'CS22942BB00'           |'R0402'| '(R0402-0201)'                 | '2.94K'   | '0.1%'  | '1/16W'  | 'IO'       | 'RES CHIP 2.94K 1/16W +-0.1%(0402)'                | 'CHIP0402 '    | ''          | ''            | '20150324'
 '1.24K'      | '0.1%'    | '1/10W'  | '0603LF'  | 'CHIP'   | 'CS21243B900'(!)        = ''              | ''                 | 'CS21243B900'           |'R0603'| '(SMR0603AW)'                  | '1.24K'   | '0.1%'  | '1/10W'  | 'DISCRETE' | 'RES CHIP 1.24K 1/10W +-0.1%(0603)'                | 'CHIP0603'     | ''          | ''            | '20150324'
 '1.24K'      | '0.1%'    | '1/10W'  | '0603LF'  | 'EMPTY'  | 'CS21243B900'(!)        = ''              | ''                 | 'CS21243B900'           |'R0603'| '(SMR0603AW)'                  | '1.24K'   | '0.1%'  | '1/10W'  | 'IO'       | 'RES CHIP 1.24K 1/10W +-0.1%(0603)'                | 'CHIP0603'     | ''          | ''            | '20150324'
 '3.32K'      | '0.1%'    | '1/10W'  | '0603LF'  | 'CHIP'   | 'CS23323B900'(!)        = ''              | ''                 | 'CS23323B900'           |'R0603'| '(SMR0603AW)'                  | '3.32K'   | '0.1%'  | '1/10W'  | 'DISCRETE' | 'RES CHIP 3.32K 1/10W +-0.1%(0603)'                | 'CHIP0603'     | ''          | ''            | '20150324'
 '3.32K'      | '0.1%'    | '1/10W'  | '0603LF'  | 'EMPTY'  | 'CS23323B900'(!)        = ''              | ''                 | 'CS23323B900'           |'R0603'| '(SMR0603AW)'                  | '3.32K'   | '0.1%'  | '1/10W'  | 'IO'       | 'RES CHIP 3.32K 1/10W +-0.1%(0603)'                | 'CHIP0603'     | ''          | ''            | '20150324'
 '0.51'       | '1%'      | '1/4W'   | '0805LF'  | 'CHIP'   | 'CS+5106FA00'(!)        = ''              | ''                 | 'CS+5106FA00'           |'R0805'| '(SMR0805AW)'                  | '0.51'    | '1%'    | '1/4W'   | 'DISCRETE' | 'RES CHIP 0.51 1/4W.+-1%(0805)'                    | 'CHIP0805'     | ''          | ''            | '20150327'
 '0.51'       | '1%'      | '1/4W'   | '0805LF'  | 'EMPTY'  | 'CS+5106FA00'(!)        = ''              | ''                 | 'CS+5106FA00'           |'R0805'| '(SMR0805AW)'                  | '0.51'    | '1%'    | '1/4W'   | 'IO'       | 'RES CHIP 0.51 1/4W.+-1%(0805)'                    | 'CHIP0805'     | ''          | ''            | '20150327'
 '4.53K'      | '1%'      | '1/10W'  | '0603LF'  | 'CHIP'   | 'CS24533F921'(!)        = ''              | ''                 | 'CS24533F921'           |'R0603'| '(SMR0603AW)'                  | '4.53K'   | '1%'    | '1/10W'  | 'DISCRETE' | 'RESISTOR CHIP 4.53K 1/10W +-1%(0603)'             | 'CHIP0603'     | ''          | ''            | '20150410'
 '4.53K'      | '1%'      | '1/10W'  | '0603LF'  | 'EMPTY'  | 'CS24533F921'(!)        = ''              | ''                 | 'CS24533F921'           |'R0603'| '(SMR0603AW)'                  | '4.53K'   | '1%'    | '1/10W'  | 'IO'       | 'RESISTOR CHIP 4.53K 1/10W +-1%(0603)'             | 'CHIP0603'     | ''          | ''            | '20150410'
 '549'        | '1%'      | '1/16W'  | '0402LF'  | 'CHIP'   | 'CS15492FB29'(!)        = 'End of Design' | 'Comp-Release Qty' | 'CS15492FB29'           |'R0402'| '(R0402-0201)'                 | '549'     | '1%'    | '1/16W'  | 'DISCRETE' | 'RES CHIP 549 1/16W +-1%(0402)'                    | 'CHIP0402 '    | ''          | ''            | '20150328'
 '549'        | '1%'      | '1/16W'  | '0402LF'  | 'EMPTY'  | 'CS15492FB29'(!)        = 'End of Design' | 'Comp-Release Qty' | 'CS15492FB29'           |'R0402'| '(R0402-0201)'                 | '549'     | '1%'    | '1/16W'  | 'IO'       | 'RES CHIP 549 1/16W +-1%(0402)'                    | 'CHIP0402 '    | ''          | ''            | '20150328'
 '100'        | '1%'      | '2W'     | '2512LF'  | 'CHIP'   | 'CS1100AFR00'(!)        = ''              | ''                 | 'CS1100AFR00'           |'R2512'| '(SMR2512AW)'                  | '100'     | '1%'    | '2W'     | 'DISCRETE' | 'RES CHIP 100 2W +-1%(2512)'                       | 'CHIP2512 '    | ''          | ''            | '20150511'
 '100'        | '1%'      | '2W'     | '2512LF'  | 'EMPTY'  | 'CS1100AFR00'(!)        = ''              | ''                 | 'CS1100AFR00'           |'R2512'| '(SMR2512AW)'                  | '100'     | '1%'    | '2W'     | 'IO'       | 'RES CHIP 100 2W +-1%(2512)'                       | 'CHIP2512 '    | ''          | ''            | '20150511'
 '10K'        | '1%'      | '1/20W'  | '0201LF'  | 'CHIP'   | 'CS31001FE14'(!)        = ''              | ''                 | 'CS31001FE14'           |'R0201'| '(SMR0201AW)'                  | '10K'     | '1%'    | '1/20W'  | 'DISCRETE' | 'RES CHIP 10K(1/20W,+-1%,0201)'                    | 'CHIP0201'     | ''          | ''            | '20150511'
 '10K'        | '1%'      | '1/20W'  | '0201LF'  | 'EMPTY'  | 'CS31001FE14'(!)        = ''              | ''                 | 'CS31001FE14'           |'R0201'| '(SMR0201AW)'                  | '10K'     | '1%'    | '1/20W'  | 'IO'       | 'RES CHIP 10K(1/20W,+-1%,0201)'                    | 'CHIP0201'     | ''          | ''            | '20150511'
 '0.005'      | '1%'      | '1/4W'   | '0603LF'  | 'CHIP'   | 'CS+0056F900'(!)        = 'End of Design' | 'Comp-Approve'     | 'CS+0056F900'           |'R0603_H38'| '(SMR0603AW)'                  | '0.005'   | '1%'    | '1/4W'   | 'DISCRETE' | 'RES CHIP 0.005 1/4W +-1%(0603)'                   | 'CHIP0603'     | ''          | ''            | '20150518'
 '0.005'      | '1%'      | '1/4W'   | '0603LF'  | 'EMPTY'  | 'CS+0056F900'(!)        = 'End of Design' | 'Comp-Approve'     | 'CS+0056F900'           |'R0603_H38'| '(SMR0603AW)'                  | '0.005'   | '1%'    | '1/4W'   | 'IO'       | 'RES CHIP 0.005 1/4W +-1%(0603)'                   | 'CHIP0603'     | ''          | ''            | '20150518'
 '69.8'       | '1%'      | '1/16W'  | '0402LF'  | 'CHIP'   | 'CS06982FB00'(!)        = 'End of Design' | 'Comp-Approve'     | 'CS06982FB00'           |'R0402'| '(R0402-0201)'                 | '69.8'    | '1%'    | '1/16W'  | 'DISCRETE' | 'RES CHIP 69.8 1/16W +-1% (0402)'                  | 'CHIP0402 '    | ''          | ''            | '20150522'
 '69.8'       | '1%'      | '1/16W'  | '0402LF'  | 'EMPTY'  | 'CS06982FB00'(!)        = 'End of Design' | 'Comp-Approve'     | 'CS06982FB00'           |'R0402'| '(R0402-0201)'                 | '69.8'    | '1%'    | '1/16W'  | 'IO'       | 'RES CHIP 69.8 1/16W +-1% (0402)'                  | 'CHIP0402 '    | ''          | ''            | '20150522'
 '5.6'        | '1%'      | '1/10W'  | '0603LF'  | 'CHIP'   | 'CS-5603F914'(!)        = 'End of Design' | 'Comp-Approve'     | 'CS-5603F914'           |'R0603'| '(SMR0603AW)'                  | '5.6'     | '1%'    | '1/10W'  | 'DISCRETE' | 'RES CHIP 5.6 1/10W +-1%(0603)'                    | 'CHIP0603'     | ''          | ''            | '20150610'
 '5.6'        | '1%'      | '1/10W'  | '0603LF'  | 'EMPTY'  | 'CS-5603F914'(!)        = 'End of Design' | 'Comp-Approve'     | 'CS-5603F914'           |'R0603'| '(SMR0603AW)'                  | '5.6'     | '1%'    | '1/10W'  | 'IO'       | 'RES CHIP 5.6 1/10W +-1%(0603)'                    | 'CHIP0603'     | ''          | ''            | '20150610'
 '49.9'       | '0.1%'    | '1/16W'  | '0402LF'  | 'CHIP'   | 'CS04992BB01'(!)        = ''              | ''                 | 'CS04992BB01'           |'R0402'| '(R0402-0201)'                 | '49.9'    | '0.1%'  | '1/16W'  | 'DISCRETE' | 'RES CHIP 49.9 1/16W +-0.1%(0402)'                 | 'CHIP0402'     | ''          | ''            | '20150611'
 '49.9'       | '0.1%'    | '1/16W'  | '0402LF'  | 'EMPTY'  | 'CS04992BB01'(!)        = ''              | ''                 | 'CS04992BB01'           |'R0402'| '(R0402-0201)'                 | '49.9'    | '0.1%'  | '1/16W'  | 'IO'       | 'RES CHIP 49.9 1/16W +-0.1%(0402)'                 | 'CHIP0402'     | ''          | ''            | '20150611'
 '59'         | '1%'      | '1/16W'  | '0402LF'  | 'CHIP'   | 'CS05902FB00'(!)        = 'End of Design' | 'Comp-Approve'     | 'CS05902FB00'           |'R0402'| '(R0402-0201)'                 | '59'      | '1%'    | '1/16W'  | 'DISCRETE' | 'RES CHIP 59 1/16W +-1%(0402)'                     | 'CHIP0402'     | ''          | ''            | '20150611'
 '59'         | '1%'      | '1/16W'  | '0402LF'  | 'EMPTY'  | 'CS05902FB00'(!)        = 'End of Design' | 'Comp-Approve'     | 'CS05902FB00'           |'R0402'| '(R0402-0201)'                 | '59'      | '1%'    | '1/16W'  | 'IO'       | 'RES CHIP 59 1/16W +-1%(0402)'                     | 'CHIP0402'     | ''          | ''            | '20150611'
 '475K'       | '1%'      | '1/16W'  | '0402LF'  | 'CHIP'   | 'CS44755FB04'(!)        = ''              | ''                 | 'CS44755FB04'           |'R0402'| '(R0402-0201)'                 | '475K'    | '1%'    | '1/16W'  | 'DISCRETE' | 'RES CHIP 475K 1/16W +-1%(0402)'                   | 'CHIP0402'     | ''          | ''            | '20150612'
 '475K'       | '1%'      | '1/16W'  | '0402LF'  | 'EMPTY'  | 'CS44755FB04'(!)        = ''              | ''                 | 'CS44755FB04'           |'R0402'| '(R0402-0201)'                 | '475K'    | '1%'    | '1/16W'  | 'IO'       | 'RES CHIP 475K 1/16W +-1%(0402)'                   | 'CHIP0402'     | ''          | ''            | '20150612'
 '127K'       | '1%'      | '1/16W'  | '0402LF'  | 'CHIP'   | 'CS41272FB19'(!)        = 'End of Design' | 'Comp-Approve'     | 'CS41272FB19'           |'R0402'| '(R0402-0201)'                 | '127K'    | '1%'    | '1/16W'  | 'DISCRETE' | 'RES CHIP 127K 1/16W +-1%(0402)'                   | 'CHIP0402'     | ''          | ''            | '20150615'
 '127K'       | '1%'      | '1/16W'  | '0402LF'  | 'EMPTY'  | 'CS41272FB19'(!)        = 'End of Design' | 'Comp-Approve'     | 'CS41272FB19'           |'R0402'| '(R0402-0201)'                 | '127K'    | '1%'    | '1/16W'  | 'IO'       | 'RES CHIP 127K 1/16W +-1%(0402)'                   | 'CHIP0402'     | ''          | ''            | '20150615'
 '15.8K'      | '1%'      | '1/16W'  | '0402LF'  | 'CHIP'   | 'CS31582FB12'(!)        = 'End of Design' | 'Comp-Approve'     | 'CS31582FB12'           |'R0402'| '(R0402-0201)'                 | '15.8K'   | '1%'    | '1/16W'  | 'DISCRETE' | 'RES CHIP 15.8K 1/16W +-1% (0402)'                 | 'CHIP0402'     | ''          | ''            | '20150615'
 '15.8K'      | '1%'      | '1/16W'  | '0402LF'  | 'EMPTY'  | 'CS31582FB12'(!)        = 'End of Design' | 'Comp-Approve'     | 'CS31582FB12'           |'R0402'| '(R0402-0201)'                 | '15.8K'   | '1%'    | '1/16W'  | 'IO'       | 'RES CHIP 15.8K 1/16W +-1% (0402)'                 | 'CHIP0402'     | ''          | ''            | '20150615'
 '100K'       | '0.1%'    | '1/16W'  | '0402LF'  | 'CHIP'   | 'CS41002BB06'(!)        = ''              | ''                 | 'CS41002BB06'           |'R0402'| '(R0402-0201)'                 | '100K'    | '0.1%'  | '1/16W'  | 'DISCRETE' | 'RES CHIP 100K 1/16W +-0.1%(0402)'                 | 'CHIP0402'     | ''          | ''            | '20150623'
 '100K'       | '0.1%'    | '1/16W'  | '0402LF'  | 'EMPTY'  | 'CS41002BB06'(!)        = ''              | ''                 | 'CS41002BB06'           |'R0402'| '(R0402-0201)'                 | '100K'    | '0.1%'  | '1/16W'  | 'IO'       | 'RES CHIP 100K 1/16W +-0.1%(0402)'                 | 'CHIP0402'     | ''          | ''            | '20150623'
 '133K'       | '0.1%'    | '1/16W'  | '0402LF'  | 'CHIP'   | 'CS41332BB00'(!)        = ''              | ''                 | 'CS41332BB00'           |'R0402'| '(R0402-0201)'                 | '133K'    | '0.1%'  | '1/16W'  | 'DISCRETE' | 'RES CHIP 133K 1/16W +-0.1%(0402)'                 | 'CHIP0402'     | ''          | ''            | '20150623'
 '133K'       | '0.1%'    | '1/16W'  | '0402LF'  | 'EMPTY'  | 'CS41332BB00'(!)        = ''              | ''                 | 'CS41332BB00'           |'R0402'| '(R0402-0201)'                 | '133K'    | '0.1%'  | '1/16W'  | 'IO'       | 'RES CHIP 133K 1/16W +-0.1%(0402)'                 | 'CHIP0402'     | ''          | ''            | '20150623'
 '5.9K'       | '0.1%'    | '1/16W'  | '0402LF'  | 'CHIP'   | 'CS25902BB00'(!)        = ''              | ''                 | 'CS25902BB00'           |'R0402'| '(R0402-0201)'                 | '5.9K'    | '0.1%'  | '1/16W'  | 'DISCRETE' | 'RES CHIP 5.9K 1/16W +-0.1% (0402)'                | 'CHIP0402'     | ''          | ''            | '20150624'
 '5.9K'       | '0.1%'    | '1/16W'  | '0402LF'  | 'EMPTY'  | 'CS25902BB00'(!)        = ''              | ''                 | 'CS25902BB00'           |'R0402'| '(R0402-0201)'                 | '5.9K'    | '0.1%'  | '1/16W'  | 'IO'       | 'RES CHIP 5.9K 1/16W +-0.1% (0402)'                | 'CHIP0402'     | ''          | ''            | '20150624'
 '118K'       | '0.1%'    | '1/16W'  | '0402LF'  | 'CHIP'   | 'CS41182BB00'(!)        = ''              | ''                 | 'CS41182BB00'           |'R0402'| '(R0402-0201)'                 | '118K'    | '0.1%'  | '1/16W'  | 'DISCRETE' | 'RES CHIP 118K 1/16W +-0.1% (0402)'                | 'CHIP0402'     | ''          | ''            | '20150624'
 '118K'       | '0.1%'    | '1/16W'  | '0402LF'  | 'EMPTY'  | 'CS41182BB00'(!)        = ''              | ''                 | 'CS41182BB00'           |'R0402'| '(R0402-0201)'                 | '118K'    | '0.1%'  | '1/16W'  | 'IO'       | 'RES CHIP 118K 1/16W +-0.1% (0402)'                | 'CHIP0402'     | ''          | ''            | '20150624'
 '16.9K'      | '0.1%'    | '1/16W'  | '0402LF'  | 'CHIP'   | 'CS31692BB00'(!)        = ''              | ''                 | 'CS31692BB00'           |'R0402'| '(R0402-0201)'                 | '16.9K'   | '0.1%'  | '1/16W'  | 'DISCRETE' | 'RES CHIP 16.9K 1/16W +-0.1%(0402)'                | 'CHIP0402'     | ''          | ''            | '20150702'
 '16.9K'      | '0.1%'    | '1/16W'  | '0402LF'  | 'EMPTY'  | 'CS31692BB00'(!)        = ''              | ''                 | 'CS31692BB00'           |'R0402'| '(R0402-0201)'                 | '16.9K'   | '0.1%'  | '1/16W'  | 'IO'       | 'RES CHIP 16.9K 1/16W +-0.1%(0402)'                | 'CHIP0402'     | ''          | ''            | '20150702'
 '7.87K'      | '1%'      | '1/16W'  | '0402LF'  | 'CHIP'   | 'CS27872FB13'(!)        = 'End of Design' | 'Comp-Approve'     | 'CS27872FB13'           |'R0402'| '(R0402-0201)'                 | '7.87K'   | '1%'    | '1/16W'  | 'DISCRETE' | 'RES CHIP 7.87K 1/16W +-1%(0402)'                  | 'CHIP0402'     | ''          | ''            | '20150720'
 '7.87K'      | '1%'      | '1/16W'  | '0402LF'  | 'EMPTY'  | 'CS27872FB13'(!)        = 'End of Design' | 'Comp-Approve'     | 'CS27872FB13'           |'R0402'| '(R0402-0201)'                 | '7.87K'   | '1%'    | '1/16W'  | 'IO'       | 'RES CHIP 7.87K 1/16W +-1%(0402)'                  | 'CHIP0402'     | ''          | ''            | '20150720'
 '158K'       | '1%'      | '1/16W'  | '0402LF'  | 'CHIP'   | 'CS41582FB14'(!)        = 'End of Design' | 'Comp-Approve'     | 'CS41582FB14'           |'R0402'| '(R0402-0201)'                 | '158K'    | '1%'    | '1/16W'  | 'DISCRETE' | 'RES CHIP 158K 1/16W +-1% (0402)'                  | 'CHIP0402'     | ''          | ''            | '20150728'
 '158K'       | '1%'      | '1/16W'  | '0402LF'  | 'EMPTY'  | 'CS41582FB14'(!)        = 'End of Design' | 'Comp-Approve'     | 'CS41582FB14'           |'R0402'| '(R0402-0201)'                 | '158K'    | '1%'    | '1/16W'  | 'IO'       | 'RES CHIP 158K 1/16W +-1% (0402)'                  | 'CHIP0402'     | ''          | ''            | '20150728'
 '15K'        | '1%'      | '1/10W'  | '0603LF'  | 'CHIP'   | 'CS31503F939'(!)        = ''              | ''                 | 'CS31503F939'           |'R0603'| '(SMR0603AW)'                  | '15K'     | '1%'    | '1/10W'  | 'DISCRETE' | 'RESISTOR CHIP 15K 1/10W+-1%(0603)'                | 'CHIP0603'     | ''          | ''            | '20150728'
 '15K'        | '1%'      | '1/10W'  | '0603LF'  | 'EMPTY'  | 'CS31503F939'(!)        = ''              | ''                 | 'CS31503F939'           |'R0603'| '(SMR0603AW)'                  | '15K'     | '1%'    | '1/10W'  | 'IO'       | 'RESISTOR CHIP 15K 1/10W+-1%(0603)'                | 'CHIP0603'     | ''          | ''            | '20150728'
 '2.26M'      | '1%'      | '1/8W'   | '0805LF'  | 'CHIP'   | 'CS52264FA00'(!)        = ''              | ''                 | 'CS52264FA00'           |'R0805'| '(SMR0805AW)'                  | '2.26M'   | '1%'    | '1/8W'   | 'DISCRETE' | 'RES CHIP 2.26M 1/8W +-1% (0805)'                  | 'CHIP0805'     | ''          | ''            | '20150803'
 '2.26M'      | '1%'      | '1/8W'   | '0805LF'  | 'EMPTY'  | 'CS52264FA00'(!)        = ''              | ''                 | 'CS52264FA00'           |'R0805'| '(SMR0805AW)'                  | '2.26M'   | '1%'    | '1/8W'   | 'IO'       | 'RES CHIP 2.26M 1/8W +-1% (0805)'                  | 'CHIP0805'     | ''          | ''            | '20150803'
 '20K'        | '1%'      | '1/8W'   | '0805LF'  | 'CHIP'   | 'CS32004FA00'(!)        = ''              | ''                 | 'CS32004FA00'           |'R0805'| '(SMR0805AW)'                  | '20K'     | '1%'    | '1/8W'   | 'DISCRETE' | 'RES CHIP 20K 1/8W +-1%(0805)'                     | 'CHIP0805'     | ''          | ''            | '20150803'
 '20K'        | '1%'      | '1/8W'   | '0805LF'  | 'EMPTY'  | 'CS32004FA00'(!)        = ''              | ''                 | 'CS32004FA00'           |'R0805'| '(SMR0805AW)'                  | '20K'     | '1%'    | '1/8W'   | 'IO'       | 'RES CHIP 20K 1/8W +-1%(0805)'                     | 'CHIP0805'     | ''          | ''            | '20150803'
 '4.99K'      | '0.1%'    | '1/16W'  | '0402LF'  | 'CHIP'   | 'CS24992BB00'(!)        = ''              | ''                 | 'CS24992BB00'           |'R0402'| '(R0402-0201)'                 | '4.99K'   | '0.1%'  | '1/16W'  | 'DISCRETE' | 'RES CHIP 4.99K 1/16W +-0.1%(0402)'                | 'CHIP0402'     | ''          | ''            | '20150805'
 '4.99K'      | '0.1%'    | '1/16W'  | '0402LF'  | 'EMPTY'  | 'CS24992BB00'(!)        = ''              | ''                 | 'CS24992BB00'           |'R0402'| '(R0402-0201)'                 | '4.99K'   | '0.1%'  | '1/16W'  | 'IO'       | 'RES CHIP 4.99K 1/16W +-0.1%(0402)'                | 'CHIP0402'     | ''          | ''            | '20150805'
 '30K'        | '0.1%'    | '1/16W'  | '0402LF'  | 'CHIP'   | 'CS33002BB00'(!)        = ''              | ''                 | 'CS33002BB00'           |'R0402'| '(R0402-0201)'                 | '30K'     | '0.1%'  | '1/16W'  | 'DISCRETE' | 'RES CHIP 30K 1/16W +-0.1%(0402)HF'                | 'CHIP0402'     | ''          | ''            | '20150805'
 '30K'        | '0.1%'    | '1/16W'  | '0402LF'  | 'EMPTY'  | 'CS33002BB00'(!)        = ''              | ''                 | 'CS33002BB00'           |'R0402'| '(R0402-0201)'                 | '30K'     | '0.1%'  | '1/16W'  | 'IO'       | 'RES CHIP 30K 1/16W +-0.1%(0402)HF'                | 'CHIP0402'     | ''          | ''            | '20150805'
 '24K'        | '0.1%'    | '1/16W'  | '0402LF'  | 'CHIP'   | 'CS32402BB00'(!)        = ''              | ''                 | 'CS32402BB00'           |'R0402'| '(R0402-0201)'                 | '24K'     | '0.1%'  | '1/16W'  | 'DISCRETE' | 'RES CHIP 24K 1/16W +-0.1% (0402)'                 | 'CHIP0402'     | ''          | ''            | '20150805'
 '24K'        | '0.1%'    | '1/16W'  | '0402LF'  | 'EMPTY'  | 'CS32402BB00'(!)        = ''              | ''                 | 'CS32402BB00'           |'R0402'| '(R0402-0201)'                 | '24K'     | '0.1%'  | '1/16W'  | 'IO'       | 'RES CHIP 24K 1/16W +-0.1% (0402)'                 | 'CHIP0402'     | ''          | ''            | '20150805'
 '29.4K'      | '0.1%'    | '1/16W'  | '0402LF'  | 'CHIP'   | 'CS32942BB00'(!)        = ''              | ''                 | 'CS32942BB00'           |'R0402'| '(R0402-0201)'                 | '29.4K'   | '0.1%'  | '1/16W'  | 'DISCRETE' | 'RES CHIP 29.4K 1/16W +-0.1%(0402)'                | 'CHIP0402'     | ''          | ''            | '20150807'
 '29.4K'      | '0.1%'    | '1/16W'  | '0402LF'  | 'EMPTY'  | 'CS32942BB00'(!)        = ''              | ''                 | 'CS32942BB00'           |'R0402'| '(R0402-0201)'                 | '29.4K'   | '0.1%'  | '1/16W'  | 'IO'       | 'RES CHIP 29.4K 1/16W +-0.1%(0402)'                | 'CHIP0402'     | ''          | ''            | '20150807'
 '60.4K'      | '0.1%'    | '1/16W'  | '0402LF'  | 'CHIP'   | 'CS36042BB00'(!)        = ''              | ''                 | 'CS36042BB00'           |'R0402'| '(R0402-0201)'                 | '60.4K'   | '0.1%'  | '1/16W'  | 'DISCRETE' | 'RES CHIP 60.4K 1/16W +-0.1%(0402)'                | 'CHIP0402'     | ''          | ''            | '20150807'
 '60.4K'      | '0.1%'    | '1/16W'  | '0402LF'  | 'EMPTY'  | 'CS36042BB00'(!)        = ''              | ''                 | 'CS36042BB00'           |'R0402'| '(R0402-0201)'                 | '60.4K'   | '0.1%'  | '1/16W'  | 'IO'       | 'RES CHIP 60.4K 1/16W +-0.1%(0402)'                | 'CHIP0402'     | ''          | ''            | '20150807'
 '51.1K'      | '1%'      | '1/16W'  | '0402LF'  | 'CHIP'   | 'CS35112FB17'(!)        = 'End of Design' | 'Comp-Approve'     | 'CS35112FB17'           |'R0402'| '(R0402-0201)'                 | '51.1K'   | '1%'    | '1/16W'  | 'DISCRETE' | 'RES CHIP 51.1K 1/16W +-1%(0402) L-F'              | 'CHIP0402'     | ''          | ''            | '20150810'
 '51.1K'      | '1%'      | '1/16W'  | '0402LF'  | 'EMPTY'  | 'CS35112FB17'(!)        = 'End of Design' | 'Comp-Approve'     | 'CS35112FB17'           |'R0402'| '(R0402-0201)'                 | '51.1K'   | '1%'    | '1/16W'  | 'IO'       | 'RES CHIP 51.1K 1/16W +-1%(0402) L-F'              | 'CHIP0402'     | ''          | ''            | '20150810'
 '475K'       | '1%'      | '1/16W'  | '0402LF'  | 'CHIP'   | 'CS44752FB08'(!)        = 'End of Design' | 'Comp-Approve'     | 'CS44752FB08'           |'R0402'| '(R0402-0201)'                 | '475K'    | '1%'    | '1/16W'  | 'DISCRETE' | 'RES CHIP 475K 1/16W +-1%(0402)'                   | 'CHIP0402'     | ''          | ''            | '20150819'
 '475K'       | '1%'      | '1/16W'  | '0402LF'  | 'EMPTY'  | 'CS44752FB08'(!)        = 'End of Design' | 'Comp-Approve'     | 'CS44752FB08'           |'R0402'| '(R0402-0201)'                 | '475K'    | '1%'    | '1/16W'  | 'IO'       | 'RES CHIP 475K 1/16W +-1%(0402)'                   | 'CHIP0402'     | ''          | ''            | '20150819'
 '6.49K'      | '0.1%'    | '1/16W'  | '0402LF'  | 'CHIP'   | 'CS26492BB00'(!)        = ''              | ''                 | 'CS26492BB00'           |'R0402'| '(R0402-0201)'                 | '6.49K'   | '0.1%'  | '1/16W'  | 'DISCRETE' | 'RES CHIP 6.49K 1/16W +-0.1%(0402)'                | 'CHIP0402'     | ''          | ''            | '20150828'
 '6.49K'      | '0.1%'    | '1/16W'  | '0402LF'  | 'EMPTY'  | 'CS26492BB00'(!)        = ''              | ''                 | 'CS26492BB00'           |'R0402'| '(R0402-0201)'                 | '6.49K'   | '0.1%'  | '1/16W'  | 'IO'       | 'RES CHIP 6.49K 1/16W +-0.1%(0402)'                | 'CHIP0402'     | ''          | ''            | '20150828'
 '6.2K'       | '5%'      | '1/16W'  | '0402LF'  | 'CHIP'   | 'CS26202JB19'(!)        = 'End of Design' | 'Comp-Approve'     | 'CS26202JB19'           |'R0402'| '(R0402-0201)'                 | '6.2K'    | '5%'    | '1/16W'  | 'DISCRETE' | 'RES CHIP 6.2K 1/16W+-5%(0402)'                    | 'CHIP0402'     | ''          | ''            | '20150910'
 '6.2K'       | '5%'      | '1/16W'  | '0402LF'  | 'EMPTY'  | 'CS26202JB19'(!)        = 'End of Design' | 'Comp-Approve'     | 'CS26202JB19'           |'R0402'| '(R0402-0201)'                 | '6.2K'    | '5%'    | '1/16W'  | 'IO'       | 'RES CHIP 6.2K 1/16W+-5%(0402)'                    | 'CHIP0402'     | ''          | ''            | '20150910'
 '85.5K'      | '1%'      | '1/16W'  | '0402LF'  | 'CHIP'   | 'CS38552FB00'(!)        = ''              | ''                 | 'CS38552FB00'           |'R0402'| '(R0402-0201)'                 | '85.5K'   | '1%'    | '1/16W'  | 'DISCRETE' | 'RES CHIP 85.5K 1/16W +-1%(0402)'                  | 'CHIP0402'     | ''          | ''            | '20150915'
 '85.5K'      | '1%'      | '1/16W'  | '0402LF'  | 'EMPTY'  | 'CS38552FB00'(!)        = ''              | ''                 | 'CS38552FB00'           |'R0402'| '(R0402-0201)'                 | '85.5K'   | '1%'    | '1/16W'  | 'IO'       | 'RES CHIP 85.5K 1/16W +-1%(0402)'                  | 'CHIP0402'     | ''          | ''            | '20150915'
 '1.96K'      | '1%'      | '1/16W'  | '0402LF'  | 'CHIP'   | 'CS21962FB08'(!)        = 'End of Design' | 'Comp-Approve'     | 'CS21962FB08'           |'R0402'| '(R0402-0201)'                 | '1.96K'   | '1%'    | '1/16W'  | 'DISCRETE' | 'RES CHIP 1.96K 1/16W +-1%(0402)'                  | 'CHIP0402'     | ''          | ''            | '20151014'
 '1.96K'      | '1%'      | '1/16W'  | '0402LF'  | 'EMPTY'  | 'CS21962FB08'(!)        = 'End of Design' | 'Comp-Approve'     | 'CS21962FB08'           |'R0402'| '(R0402-0201)'                 | '1.96K'   | '1%'    | '1/16W'  | 'IO'       | 'RES CHIP 1.96K 1/16W +-1%(0402)'                  | 'CHIP0402'     | ''          | ''            | '20151014'
 '39'         | '1%'      | '1/16W'  | '0402LF'  | 'CHIP'   | 'CS03902FB11'(!)        = 'End of Design' | 'Comp-Approve'     | 'CS03902FB11'           |'R0402'| '(R0402-0201)'                 | '39'      | '1%'    | '1/16W'  | 'DISCRETE' | 'RES CHIP 39 1/16W +-1%(0402)'                     | 'CHIP0402'     | ''          | ''            | '20151020'
 '39'         | '1%'      | '1/16W'  | '0402LF'  | 'EMPTY'  | 'CS03902FB11'(!)        = 'End of Design' | 'Comp-Approve'     | 'CS03902FB11'           |'R0402'| '(R0402-0201)'                 | '39'      | '1%'    | '1/16W'  | 'IO'       | 'RES CHIP 39 1/16W +-1%(0402)'                     | 'CHIP0402'     | ''          | ''            | '20151020'
 '4.3K'       | '1%'      | '1/16W'  | '0402LF'  | 'CHIP'   | 'CS24302FB07'(!)        = 'End of Design' | 'Comp-Approve'     | 'CS24302FB07'           |'R0402'| '(R0402-0201)'                 | '4.3K'    | '1%'    | '1/16W'  | 'DISCRETE' | 'RES CHIP 4.3K 1/16W +-1%(0402)'                   | 'CHIP0402'     | ''          | ''            | '20151120'
 '4.3K'       | '1%'      | '1/16W'  | '0402LF'  | 'EMPTY'  | 'CS24302FB07'(!)        = 'End of Design' | 'Comp-Approve'     | 'CS24302FB07'           |'R0402'| '(R0402-0201)'                 | '4.3K'    | '1%'    | '1/16W'  | 'IO'       | 'RES CHIP 4.3K 1/16W +-1%(0402)'                   | 'CHIP0402'     | ''          | ''            | '20151120'
 '20K'        | '0.1%'    | '1/16W'  | '0402LF'  | 'CHIP'   | 'CS32002BB00'(!)        = ''              | ''                 | 'CS32002BB00'           |'R0402'| '(R0402-0201)'                 | '20K'     | '0.1%'  | '1/16W'  | 'DISCRETE' | 'RES CHIP 20K 1/16W +-0.1%(0402)'                  | 'CHIP0402'     | ''          | ''            | '20151203'
 '20K'        | '0.1%'    | '1/16W'  | '0402LF'  | 'EMPTY'  | 'CS32002BB00'(!)        = ''              | ''                 | 'CS32002BB00'           |'R0402'| '(R0402-0201)'                 | '20K'     | '0.1%'  | '1/16W'  | 'IO'       | 'RES CHIP 20K 1/16W +-0.1%(0402)'                  | 'CHIP0402'     | ''          | ''            | '20151203'
 '1.69M'      | '1%'      | '1/16W'  | '0402LF'  | 'CHIP'   | 'CS51692FB06'(!)        = ''              | ''                 | 'CS51692FB06'           |'R0402'| '(R0402-0201)'                 | '1.69M'   | '1%'    | '1/16W'  | 'DISCRETE' | 'RES CHIP 1.69M.1/16W +-1%(0402)EP'                | 'CHIP0402'     | ''          | ''            | '20151207'
 '1.69M'      | '1%'      | '1/16W'  | '0402LF'  | 'EMPTY'  | 'CS51692FB06'(!)        = ''              | ''                 | 'CS51692FB06'           |'R0402'| '(R0402-0201)'                 | '1.69M'   | '1%'    | '1/16W'  | 'IO'       | 'RES CHIP 1.69M.1/16W +-1%(0402)EP'                | 'CHIP0402'     | ''          | ''            | '20151207'
 '681K'       | '1%'      | '1/16W'  | '0402LF'  | 'CHIP'   | 'CS46812FB00'(!)        = 'End of Design' | 'Comp-Approve'     | 'CS46812FB00'           |'R0402'| '(R0402-0201)'                 | '681K'    | '1%'    | '1/16W'  | 'DISCRETE' | 'RES CHIP 681K 1/16W +-1%(0402)'                   | 'CHIP0402'     | ''          | ''            | '20151208'
 '681K'       | '1%'      | '1/16W'  | '0402LF'  | 'EMPTY'  | 'CS46812FB00'(!)        = 'End of Design' | 'Comp-Approve'     | 'CS46812FB00'           |'R0402'| '(R0402-0201)'                 | '681K'    | '1%'    | '1/16W'  | 'IO'       | 'RES CHIP 681K 1/16W +-1%(0402)'                   | 'CHIP0402'     | ''          | ''            | '20151208'
 '1.07K'      | '0.1%'    | '1/16W'  | '0402LF'  | 'CHIP'   | 'CS21072BB00'(!)        = ''              | ''                 | 'CS21072BB00'           |'R0402'| '(R0402-0201)'                 | '1.07K'   | '0.1%'  | '1/16W'  | 'DISCRETE' | 'RES CHIP 1.07K 1/16W +-0.1% (0402)'               | 'CHIP0402'     | ''          | ''            | '20151208'
 '1.07K'      | '0.1%'    | '1/16W'  | '0402LF'  | 'EMPTY'  | 'CS21072BB00'(!)        = ''              | ''                 | 'CS21072BB00'           |'R0402'| '(R0402-0201)'                 | '1.07K'   | '0.1%'  | '1/16W'  | 'IO'       | 'RES CHIP 1.07K 1/16W +-0.1% (0402)'               | 'CHIP0402'     | ''          | ''            | '20151208'
 '150'        | '5%'      | '1/16W'  | '0402LF'  | 'CHIP'   | 'TMP_QCS11502JB22'(!)   = 'End of Design' | 'Comp-Approve'     | 'CS11502JB22'           |'R0402'| '(R0402-0201)'                 | '150'     | '5%'    | '1/16W'  | 'DISCRETE' | 'RES CHIP 150 1/16W +-5%(0402)'                    | 'CHIP0402'     | ''          | ''            | '20151222'
 '150'        | '5%'      | '1/16W'  | '0402LF'  | 'EMPTY'  | 'TMP_QCS11502JB22'(!)   = 'End of Design' | 'Comp-Approve'     | 'CS11502JB22'           |'R0402'| '(R0402-0201)'                 | '150'     | '5%'    | '1/16W'  | 'IO'       | 'RES CHIP 150 1/16W +-5%(0402)'                    | 'CHIP0402'     | ''          | ''            | '20151222'
 '0'          | '5%'      | '1/20W'  | '0201LF'  | 'CHIP'   | 'CS00001JE18'(!)        = ''              | ''                 | 'CS00001JE18'           |'R0201'| '(SMR0201AW)'                  | '0'       | '5%'    | '1/20W'  | 'DISCRETE' | 'RES CHIP 0(1/20W,+-5%,0201)'                      | 'CHIP0201'     | ''          | ''            | '20151228'
 '0'          | '5%'      | '1/20W'  | '0201LF'  | 'EMPTY'  | 'CS00001JE18'(!)        = ''              | ''                 | 'CS00001JE18'           |'R0201'| '(SMR0201AW)'                  | '0'       | '5%'    | '1/20W'  | 'IO'       | 'RES CHIP 0(1/20W,+-5%,0201)'                      | 'CHIP0201'     | ''          | ''            | '20151228'
 '249K'       | '1%'      | '1/16W'  | '0402LF'  | 'CHIP'   | 'CS42492FB18'(!)        = 'End of Design' | 'Comp-Approve'     | 'CS42492FB18'           |'R0402'| '(R0402-0201)'                 | '249K'    | '1%'    | '1/16W'  | 'DISCRETE' | 'RES CHIP 249K 1/16W +-1%(0402)EP'                 | 'CHIP0402'     | ''          | ''            | '20151228'
 '249K'       | '1%'      | '1/16W'  | '0402LF'  | 'EMPTY'  | 'CS42492FB18'(!)        = 'End of Design' | 'Comp-Approve'     | 'CS42492FB18'           |'R0402'| '(R0402-0201)'                 | '249K'    | '1%'    | '1/16W'  | 'IO'       | 'RES CHIP 249K 1/16W +-1%(0402)EP'                 | 'CHIP0402'     | ''          | ''            | '20151228'
 '0.001'      | '1%'      | '1W'     | '2512LF'  | 'CHIP'   | 'CS+0018FR03'(!)        = ''              | ''                 | 'CS+0018FR03'           |'R2512A'| '(SMR2512AW)'                  | '0.001'   | '1%'    | '1W'     | 'DISCRETE' | 'RES CHIP 0.001 1W +-1%(2512)AEC'                  | 'CHIP2512'     | ''          | ''            | '20151229'
 '0.001'      | '1%'      | '1W'     | '2512LF'  | 'EMPTY'  | 'CS+0018FR03'(!)        = ''              | ''                 | 'CS+0018FR03'           |'R2512A'| '(SMR2512AW)'                  | '0.001'   | '1%'    | '1W'     | 'IO'       | 'RES CHIP 0.001 1W +-1%(2512)AEC'                  | 'CHIP2512'     | ''          | ''            | '20151229'
 '0.0005'     | '1%'      | '1W'     | '2512LF'  | 'CHIP'   | 'CS00008FR03'(!)        = ''              | ''                 | 'CS00008FR03'           |'R2512A'| '(SMR2512AW)'                  | '0.0005'  | '1%'    | '1W'     | 'DISCRETE' | 'RES CHIP 0.0005 1W +-1%(2512)AEC'                 | 'CHIP2512'     | ''          | ''            | '20160105'
 '0.0005'     | '1%'      | '1W'     | '2512LF'  | 'EMPTY'  | 'CS00008FR03'(!)        = ''              | ''                 | 'CS00008FR03'           |'R2512A'| '(SMR2512AW)'                  | '0.0005'  | '1%'    | '1W'     | 'IO'       | 'RES CHIP 0.0005 1W +-1%(2512)AEC'                 | 'CHIP2512'     | ''          | ''            | '20160105'
 '41.2K'      | '1%'      | '1/16W'  | '0402LF'  | 'CHIP'   | 'CS34122FB19'(!)        = ''              | ''                 | 'CS34122FB19'           |'R0402'| '(R0402-0201)'                 | '41.2K'   | '1%'    | '1/16W'  | 'DISCRETE' | 'RES CHIP 41.2K 1/16W +-1%(0402)'                  | 'CHIP0402'     | ''          | ''            | '20160112'
 '41.2K'      | '1%'      | '1/16W'  | '0402LF'  | 'EMPTY'  | 'CS34122FB19'(!)        = ''              | ''                 | 'CS34122FB19'           |'R0402'| '(R0402-0201)'                 | '41.2K'   | '1%'    | '1/16W'  | 'IO'       | 'RES CHIP 41.2K 1/16W +-1%(0402)'                  | 'CHIP0402'     | ''          | ''            | '20160112'
 '15'         | '1%'      | '1/20W'  | '0201LF'  | 'CHIP'   | 'CS01501FE01'(!)        = ''              | 'End of Life'      | 'CS01501FE01'           |'R0201_EOL'| '(SMR0201AW)'                  | '15'      | '1%'    | '1/20W'  | 'DISCRETE' | 'RES CHIP 15 1/20W +-1%(0201)'                     | 'CHIP0201'     | ''          | ''            | '20160112'
 '15'         | '1%'      | '1/20W'  | '0201LF'  | 'EMPTY'  | 'CS01501FE01'(!)        = ''              | 'End of Life'      | 'CS01501FE01'           |'R0201_EOL'| '(SMR0201AW)'                  | '15'      | '1%'    | '1/20W'  | 'IO'       | 'RES CHIP 15 1/20W +-1%(0201)'                     | 'CHIP0201'     | ''          | ''            | '20160112'
 '1.54M'      | '1%'      | '1/8W'   | '0805LF'  | 'CHIP'   | 'CS51544FA00'(!)        = ''              | ''                 | 'CS51544FA00'           |'R0805'| '(SMR0805AW)'                  | '1.54M'   | '1%'    | '1/8W'   | 'DISCRETE' | 'RES CHIP 1.54M 1/8W +-1% (0805)'                  | 'CHIP0805'     | ''          | ''            | '20160112'
 '1.54M'      | '1%'      | '1/8W'   | '0805LF'  | 'EMPTY'  | 'CS51544FA00'(!)        = ''              | ''                 | 'CS51544FA00'           |'R0805'| '(SMR0805AW)'                  | '1.54M'   | '1%'    | '1/8W'   | 'IO'       | 'RES CHIP 1.54M 1/8W +-1% (0805)'                  | 'CHIP0805'     | ''          | ''            | '20160112'
 '147K'       | '1%'      | '1/16W'  | '0402LF'  | 'CHIP'   | 'CS41472FB04'(!)        = ''              | ''                 | 'CS41472FB04'           |'R0402'| '(R0402-0201)'                 | '147K'    | '1%'    | '1/16W'  | 'DISCRETE' | 'RES CHIP 147K 1/16W +-1%(0402)AEC'                | 'CHIP0402'     | ''          | ''            | '20160111'
 '147K'       | '1%'      | '1/16W'  | '0402LF'  | 'EMPTY'  | 'CS41472FB04'(!)        = ''              | ''                 | 'CS41472FB04'           |'R0402'| '(R0402-0201)'                 | '147K'    | '1%'    | '1/16W'  | 'IO'       | 'RES CHIP 147K 1/16W +-1%(0402)AEC'                | 'CHIP0402'     | ''          | ''            | '20160111'
 '0'          | '1%'      | '1/16W'  | '0402LF'  | 'CHIP'   | 'CS00002FB03'(!)        = ''              | ''                 | 'CS00002FB03'           |'R0402'| '(R0402_OCTAGONXA,R0402-0201)' | '0'       | '1%'    | '1/16W'  | 'DISCRETE' | 'RES CHIP 0 1/16W +-1%(0402)AEC'                   | 'CHIP0402'     | ''          | ''            | '20160111'
 '0'          | '1%'      | '1/16W'  | '0402LF'  | 'EMPTY'  | 'CS00002FB03'(!)        = ''              | ''                 | 'CS00002FB03'           |'R0402'| '(R0402_OCTAGONXA,R0402-0201)' | '0'       | '1%'    | '1/16W'  | 'IO'       | 'RES CHIP 0 1/16W +-1%(0402)AEC'                   | 'CHIP0402'     | ''          | ''            | '20160111'
 '0'          | '5%'      | '1/16W'  | '0402LF'  | 'CHIP'   | 'CS00002JB17'(!)        = ''              | ''                 | 'CS00002JB17'           |'R0402'| '(R0402-0201)'                 | '0'       | '5%'    | '1/16W'  | 'DISCRETE' | 'RES CHIP 0 1/16W +-5%(0402)AEC'                   | 'CHIP0402'     | ''          | ''            | '20160111'
 '0'          | '5%'      | '1/16W'  | '0402LF'  | 'EMPTY'  | 'CS00002JB17'(!)        = ''              | ''                 | 'CS00002JB17'           |'R0402'| '(R0402-0201)'                 | '0'       | '5%'    | '1/16W'  | 'IO'       | 'RES CHIP 0 1/16W +-5%(0402)AEC'                   | 'CHIP0402'     | ''          | ''            | '20160111'
 '1'          | '1%'      | '1/16W'  | '0402LF'  | 'CHIP'   | 'CS-1002FB09'(!)        = ''              | ''                 | 'CS-1002FB09'           |'R0402'| '(R0402-0201)'                 | '1'       | '1%'    | '1/16W'  | 'DISCRETE' | 'RES CHIP 1 1/16W +-1%(0402)AEC'                   | 'CHIP0402'     | ''          | ''            | '20160111'
 '1'          | '1%'      | '1/16W'  | '0402LF'  | 'EMPTY'  | 'CS-1002FB09'(!)        = ''              | ''                 | 'CS-1002FB09'           |'R0402'| '(R0402-0201)'                 | '1'       | '1%'    | '1/16W'  | 'IO'       | 'RES CHIP 1 1/16W +-1%(0402)AEC'                   | 'CHIP0402'     | ''          | ''            | '20160111'
 '1'          | '5%'      | '1/16W'  | '0402LF'  | 'CHIP'   | 'CS-1002JB06'(!)        = ''              | ''                 | 'CS-1002JB06'           |'R0402'| '(R0402-0201)'                 | '1'       | '5%'    | '1/16W'  | 'DISCRETE' | 'RES CHIP 1 1/16W +-5%(0402)AEC'                   | 'CHIP0402'     | ''          | ''            | '20160111'
 '1'          | '5%'      | '1/16W'  | '0402LF'  | 'EMPTY'  | 'CS-1002JB06'(!)        = ''              | ''                 | 'CS-1002JB06'           |'R0402'| '(R0402-0201)'                 | '1'       | '5%'    | '1/16W'  | 'IO'       | 'RES CHIP 1 1/16W +-5%(0402)AEC'                   | 'CHIP0402'     | ''          | ''            | '20160111'
 '1.8K'       | '1%'      | '1/16W'  | '0402LF'  | 'CHIP'   | 'CS21802FB03'(!)        = ''              | ''                 | 'CS21802FB03'           |'R0402'| '(R0402-0201)'                 | '1.8K'    | '1%'    | '1/16W'  | 'DISCRETE' | 'RES CHIP 1.8K 1/16W +-1%(0402)AEC'                | 'CHIP0402'     | ''          | ''            | '20160111'
 '1.8K'       | '1%'      | '1/16W'  | '0402LF'  | 'EMPTY'  | 'CS21802FB03'(!)        = ''              | ''                 | 'CS21802FB03'           |'R0402'| '(R0402-0201)'                 | '1.8K'    | '1%'    | '1/16W'  | 'IO'       | 'RES CHIP 1.8K 1/16W +-1%(0402)AEC'                | 'CHIP0402'     | ''          | ''            | '20160111'
 '10'         | '1%'      | '1/16W'  | '0402LF'  | 'CHIP'   | 'CS01002FB11'(!)        = ''              | ''                 | 'CS01002FB11'           |'R0402'| '(R0402-0201)'                 | '10'      | '1%'    | '1/16W'  | 'DISCRETE' | 'RES CHIP 10 1/16W +-1%(0402)AEC'                  | 'CHIP0402'     | ''          | ''            | '20160111'
 '10'         | '1%'      | '1/16W'  | '0402LF'  | 'EMPTY'  | 'CS01002FB11'(!)        = ''              | ''                 | 'CS01002FB11'           |'R0402'| '(R0402-0201)'                 | '10'      | '1%'    | '1/16W'  | 'IO'       | 'RES CHIP 10 1/16W +-1%(0402)AEC'                  | 'CHIP0402'     | ''          | ''            | '20160111'
 '100'        | '0.1%'    | '1/16W'  | '0402LF'  | 'CHIP'   | 'CS11002BB01'(!)        = ''              | ''                 | 'CS11002BB01'           |'R0402'| '(R0402-0201)'                 | '100'     | '0.1%'  | '1/16W'  | 'DISCRETE' | 'RES CHIP 100 1/16W +-0.1%(0402)AEC'               | 'CHIP0402'     | ''          | ''            | '20160111'
 '100'        | '0.1%'    | '1/16W'  | '0402LF'  | 'EMPTY'  | 'CS11002BB01'(!)        = ''              | ''                 | 'CS11002BB01'           |'R0402'| '(R0402-0201)'                 | '100'     | '0.1%'  | '1/16W'  | 'IO'       | 'RES CHIP 100 1/16W +-0.1%(0402)AEC'               | 'CHIP0402'     | ''          | ''            | '20160111'
 '100'        | '1%'      | '1/16W'  | '0402LF'  | 'CHIP'   | 'CS11002FB11'(!)        = ''              | ''                 | 'CS11002FB11'           |'R0402'| '(R0402-0201)'                 | '100'     | '1%'    | '1/16W'  | 'DISCRETE' | 'RES CHIP 100 1/16W +-1%(0402)AEC'                 | 'CHIP0402'     | ''          | ''            | '20160111'
 '100'        | '1%'      | '1/16W'  | '0402LF'  | 'EMPTY'  | 'CS11002FB11'(!)        = ''              | ''                 | 'CS11002FB11'           |'R0402'| '(R0402-0201)'                 | '100'     | '1%'    | '1/16W'  | 'IO'       | 'RES CHIP 100 1/16W +-1%(0402)AEC'                 | 'CHIP0402'     | ''          | ''            | '20160111'
 '100K'       | '0.1%'    | '1/16W'  | '0402LF'  | 'CHIP'   | 'CS41002BB02'(!)        = ''              | ''                 | 'CS41002BB02'           |'R0402'| '(R0402-0201)'                 | '100K'    | '0.1%'  | '1/16W'  | 'DISCRETE' | 'RES CHIP 100K 1/16W +-0.1%(0402)AEC'              | 'CHIP0402'     | ''          | ''            | '20160111'
 '100K'       | '0.1%'    | '1/16W'  | '0402LF'  | 'EMPTY'  | 'CS41002BB02'(!)        = ''              | ''                 | 'CS41002BB02'           |'R0402'| '(R0402-0201)'                 | '100K'    | '0.1%'  | '1/16W'  | 'IO'       | 'RES CHIP 100K 1/16W +-0.1%(0402)AEC'              | 'CHIP0402'     | ''          | ''            | '20160111'
 '100K'       | '1%'      | '1/16W'  | '0402LF'  | 'CHIP'   | 'CS41002FB16'(!)        = ''              | ''                 | 'CS41002FB16'           |'R0402'| '(R0402-0201)'                 | '100K'    | '1%'    | '1/16W'  | 'DISCRETE' | 'RES CHIP 100K 1/16W +-1%(0402)AEC'                | 'CHIP0402'     | ''          | ''            | '20160113'
 '100K'       | '1%'      | '1/16W'  | '0402LF'  | 'EMPTY'  | 'CS41002FB16'(!)        = ''              | ''                 | 'CS41002FB16'           |'R0402'| '(R0402-0201)'                 | '100K'    | '1%'    | '1/16W'  | 'IO'       | 'RES CHIP 100K 1/16W +-1%(0402)AEC'                | 'CHIP0402'     | ''          | ''            | '20160113'
 '10K'        | '0.1%'    | '1/16W'  | '0402LF'  | 'CHIP'   | 'CS31002BB05'(!)        = ''              | ''                 | 'CS31002BB05'           |'R0402'| '(R0402-0201)'                 | '10K'     | '0.1%'  | '1/16W'  | 'DISCRETE' | 'RES CHIP 10K 1/16W +-0.1%(0402)AEC'               | 'CHIP0402'     | ''          | ''            | '20160113'
 '10K'        | '0.1%'    | '1/16W'  | '0402LF'  | 'EMPTY'  | 'CS31002BB05'(!)        = ''              | ''                 | 'CS31002BB05'           |'R0402'| '(R0402-0201)'                 | '10K'     | '0.1%'  | '1/16W'  | 'IO'       | 'RES CHIP 10K 1/16W +-0.1%(0402)AEC'               | 'CHIP0402'     | ''          | ''            | '20160113'
 '10K'        | '1%'      | '1/16W'  | '0402LF'  | 'CHIP'   | 'CS31002FB13'(!)        = ''              | ''                 | 'CS31002FB13'           |'R0402'| '(R0402-0201)'                 | '10K'     | '1%'    | '1/16W'  | 'DISCRETE' | 'RES CHIP 10K 1/16W +-1%(0402)AEC'                 | 'CHIP0402'     | ''          | ''            | '20160113'
 '10K'        | '1%'      | '1/16W'  | '0402LF'  | 'EMPTY'  | 'CS31002FB13'(!)        = ''              | ''                 | 'CS31002FB13'           |'R0402'| '(R0402-0201)'                 | '10K'     | '1%'    | '1/16W'  | 'IO'       | 'RES CHIP 10K 1/16W +-1%(0402)AEC'                 | 'CHIP0402'     | ''          | ''            | '20160113'
 '10K'        | '5%'      | '1/16W'  | '0402LF'  | 'CHIP'   | 'CS31002JB09'(!)        = ''              | ''                 | 'CS31002JB09'           |'R0402'| '(R0402-0201)'                 | '10K'     | '5%'    | '1/16W'  | 'DISCRETE' | 'RES CHIP 10K 1/16W +-5%(0402)AEC'                 | 'CHIP0402'     | ''          | ''            | '20160113'
 '10K'        | '5%'      | '1/16W'  | '0402LF'  | 'EMPTY'  | 'CS31002JB09'(!)        = ''              | ''                 | 'CS31002JB09'           |'R0402'| '(R0402-0201)'                 | '10K'     | '5%'    | '1/16W'  | 'IO'       | 'RES CHIP 10K 1/16W +-5%(0402)AEC'                 | 'CHIP0402'     | ''          | ''            | '20160113'
 '11.8K'      | '1%'      | '1/16W'  | '0402LF'  | 'CHIP'   | 'CS31182FB04'(!)        = ''              | ''                 | 'CS31182FB04'           |'R0402'| '(R0402-0201)'                 | '11.8K'   | '1%'    | '1/16W'  | 'DISCRETE' | 'RES CHIP 11.8K 1/16W +-1%(0402)AEC'               | 'CHIP0402'     | ''          | ''            | '20160113'
 '11.8K'      | '1%'      | '1/16W'  | '0402LF'  | 'EMPTY'  | 'CS31182FB04'(!)        = ''              | ''                 | 'CS31182FB04'           |'R0402'| '(R0402-0201)'                 | '11.8K'   | '1%'    | '1/16W'  | 'IO'       | 'RES CHIP 11.8K 1/16W +-1%(0402)AEC'               | 'CHIP0402'     | ''          | ''            | '20160113'
 '43K'        | '1%'      | '1/10W'  | '0603LF'  | 'CHIP'   | 'CS34303F901'(!)        = 'End of Design' | 'Comp-Approve'     | 'CS34303F901'           |'R0603'| '(SMR0603AW)'                  | '43K'     | '1%'    | '1/10W'  | 'DISCRETE' | 'RES CHIP 43K 1/10W +-1%(0603)'                    | 'CHIPR0603'    | ''          | ''            | '20160115'
 '43K'        | '1%'      | '1/10W'  | '0603LF'  | 'EMPTY'  | 'CS34303F901'(!)        = 'End of Design' | 'Comp-Approve'     | 'CS34303F901'           |'R0603'| '(SMR0603AW)'                  | '43K'     | '1%'    | '1/10W'  | 'IO'       | 'RES CHIP 43K 1/10W +-1%(0603)'                    | 'CHIPR0603'    | ''          | ''            | '20160115'
 '1K'         | '1%'      | '1/16W'  | '0402LF'  | 'CHIP'   | 'CS21002BB01'(!)        = ''              | 'End of Life'      | 'CS21002BB01'           |'R0402_EOL'| '(R0402-0201)'                 | '1K'      | '1%'    | '1/16W'  | 'DISCRETE' | 'RES CHIP 1K 1/16W +-0.1%(0402)AEC'                | 'CHIPR0402'    | ''          | ''            | '20160115'
 '1K'         | '1%'      | '1/16W'  | '0402LF'  | 'EMPTY'  | 'CS21002BB01'(!)        = ''              | 'End of Life'      | 'CS21002BB01'           |'R0402_EOL'| '(R0402-0201)'                 | '1K'      | '1%'    | '1/16W'  | 'IO'       | 'RES CHIP 1K 1/16W +-0.1%(0402)AEC'                | 'CHIPR0402'    | ''          | ''            | '20160115'
 '0.005'      | '1%'      | '1W'     | '2512LF'  | 'CHIP'   | 'CS+0058FR02'(!)        = 'Non-Preferred' | 'End of Life'      | 'CS+0058FR02'           |'R2512A_EOL'| '(SMR2512AW)'                  | '0.005'   | '1%'    | '1W'     | 'DISCRETE' | 'RES CHIP 0.005 1W +-1%(2512)AEC'                  | 'CHIP2512'     | ''          | ''            | '20160115'
 '0.005'      | '1%'      | '1W'     | '2512LF'  | 'EMPTY'  | 'CS+0058FR02'(!)        = 'Non-Preferred' | 'End of Life'      | 'CS+0058FR02'           |'R2512A_EOL'| '(SMR2512AW)'                  | '0.005'   | '1%'    | '1W'     | 'IO'       | 'RES CHIP 0.005 1W +-1%(2512)AEC'                  | 'CHIP2512'     | ''          | ''            | '20160115'
 '113'        | '1%'      | '1/16W'  | '0402LF'  | 'CHIP'   | 'CS11132FB04'(!)        = ''              | ''                 | 'CS11132FB04'           |'R0402'| '(R0402-0201)'                 | '113'     | '1%'    | '1/16W'  | 'DISCRETE' | 'RES CHIP 113 1/16W +-1%(0402)AEC'                 | 'CHIP0402'     | ''          | ''            | '20160116'
 '113'        | '1%'      | '1/16W'  | '0402LF'  | 'EMPTY'  | 'CS11132FB04'(!)        = ''              | ''                 | 'CS11132FB04'           |'R0402'| '(R0402-0201)'                 | '113'     | '1%'    | '1/16W'  | 'IO'       | 'RES CHIP 113 1/16W +-1%(0402)AEC'                 | 'CHIP0402'     | ''          | ''            | '20160116'
 '115K'       | '1%'      | '1/16W'  | '0402LF'  | 'CHIP'   | 'CS41152FB01'(!)        = ''              | ''                 | 'CS41152FB01'           |'R0402'| '(R0402-0201)'                 | '115K'    | '1%'    | '1/16W'  | 'DISCRETE' | 'RES CHIP 115K 1/16W +-1%(0402)AEC'                | 'CHIP0402'     | ''          | ''            | '20160116'
 '115K'       | '1%'      | '1/16W'  | '0402LF'  | 'EMPTY'  | 'CS41152FB01'(!)        = ''              | ''                 | 'CS41152FB01'           |'R0402'| '(R0402-0201)'                 | '115K'    | '1%'    | '1/16W'  | 'IO'       | 'RES CHIP 115K 1/16W +-1%(0402)AEC'                | 'CHIP0402'     | ''          | ''            | '20160116'
 '12.1K'      | '1%'      | '1/16W'  | '0402LF'  | 'CHIP'   | 'CS31212FB06'(!)        = ''              | ''                 | 'CS31212FB06'           |'R0402'| '(R0402-0201)'                 | '12.1K'   | '1%'    | '1/16W'  | 'DISCRETE' | 'RES CHIP 12.1K 1/16W +-1%(0402)AEC'               | 'CHIP0402'     | ''          | ''            | '20160116'
 '12.1K'      | '1%'      | '1/16W'  | '0402LF'  | 'EMPTY'  | 'CS31212FB06'(!)        = ''              | ''                 | 'CS31212FB06'           |'R0402'| '(R0402-0201)'                 | '12.1K'   | '1%'    | '1/16W'  | 'IO'       | 'RES CHIP 12.1K 1/16W +-1%(0402)AEC'               | 'CHIP0402'     | ''          | ''            | '20160116'
 '120'        | '1%'      | '1/16W'  | '0402LF'  | 'CHIP'   | 'CS11202FB04'(!)        = ''              | ''                 | 'CS11202FB04'           |'R0402'| '(R0402-0201)'                 | '120'     | '1%'    | '1/16W'  | 'DISCRETE' | 'RES CHIP 120 1/16W +-1%(0402)AEC'                 | 'CHIP0402'     | ''          | ''            | '20160116'
 '120'        | '1%'      | '1/16W'  | '0402LF'  | 'EMPTY'  | 'CS11202FB04'(!)        = ''              | ''                 | 'CS11202FB04'           |'R0402'| '(R0402-0201)'                 | '120'     | '1%'    | '1/16W'  | 'IO'       | 'RES CHIP 120 1/16W +-1%(0402)AEC'                 | 'CHIP0402'     | ''          | ''            | '20160116'
 '12K'        | '1%'      | '1/16W'  | '0402LF'  | 'CHIP'   | 'CS31202FB05'(!)        = ''              | ''                 | 'CS31202FB05'           |'R0402'| '(R0402-0201)'                 | '12K'     | '1%'    | '1/16W'  | 'DISCRETE' | 'RES CHIP 12K 1/16W +-1%(0402)AEC'                 | 'CHIP0402'     | ''          | ''            | '20160116'
 '12K'        | '1%'      | '1/16W'  | '0402LF'  | 'EMPTY'  | 'CS31202FB05'(!)        = ''              | ''                 | 'CS31202FB05'           |'R0402'| '(R0402-0201)'                 | '12K'     | '1%'    | '1/16W'  | 'IO'       | 'RES CHIP 12K 1/16W +-1%(0402)AEC'                 | 'CHIP0402'     | ''          | ''            | '20160116'
 '15'         | '1%'      | '1/16W'  | '0402LF'  | 'CHIP'   | 'CS01502FB04'(!)        = ''              | ''                 | 'CS01502FB04'           |'R0402'| '(R0402-0201)'                 | '15'      | '1%'    | '1/16W'  | 'DISCRETE' | 'RES CHIP 15 1/16W +-1%(0402)AEC'                  | 'CHIP0402'     | ''          | ''            | '20160116'
 '15'         | '1%'      | '1/16W'  | '0402LF'  | 'EMPTY'  | 'CS01502FB04'(!)        = ''              | ''                 | 'CS01502FB04'           |'R0402'| '(R0402-0201)'                 | '15'      | '1%'    | '1/16W'  | 'IO'       | 'RES CHIP 15 1/16W +-1%(0402)AEC'                  | 'CHIP0402'     | ''          | ''            | '20160116'
 '15.8K'      | '1%'      | '1/16W'  | '0402LF'  | 'CHIP'   | 'CS31582FB03'(!)        = ''              | ''                 | 'CS31582FB03'           |'R0402'| '(R0402-0201)'                 | '15.8K'   | '1%'    | '1/16W'  | 'DISCRETE' | 'RES CHIP 15.8K 1/16W +-1%(0402)AEC'               | 'CHIP0402'     | ''          | ''            | '20160116'
 '15.8K'      | '1%'      | '1/16W'  | '0402LF'  | 'EMPTY'  | 'CS31582FB03'(!)        = ''              | ''                 | 'CS31582FB03'           |'R0402'| '(R0402-0201)'                 | '15.8K'   | '1%'    | '1/16W'  | 'IO'       | 'RES CHIP 15.8K 1/16W +-1%(0402)AEC'               | 'CHIP0402'     | ''          | ''            | '20160116'
 '150'        | '1%'      | '1/16W'  | '0402LF'  | 'CHIP'   | 'CS11502FB08'(!)        = ''              | ''                 | 'CS11502FB08'           |'R0402'| '(R0402-0201)'                 | '150'     | '1%'    | '1/16W'  | 'DISCRETE' | 'RES CHIP 150 1/16W +-1%(0402)AEC'                 | 'CHIP0402'     | ''          | ''            | '20160116'
 '150'        | '1%'      | '1/16W'  | '0402LF'  | 'EMPTY'  | 'CS11502FB08'(!)        = ''              | ''                 | 'CS11502FB08'           |'R0402'| '(R0402-0201)'                 | '150'     | '1%'    | '1/16W'  | 'IO'       | 'RES CHIP 150 1/16W +-1%(0402)AEC'                 | 'CHIP0402'     | ''          | ''            | '20160116'
 '150'        | '5%'      | '1/16W'  | '0402LF'  | 'CHIP'   | 'CS11502JB03'(!)        = ''              | ''                 | 'CS11502JB03'           |'R0402'| '(R0402-0201)'                 | '150'     | '5%'    | '1/16W'  | 'DISCRETE' | 'RES CHIP 150 1/16W +-5%(0402)AEC'                 | 'CHIP0402'     | ''          | ''            | '20160116'
 '150'        | '5%'      | '1/16W'  | '0402LF'  | 'EMPTY'  | 'CS11502JB03'(!)        = ''              | ''                 | 'CS11502JB03'           |'R0402'| '(R0402-0201)'                 | '150'     | '5%'    | '1/16W'  | 'IO'       | 'RES CHIP 150 1/16W +-5%(0402)AEC'                 | 'CHIP0402'     | ''          | ''            | '20160116'
 '150K'       | '1%'      | '1/16W'  | '0402LF'  | 'CHIP'   | 'CS41502FB05'(!)        = ''              | ''                 | 'CS41502FB05'           |'R0402'| '(R0402-0201)'                 | '150K'    | '1%'    | '1/16W'  | 'DISCRETE' | 'RES CHIP 150K 1/16W +-1%(0402)AEC'                | 'CHIP0402'     | ''          | ''            | '20160116'
 '150K'       | '1%'      | '1/16W'  | '0402LF'  | 'EMPTY'  | 'CS41502FB05'(!)        = ''              | ''                 | 'CS41502FB05'           |'R0402'| '(R0402-0201)'                 | '150K'    | '1%'    | '1/16W'  | 'IO'       | 'RES CHIP 150K 1/16W +-1%(0402)AEC'                | 'CHIP0402'     | ''          | ''            | '20160116'
 '154K'       | '1%'      | '1/16W'  | '0402LF'  | 'CHIP'   | 'CS41542FB06'(!)        = ''              | ''                 | 'CS41542FB06'           |'R0402'| '(R0402-0201)'                 | '154K'    | '1%'    | '1/16W'  | 'DISCRETE' | 'RES CHIP 154K 1/16W +-1%(0402)AEC'                | 'CHIP0402'     | ''          | ''            | '20160116'
 '154K'       | '1%'      | '1/16W'  | '0402LF'  | 'EMPTY'  | 'CS41542FB06'(!)        = ''              | ''                 | 'CS41542FB06'           |'R0402'| '(R0402-0201)'                 | '154K'    | '1%'    | '1/16W'  | 'IO'       | 'RES CHIP 154K 1/16W +-1%(0402)AEC'                | 'CHIP0402'     | ''          | ''            | '20160116'
 '15K'        | '1%'      | '1/16W'  | '0402LF'  | 'CHIP'   | 'CS31502FB06'(!)        = ''              | ''                 | 'CS31502FB06'           |'R0402'| '(R0402-0201)'                 | '15K'     | '1%'    | '1/16W'  | 'DISCRETE' | 'RES CHIP 15K 1/16W +-1%(0402)AEC'                 | 'CHIP0402'     | ''          | ''            | '20160116'
 '15K'        | '1%'      | '1/16W'  | '0402LF'  | 'EMPTY'  | 'CS31502FB06'(!)        = ''              | ''                 | 'CS31502FB06'           |'R0402'| '(R0402-0201)'                 | '15K'     | '1%'    | '1/16W'  | 'IO'       | 'RES CHIP 15K 1/16W +-1%(0402)AEC'                 | 'CHIP0402'     | ''          | ''            | '20160116'
 '169'        | '1%'      | '1/16W'  | '0402LF'  | 'CHIP'   | 'CS11692FB02'(!)        = ''              | ''                 | 'CS11692FB02'           |'R0402'| '(R0402-0201)'                 | '169'     | '1%'    | '1/16W'  | 'DISCRETE' | 'RES CHIP 169 1/16W +-1%(0402)AEC'                 | 'CHIP0402'     | ''          | ''            | '20160116'
 '169'        | '1%'      | '1/16W'  | '0402LF'  | 'EMPTY'  | 'CS11692FB02'(!)        = ''              | ''                 | 'CS11692FB02'           |'R0402'| '(R0402-0201)'                 | '169'     | '1%'    | '1/16W'  | 'IO'       | 'RES CHIP 169 1/16W +-1%(0402)AEC'                 | 'CHIP0402'     | ''          | ''            | '20160116'
 '16K'        | '1%'      | '1/16W'  | '0402LF'  | 'CHIP'   | 'CS31602FB02'(!)        = ''              | ''                 | 'CS31602FB02'           |'R0402'| '(R0402-0201)'                 | '16K'     | '1%'    | '1/16W'  | 'DISCRETE' | 'RES CHIP 16K 1/16W +-1%(0402)AEC'                 | 'CHIP0402'     | ''          | ''            | '20160116'
 '16K'        | '1%'      | '1/16W'  | '0402LF'  | 'EMPTY'  | 'CS31602FB02'(!)        = ''              | ''                 | 'CS31602FB02'           |'R0402'| '(R0402-0201)'                 | '16K'     | '1%'    | '1/16W'  | 'IO'       | 'RES CHIP 16K 1/16W +-1%(0402)AEC'                 | 'CHIP0402'     | ''          | ''            | '20160116'
 '1K'         | '5%'      | '1/16W'  | '0402LF'  | 'CHIP'   | 'CS21002JB08'(!)        = ''              | ''                 | 'CS21002JB08'           |'R0402'| '(R0402-0201)'                 | '1K'      | '5%'    | '1/16W'  | 'DISCRETE' | 'RES CHIP 1K 1/16W +-5%(0402)AEC'                  | 'CHIP0402'     | ''          | ''            | '20160116'
 '1K'         | '5%'      | '1/16W'  | '0402LF'  | 'EMPTY'  | 'CS21002JB08'(!)        = ''              | ''                 | 'CS21002JB08'           |'R0402'| '(R0402-0201)'                 | '1K'      | '5%'    | '1/16W'  | 'IO'       | 'RES CHIP 1K 1/16W +-5%(0402)AEC'                  | 'CHIP0402'     | ''          | ''            | '20160116'
 '1M'         | '1%'      | '1/16W'  | '0402LF'  | 'CHIP'   | 'CS51002FB06'(!)        = ''              | ''                 | 'CS51002FB06'           |'R0402'| '(R0402-0201)'                 | '1M'      | '1%'    | '1/16W'  | 'DISCRETE' | 'RES CHIP 1M 1/16W +-1%(0402)AEC'                  | 'CHIP0402'     | ''          | ''            | '20160116'
 '1M'         | '1%'      | '1/16W'  | '0402LF'  | 'EMPTY'  | 'CS51002FB06'(!)        = ''              | ''                 | 'CS51002FB06'           |'R0402'| '(R0402-0201)'                 | '1M'      | '1%'    | '1/16W'  | 'IO'       | 'RES CHIP 1M 1/16W +-1%(0402)AEC'                  | 'CHIP0402'     | ''          | ''            | '20160116'
 '2'          | '1%'      | '1/16W'  | '0402LF'  | 'CHIP'   | 'CS-2002FB03'(!)        = ''              | ''                 | 'CS-2002FB03'           |'R0402'| '(R0402-0201)'                 | '2'       | '1%'    | '1/16W'  | 'DISCRETE' | 'RES CHIP 2 1/16W +-1%(0402)AEC'                   | 'CHIP0402'     | ''          | ''            | '20160116'
 '2'          | '1%'      | '1/16W'  | '0402LF'  | 'EMPTY'  | 'CS-2002FB03'(!)        = ''              | ''                 | 'CS-2002FB03'           |'R0402'| '(R0402-0201)'                 | '2'       | '1%'    | '1/16W'  | 'IO'       | 'RES CHIP 2 1/16W +-1%(0402)AEC'                   | 'CHIP0402'     | ''          | ''            | '20160116'
 '2.2K'       | '1%'      | '1/16W'  | '0402LF'  | 'CHIP'   | 'CS22202FB02'(!)        = ''              | ''                 | 'CS22202FB02'           |'R0402'| '(R0402-0201)'                 | '2.2K'    | '1%'    | '1/16W'  | 'DISCRETE' | 'RES CHIP 2.2K 1/16W +-1%(0402)AEC'                | 'CHIP0402'     | ''          | ''            | '20160116'
 '2.2K'       | '1%'      | '1/16W'  | '0402LF'  | 'EMPTY'  | 'CS22202FB02'(!)        = ''              | ''                 | 'CS22202FB02'           |'R0402'| '(R0402-0201)'                 | '2.2K'    | '1%'    | '1/16W'  | 'IO'       | 'RES CHIP 2.2K 1/16W +-1%(0402)AEC'                | 'CHIP0402'     | ''          | ''            | '20160116'
 '20'         | '1%'      | '1/16W'  | '0402LF'  | 'CHIP'   | 'CS02002FB04'(!)        = ''              | ''                 | 'CS02002FB04'           |'R0402'| '(R0402-0201)'                 | '20'      | '1%'    | '1/16W'  | 'DISCRETE' | 'RES CHIP 20 1/16W +-1%(0402)AEC'                  | 'CHIP0402'     | ''          | ''            | '20160116'
 '20'         | '1%'      | '1/16W'  | '0402LF'  | 'EMPTY'  | 'CS02002FB04'(!)        = ''              | ''                 | 'CS02002FB04'           |'R0402'| '(R0402-0201)'                 | '20'      | '1%'    | '1/16W'  | 'IO'       | 'RES CHIP 20 1/16W +-1%(0402)AEC'                  | 'CHIP0402'     | ''          | ''            | '20160116'
 '200'        | '1%'      | '1/16W'  | '0402LF'  | 'CHIP'   | 'CS12002FB12'(!)        = ''              | ''                 | 'CS12002FB12'           |'R0402'| '(R0402-0201)'                 | '200'     | '1%'    | '1/16W'  | 'DISCRETE' | 'RES CHIP 200 1/16W +-1%(0402)AEC'                 | 'CHIP0402'     | ''          | ''            | '20160116'
 '200'        | '1%'      | '1/16W'  | '0402LF'  | 'EMPTY'  | 'CS12002FB12'(!)        = ''              | ''                 | 'CS12002FB12'           |'R0402'| '(R0402-0201)'                 | '200'     | '1%'    | '1/16W'  | 'IO'       | 'RES CHIP 200 1/16W +-1%(0402)AEC'                 | 'CHIP0402'     | ''          | ''            | '20160116'
 '200K'       | '1%'      | '1/16W'  | '0402LF'  | 'CHIP'   | 'CS42002FB10'(!)        = ''              | ''                 | 'CS42002FB10'           |'R0402'| '(R0402-0201)'                 | '200K'    | '1%'    | '1/16W'  | 'DISCRETE' | 'RES CHIP 200K 1/16W +-1%(0402)AEC'                | 'CHIP0402'     | ''          | ''            | '20160116'
 '200K'       | '1%'      | '1/16W'  | '0402LF'  | 'EMPTY'  | 'CS42002FB10'(!)        = ''              | ''                 | 'CS42002FB10'           |'R0402'| '(R0402-0201)'                 | '200K'    | '1%'    | '1/16W'  | 'IO'       | 'RES CHIP 200K 1/16W +-1%(0402)AEC'                | 'CHIP0402'     | ''          | ''            | '20160116'
 '200'        | '0.1%'    | '1/16W'  | '0402LF'  | 'CHIP'   | 'CS12002BB01'(!)        = ''              | ''                 | 'CS12002BB01'           |'R0402'| '(R0402-0201)'                 | '200'     | '0.1%'  | '1/16W'  | 'DISCRETE' | 'RES CHIP 200 1/16W +-0.1%(0402)AEC'               | 'CHIP0402'     | ''          | ''            | '20160120'
 '200'        | '0.1%'    | '1/16W'  | '0402LF'  | 'EMPTY'  | 'CS12002BB01'(!)        = ''              | ''                 | 'CS12002BB01'           |'R0402'| '(R0402-0201)'                 | '200'     | '0.1%'  | '1/16W'  | 'IO'       | 'RES CHIP 200 1/16W +-0.1%(0402)AEC'               | 'CHIP0402'     | ''          | ''            | '20160120'
 '200'        | '0.1%'    | '1/16W'  | '0402LF'  | 'CHIP'   | 'CS12002BB00'(!)        = ''              | ''                 | 'CS12002BB00'           |'R0402'| '(R0402-0201)'                 | '200'     | '0.1%'  | '1/16W'  | 'DISCRETE' | 'RES CHIP 200 1/16W +-0.1% (0402)'                 | 'CHIP0402'     | ''          | ''            | '20160120'
 '200'        | '0.1%'    | '1/16W'  | '0402LF'  | 'EMPTY'  | 'CS12002BB00'(!)        = ''              | ''                 | 'CS12002BB00'           |'R0402'| '(R0402-0201)'                 | '200'     | '0.1%'  | '1/16W'  | 'IO'       | 'RES CHIP 200 1/16W +-0.1% (0402)'                 | 'CHIP0402'     | ''          | ''            | '20160120'
 '20K'        | '1%'      | '1/16W'  | '0402LF'  | 'CHIP'   | 'CS32002FB12'(!)        = ''              | ''                 | 'CS32002FB12'           |'R0402'| '(R0402-0201)'                 | '20K'     | '1%'    | '1/16W'  | 'DISCRETE' | 'RES CHIP 20K 1/16W +-1%(0402)AEC'                 | 'CHIP0402'     | ''          | ''            | '20160120'
 '20K'        | '1%'      | '1/16W'  | '0402LF'  | 'EMPTY'  | 'CS32002FB12'(!)        = ''              | ''                 | 'CS32002FB12'           |'R0402'| '(R0402-0201)'                 | '20K'     | '1%'    | '1/16W'  | 'IO'       | 'RES CHIP 20K 1/16W +-1%(0402)AEC'                 | 'CHIP0402'     | ''          | ''            | '20160120'
 '22'         | '1%'      | '1/16W'  | '0402LF'  | 'CHIP'   | 'CS02202FB03'(!)        = ''              | ''                 | 'CS02202FB03'           |'R0402'| '(R0402-0201)'                 | '22'      | '1%'    | '1/16W'  | 'DISCRETE' | 'RES CHIP 22 1/16W +-1%(0402)AEC'                  | 'CHIP0402'     | ''          | ''            | '20160120'
 '22'         | '1%'      | '1/16W'  | '0402LF'  | 'EMPTY'  | 'CS02202FB03'(!)        = ''              | ''                 | 'CS02202FB03'           |'R0402'| '(R0402-0201)'                 | '22'      | '1%'    | '1/16W'  | 'IO'       | 'RES CHIP 22 1/16W +-1%(0402)AEC'                  | 'CHIP0402'     | ''          | ''            | '20160120'
 '220'        | '5%'      | '1/16W'  | '0402LF'  | 'CHIP'   | 'CS12202JB04'(!)        = ''              | ''                 | 'CS12202JB04'           |'R0402'| '(R0402-0201)'                 | '220'     | '5%'    | '1/16W'  | 'DISCRETE' | 'RES CHIP 220 1/16W +-5%(0402)AEC'                 | 'CHIP0402'     | ''          | ''            | '20160120'
 '220'        | '5%'      | '1/16W'  | '0402LF'  | 'EMPTY'  | 'CS12202JB04'(!)        = ''              | ''                 | 'CS12202JB04'           |'R0402'| '(R0402-0201)'                 | '220'     | '5%'    | '1/16W'  | 'IO'       | 'RES CHIP 220 1/16W +-5%(0402)AEC'                 | 'CHIP0402'     | ''          | ''            | '20160120'
 '221'        | '1%'      | '1/16W'  | '0402LF'  | 'CHIP'   | 'CS12212FB04'(!)        = ''              | ''                 | 'CS12212FB04'           |'R0402'| '(R0402-0201)'                 | '221'     | '1%'    | '1/16W'  | 'DISCRETE' | 'RES CHIP 221 1/16W +-1%(0402)AEC'                 | 'CHIP0402'     | ''          | ''            | '20160120'
 '221'        | '1%'      | '1/16W'  | '0402LF'  | 'EMPTY'  | 'CS12212FB04'(!)        = ''              | ''                 | 'CS12212FB04'           |'R0402'| '(R0402-0201)'                 | '221'     | '1%'    | '1/16W'  | 'IO'       | 'RES CHIP 221 1/16W +-1%(0402)AEC'                 | 'CHIP0402'     | ''          | ''            | '20160120'
 '240'        | '1%'      | '1/16W'  | '0402LF'  | 'CHIP'   | 'CS12402FB02'(!)        = ''              | ''                 | 'CS12402FB02'           |'R0402'| '(R0402-0201)'                 | '240'     | '1%'    | '1/16W'  | 'DISCRETE' | 'RES CHIP 240 1/16W +-1%(0402)AEC'                 | 'CHIP0402'     | ''          | ''            | '20160120'
 '240'        | '1%'      | '1/16W'  | '0402LF'  | 'EMPTY'  | 'CS12402FB02'(!)        = ''              | ''                 | 'CS12402FB02'           |'R0402'| '(R0402-0201)'                 | '240'     | '1%'    | '1/16W'  | 'IO'       | 'RES CHIP 240 1/16W +-1%(0402)AEC'                 | 'CHIP0402'     | ''          | ''            | '20160120'
 '249'        | '0.1%'    | '1/16W'  | '0402LF'  | 'CHIP'   | 'CS12492BB03'(!)        = ''              | ''                 | 'CS12492BB03'           |'R0402'| '(R0402-0201)'                 | '249'     | '0.1%'  | '1/16W'  | 'DISCRETE' | 'RES CHIP 249 1/16W +-0.1%(0402)AEC'               | 'CHIP0402'     | ''          | ''            | '20160120'
 '249'        | '0.1%'    | '1/16W'  | '0402LF'  | 'EMPTY'  | 'CS12492BB03'(!)        = ''              | ''                 | 'CS12492BB03'           |'R0402'| '(R0402-0201)'                 | '249'     | '0.1%'  | '1/16W'  | 'IO'       | 'RES CHIP 249 1/16W +-0.1%(0402)AEC'               | 'CHIP0402'     | ''          | ''            | '20160120'
 '25.5K'      | '1%'      | '1/16W'  | '0402LF'  | 'CHIP'   | 'CS32552FB04'(!)        = ''              | ''                 | 'CS32552FB04'           |'R0402'| '(R0402-0201)'                 | '25.5K'   | '1%'    | '1/16W'  | 'DISCRETE' | 'RES CHIP 25.5K 1/16W +-1%(0402)AEC'               | 'CHIP0402'     | ''          | ''            | '20160120'
 '25.5K'      | '1%'      | '1/16W'  | '0402LF'  | 'EMPTY'  | 'CS32552FB04'(!)        = ''              | ''                 | 'CS32552FB04'           |'R0402'| '(R0402-0201)'                 | '25.5K'   | '1%'    | '1/16W'  | 'IO'       | 'RES CHIP 25.5K 1/16W +-1%(0402)AEC'               | 'CHIP0402'     | ''          | ''            | '20160120'
 '255K'       | '1%'      | '1/16W'  | '0402LF'  | 'CHIP'   | 'CS42552FB03'(!)        = ''              | ''                 | 'CS42552FB03'           |'R0402'| '(R0402-0201)'                 | '255K'    | '1%'    | '1/16W'  | 'DISCRETE' | 'RES CHIP 255K 1/16W +-1%(0402)AEC'                | 'CHIP0402'     | ''          | ''            | '20160121'
 '255K'       | '1%'      | '1/16W'  | '0402LF'  | 'EMPTY'  | 'CS42552FB03'(!)        = ''              | ''                 | 'CS42552FB03'           |'R0402'| '(R0402-0201)'                 | '255K'    | '1%'    | '1/16W'  | 'IO'       | 'RES CHIP 255K 1/16W +-1%(0402)AEC'                | 'CHIP0402'     | ''          | ''            | '20160121'
 '27.4'       | '1%'      | '1/16W'  | '0402LF'  | 'CHIP'   | 'CS02742FB04'(!)        = ''              | ''                 | 'CS02742FB04'           |'R0402'| '(R0402-0201)'                 | '27.4'    | '1%'    | '1/16W'  | 'DISCRETE' | 'RES CHIP 27.4 1/16W +-1%(0402)AEC'                | 'CHIP0402'     | ''          | ''            | '20160121'
 '27.4'       | '1%'      | '1/16W'  | '0402LF'  | 'EMPTY'  | 'CS02742FB04'(!)        = ''              | ''                 | 'CS02742FB04'           |'R0402'| '(R0402-0201)'                 | '27.4'    | '1%'    | '1/16W'  | 'IO'       | 'RES CHIP 27.4 1/16W +-1%(0402)AEC'                | 'CHIP0402'     | ''          | ''            | '20160121'
 '2K'         | '1%'      | '1/16W'  | '0402LF'  | 'CHIP'   | 'CS22002FB11'(!)        = ''              | ''                 | 'CS22002FB11'           |'R0402'| '(R0402-0201)'                 | '2K'      | '1%'    | '1/16W'  | 'DISCRETE' | 'RES CHIP 2K 1/16W +-1%(0402)AEC'                  | 'CHIP0402'     | ''          | ''            | '20160121'
 '2K'         | '1%'      | '1/16W'  | '0402LF'  | 'EMPTY'  | 'CS22002FB11'(!)        = ''              | ''                 | 'CS22002FB11'           |'R0402'| '(R0402-0201)'                 | '2K'      | '1%'    | '1/16W'  | 'IO'       | 'RES CHIP 2K 1/16W +-1%(0402)AEC'                  | 'CHIP0402'     | ''          | ''            | '20160121'
 '3.01K'      | '1%'      | '1/16W'  | '0402LF'  | 'CHIP'   | 'CS23012FB09'(!)        = ''              | ''                 | 'CS23012FB09'           |'R0402'| '(R0402-0201)'                 | '3.01K'   | '1%'    | '1/16W'  | 'DISCRETE' | 'RES CHIP 3.01K 1/16W +-1%(0402)AEC'               | 'CHIP0402'     | ''          | ''            | '20160121'
 '3.01K'      | '1%'      | '1/16W'  | '0402LF'  | 'EMPTY'  | 'CS23012FB09'(!)        = ''              | ''                 | 'CS23012FB09'           |'R0402'| '(R0402-0201)'                 | '3.01K'   | '1%'    | '1/16W'  | 'IO'       | 'RES CHIP 3.01K 1/16W +-1%(0402)AEC'               | 'CHIP0402'     | ''          | ''            | '20160121'
 '33'         | '1%'      | '1/16W'  | '0402LF'  | 'CHIP'   | 'CS03302FB04'(!)        = ''              | ''                 | 'CS03302FB04'           |'R0402'| '(R0402-0201)'                 | '33'      | '1%'    | '1/16W'  | 'DISCRETE' | 'RES CHIP 33 1/16W +-1%(0402)AEC'                  | 'CHIP0402'     | ''          | ''            | '20160121'
 '33'         | '1%'      | '1/16W'  | '0402LF'  | 'EMPTY'  | 'CS03302FB04'(!)        = ''              | ''                 | 'CS03302FB04'           |'R0402'| '(R0402-0201)'                 | '33'      | '1%'    | '1/16W'  | 'IO'       | 'RES CHIP 33 1/16W +-1%(0402)AEC'                  | 'CHIP0402'     | ''          | ''            | '20160121'
 '33'         | '5%'      | '1/16W'  | '0402LF'  | 'CHIP'   | 'CS03302JB09'(!)        = ''              | ''                 | 'CS03302JB09'           |'R0402'| '(R0402-0201)'                 | '33'      | '5%'    | '1/16W'  | 'DISCRETE' | 'RES CHIP 33 1/16W +-5% (0402)AEC'                 | 'CHIP0402'     | ''          | ''            | '20160121'
 '33'         | '5%'      | '1/16W'  | '0402LF'  | 'EMPTY'  | 'CS03302JB09'(!)        = ''              | ''                 | 'CS03302JB09'           |'R0402'| '(R0402-0201)'                 | '33'      | '5%'    | '1/16W'  | 'IO'       | 'RES CHIP 33 1/16W +-5% (0402)AEC'                 | 'CHIP0402'     | ''          | ''            | '20160121'
 '332'        | '1%'      | '1/16W'  | '0402LF'  | 'CHIP'   | 'CS13322FB06'(!)        = ''              | ''                 | 'CS13322FB06'           |'R0402'| '(R0402-0201)'                 | '332'     | '1%'    | '1/16W'  | 'DISCRETE' | 'RES CHIP 332 1/16W +-1%(0402)AEC'                 | 'CHIP0402'     | ''          | ''            | '20160121'
 '332'        | '1%'      | '1/16W'  | '0402LF'  | 'EMPTY'  | 'CS13322FB06'(!)        = ''              | ''                 | 'CS13322FB06'           |'R0402'| '(R0402-0201)'                 | '332'     | '1%'    | '1/16W'  | 'IO'       | 'RES CHIP 332 1/16W +-1%(0402)AEC'                 | 'CHIP0402'     | ''          | ''            | '20160121'
 '348'        | '1%'      | '1/16W'  | '0402LF'  | 'CHIP'   | 'CS13482FB03'(!)        = ''              | ''                 | 'CS13482FB03'           |'R0402'| '(R0402-0201)'                 | '348'     | '1%'    | '1/16W'  | 'DISCRETE' | 'RES CHIP 348 1/16W +-1%(0402)AEC'                 | 'CHIP0402'     | ''          | ''            | '20160121'
 '348'        | '1%'      | '1/16W'  | '0402LF'  | 'EMPTY'  | 'CS13482FB03'(!)        = ''              | ''                 | 'CS13482FB03'           |'R0402'| '(R0402-0201)'                 | '348'     | '1%'    | '1/16W'  | 'IO'       | 'RES CHIP 348 1/16W +-1%(0402)AEC'                 | 'CHIP0402'     | ''          | ''            | '20160121'
 '348K'       | '1%'      | '1/16W'  | '0402LF'  | 'CHIP'   | 'CS43482FB02'(!)        = ''              | ''                 | 'CS43482FB02'           |'R0402'| '(R0402-0201)'                 | '348K'    | '1%'    | '1/16W'  | 'DISCRETE' | 'RES CHIP 348K 1/16W +-1%(0402)AEC'                | 'CHIP0402'     | ''          | ''            | '20160121'
 '348K'       | '1%'      | '1/16W'  | '0402LF'  | 'EMPTY'  | 'CS43482FB02'(!)        = ''              | ''                 | 'CS43482FB02'           |'R0402'| '(R0402-0201)'                 | '348K'    | '1%'    | '1/16W'  | 'IO'       | 'RES CHIP 348K 1/16W +-1%(0402)AEC'                | 'CHIP0402'     | ''          | ''            | '20160121'
 '34K'        | '1%'      | '1/16W'  | '0402LF'  | 'CHIP'   | 'CS33402FB03'(!)        = ''              | ''                 | 'CS33402FB03'           |'R0402'| '(R0402-0201)'                 | '34K'     | '1%'    | '1/16W'  | 'DISCRETE' | 'RES CHIP 34K 1/16W +-1%(0402)AEC'                 | 'CHIP0402'     | ''          | ''            | '20160121'
 '34K'        | '1%'      | '1/16W'  | '0402LF'  | 'EMPTY'  | 'CS33402FB03'(!)        = ''              | ''                 | 'CS33402FB03'           |'R0402'| '(R0402-0201)'                 | '34K'     | '1%'    | '1/16W'  | 'IO'       | 'RES CHIP 34K 1/16W +-1%(0402)AEC'                 | 'CHIP0402'     | ''          | ''            | '20160121'
 '36'         | '5%'      | '1/16W'  | '0402LF'  | 'CHIP'   | 'CS03602JB02'(!)        = ''              | ''                 | 'CS03602JB02'           |'R0402'| '(R0402-0201)'                 | '36'      | '5%'    | '1/16W'  | 'DISCRETE' | 'RES CHIP 36 1/16W +-5%(0402)AEC'                  | 'CHIP0402'     | ''          | ''            | '20160201'
 '36'         | '5%'      | '1/16W'  | '0402LF'  | 'EMPTY'  | 'CS03602JB02'(!)        = ''              | ''                 | 'CS03602JB02'           |'R0402'| '(R0402-0201)'                 | '36'      | '5%'    | '1/16W'  | 'IO'       | 'RES CHIP 36 1/16W +-5%(0402)AEC'                  | 'CHIP0402'     | ''          | ''            | '20160201'
 '37.4K'      | '1%'      | '1/16W'  | '0402LF'  | 'CHIP'   | 'CS33742FB06'(!)        = ''              | ''                 | 'CS33742FB06'           |'R0402'| '(R0402-0201)'                 | '37.4K'   | '1%'    | '1/16W'  | 'DISCRETE' | 'RES CHIP 37.4K 1/16W +-1%(0402)AEC'               | 'CHIP0402'     | ''          | ''            | '20160201'
 '37.4K'      | '1%'      | '1/16W'  | '0402LF'  | 'EMPTY'  | 'CS33742FB06'(!)        = ''              | ''                 | 'CS33742FB06'           |'R0402'| '(R0402-0201)'                 | '37.4K'   | '1%'    | '1/16W'  | 'IO'       | 'RES CHIP 37.4K 1/16W +-1%(0402)AEC'               | 'CHIP0402'     | ''          | ''            | '20160201'
 '0.0003'     | '1%'      | '4W'     | '2725LF'  | 'CHIP'   | 'CS0000FFT04'(!)        = 'End of Design' | 'Comp-Approve'     | 'CS0000FFT04'           |'R2725'| '(SMR2725AW)'                  | '0.0003'  | '1%'    | '4W'     | 'DISCRETE' | 'RES CHIP 0.0003 4W +-1%(2725)'                    | 'CHIP2725'     | ''          | ''            | '20160201'
 '0.0003'     | '1%'      | '4W'     | '2725LF'  | 'EMPTY'  | 'CS0000FFT04'(!)        = 'End of Design' | 'Comp-Approve'     | 'CS0000FFT04'           |'R2725'| '(SMR2725AW)'                  | '0.0003'  | '1%'    | '4W'     | 'IO'       | 'RES CHIP 0.0003 4W +-1%(2725)'                    | 'CHIP2725'     | ''          | ''            | '20160201'
 '82K'        | '1%'      | '1/8W'   | '0805LF'  | 'CHIP'   | 'CS38204FA00'(!)        = ''              | ''                 | 'CS38204FA00'           |'R0805'| '(SMR0805AW)'                  | '82K'     | '1%'    | '1/8W'   | 'DISCRETE' | 'RES CHIP 82K 1/8W +-1%(0805)'                     | 'CHIP0805'     | ''          | ''            | '20160205'
 '82K'        | '1%'      | '1/8W'   | '0805LF'  | 'EMPTY'  | 'CS38204FA00'(!)        = ''              | ''                 | 'CS38204FA00'           |'R0805'| '(SMR0805AW)'                  | '82K'     | '1%'    | '1/8W'   | 'IO'       | 'RES CHIP 82K 1/8W +-1%(0805)'                     | 'CHIP0805'     | ''          | ''            | '20160205'
 '665K'       | '0.1%'    | '1/16W'  | '0402LF'  | 'CHIP'   | 'CS46652BB00'(!)        = ''              | ''                 | 'CS46652BB00'           |'R0402'| '(R0402-0201)'                 | '665K'    | '0.1%'  | '1/16W'  | 'DISCRETE' | 'RES CHIP 665K 1/16W +-0.1%(0402)'                 | 'CHIP0402'     | ''          | ''            | '20160205'
 '665K'       | '0.1%'    | '1/16W'  | '0402LF'  | 'EMPTY'  | 'CS46652BB00'(!)        = ''              | ''                 | 'CS46652BB00'           |'R0402'| '(R0402-0201)'                 | '665K'    | '0.1%'  | '1/16W'  | 'IO'       | 'RES CHIP 665K 1/16W +-0.1%(0402)'                 | 'CHIP0402'     | ''          | ''            | '20160205'
 '4.02'       | '1%'      | '1/16W'  | '0402LF'  | 'CHIP'   | 'CS-4022FB00'(!)        = ''              | ''                 | 'CS-4022FB00'           |'R0402'| '(R0402-0201)'                 | '4.02'    | '1%'    | '1/16W'  | 'DISCRETE' | 'RES CHIP 4.02 1/16W +-1%(0402)'                   | 'CHIP0402'     | ''          | ''            | '20160205'
 '4.02'       | '1%'      | '1/16W'  | '0402LF'  | 'EMPTY'  | 'CS-4022FB00'(!)        = ''              | ''                 | 'CS-4022FB00'           |'R0402'| '(R0402-0201)'                 | '4.02'    | '1%'    | '1/16W'  | 'IO'       | 'RES CHIP 4.02 1/16W +-1%(0402)'                   | 'CHIP0402'     | ''          | ''            | '20160205'
 '665K'       | '0.1%'    | '1/8W'   | '0805LF'  | 'CHIP'   | 'CS46654BA00'(!)        = ''              | ''                 | 'CS46654BA00'           |'R0805'| '(SMR0805AW)'                  | '665K'    | '0.1%'  | '1/8W'   | 'DISCRETE' | 'RES CHIP 665K 1/8W +-0.1%(0805)AEC'               | 'CHIP0805'     | ''          | ''            | '20160303'
 '665K'       | '0.1%'    | '1/8W'   | '0805LF'  | 'EMPTY'  | 'CS46654BA00'(!)        = ''              | ''                 | 'CS46654BA00'           |'R0805'| '(SMR0805AW)'                  | '665K'    | '0.1%'  | '1/8W'   | 'IO'       | 'RES CHIP 665K 1/8W +-0.1%(0805)AEC'               | 'CHIP0805'     | ''          | ''            | '20160303'
 '0.001'      | '1%'      | '3W'     | '2512LF'  | 'CHIP'   | 'CS+001DFR00'(!)        = ''              | ''                 | 'CS+001DFR00'           |'R2512XJ'| '(SMR2512AW)'                  | '0.001'   | '1%'    | '3W'     | 'DISCRETE' | 'RES CHIP 0.001 3W(+-1%,2512)'                     | 'CHIP2512'     | ''          | ''            | '20160303'
 '0.001'      | '1%'      | '3W'     | '2512LF'  | 'EMPTY'  | 'CS+001DFR00'(!)        = ''              | ''                 | 'CS+001DFR00'           |'R2512XJ'| '(SMR2512AW)'                  | '0.001'   | '1%'    | '3W'     | 'IO'       | 'RES CHIP 0.001 3W(+-1%,2512)'                     | 'CHIP2512'     | ''          | ''            | '20160303'
 '0.002'      | '1%'      | '1W'     | '1206LF'  | 'CHIP'   | 'CS+0028F201'(!)        = ''              | ''                 | 'CS+0028F201'           |'R1206XA'| '(SMR1206AW)'                  | '0.002'   | '1%'    | '1W'     | 'DISCRETE' | 'RES CHIP 0.002 1W +-1%(1206)'                     | 'CHIP1206'     | ''          | ''            | '20160307'
 '0.002'      | '1%'      | '1W'     | '1206LF'  | 'EMPTY'  | 'CS+0028F201'(!)        = ''              | ''                 | 'CS+0028F201'           |'R1206XA'| '(SMR1206AW)'                  | '0.002'   | '1%'    | '1W'     | 'IO'       | 'RES CHIP 0.002 1W +-1%(1206)'                     | 'CHIP1206'     | ''          | ''            | '20160307'
 '820'        | '1%'      | '1/4W'   | '0805LF'  | 'CHIP'   | 'CS18206FA00'(!)        = ''              | ''                 | 'CS18206FA00'           |'R0805'| '(SMR0805AW)'                  | '820'     | '1%'    | '1/4W'   | 'DISCRETE' | 'RES CHIP 820 1/4W +-1%(0805)'                     | 'CHIP0805'     | ''          | ''            | '20160310'
 '820'        | '1%'      | '1/4W'   | '0805LF'  | 'EMPTY'  | 'CS18206FA00'(!)        = ''              | ''                 | 'CS18206FA00'           |'R0805'| '(SMR0805AW)'                  | '820'     | '1%'    | '1/4W'   | 'IO'       | 'RES CHIP 820 1/4W +-1%(0805)'                     | 'CHIP0805'     | ''          | ''            | '20160310'
 '887'        | '1%'      | '1/16W'  | 'R0402LF' | 'CHIP'   | 'CS18872FB01'(!)        = 'End of Design' | 'Comp-Approve'     | 'CS18872FB01'           |'R0402'| '(R0402-0201)'                 | '887'     | '1%'    | '1/16W'  | 'DISCRETE' | 'RES CHIP 887 1/16W +-1%(0402)'                    | 'CHIP0402'     | ''          | ''            | '20160314'
 '887'        | '1%'      | '1/16W'  | 'R0402LF' | 'EMPTY'  | 'CS18872FB01'(!)        = 'End of Design' | 'Comp-Approve'     | 'CS18872FB01'           |'R0402'| '(R0402-0201)'                 | '887'     | '1%'    | '1/16W'  | 'IO'       | 'RES CHIP 887 1/16W +-1%(0402)'                    | 'CHIP0402'     | ''          | ''            | '20160314'
 '2.2'        | '1%'      | '1/10W'  | '0603LF'  | 'CHIP'   | 'CS-2203F901'(!)        = ''              | ''                 | 'CS-2203F901'           |'R0603'| '(SMR0603AW)'                  | '2.2'     | '1%'    | '1/10W'  | 'DISCRETE' | 'RES CHIP 2.2 1/10W +-1%(0603)AEC'                 | 'CHIPR0603'    | ''          | ''            | '20160315'
 '2.2'        | '1%'      | '1/10W'  | '0603LF'  | 'EMPTY'  | 'CS-2203F901'(!)        = ''              | ''                 | 'CS-2203F901'           |'R0603'| '(SMR0603AW)'                  | '2.2'     | '1%'    | '1/10W'  | 'IO'       | 'RES CHIP 2.2 1/10W +-1%(0603)AEC'                 | 'CHIPR0603'    | ''          | ''            | '20160315'
 '27'         | '1%'      | '1/16W'  | '0402LF'  | 'CHIP'   | 'CS02702FB11'(!)        = 'End of Design' | 'Comp-Approve'     | 'CS02702FB11'           |'R0402'| '(R0402-0201)'                 | '27'      | '1%'    | '1/16W'  | 'DISCRETE' | 'RES CHIP 27 1/16W +-1%(0402)'                     | 'CHIPR0402'    | ''          | ''            | '20160317'
 '27'         | '1%'      | '1/16W'  | '0402LF'  | 'EMPTY'  | 'CS02702FB11'(!)        = 'End of Design' | 'Comp-Approve'     | 'CS02702FB11'           |'R0402'| '(R0402-0201)'                 | '27'      | '1%'    | '1/16W'  | 'IO'       | 'RES CHIP 27 1/16W +-1%(0402)'                     | 'CHIPR0402'    | ''          | ''            | '20160317'
 '43K'        | '1%'      | '1/8W'   | '0805LF'  | 'CHIP'   | 'CS34304FA00'(!)        = ''              | ''                 | 'CS34304FA00'           |'R0805'| '(SMR0805AW)'                  | '43K'     | '1%'    | '1/8W'   | 'DISCRETE' | 'RES CHIP 43K 1/8W +-1% (0805)'                    | 'CHIPR0805'    | ''          | ''            | '20160321'
 '43K'        | '1%'      | '1/8W'   | '0805LF'  | 'EMPTY'  | 'CS34304FA00'(!)        = ''              | ''                 | 'CS34304FA00'           |'R0805'| '(SMR0805AW)'                  | '43K'     | '1%'    | '1/8W'   | 'IO'       | 'RES CHIP 43K 1/8W +-1% (0805)'                    | 'CHIPR0805'    | ''          | ''            | '20160321'
 '8.2'        | '5%'      | '1W'     | '2512LF'  | 'CHIP'   | 'CS00828JR00'(!)        = ''              | ''                 | 'CS00828JR00'           |'R2512XK'| '(SMR2512AW)'                  | '8.2'     | '5%'    | '1W'     | 'DISCRETE' | 'RES CHIP 8.2 1W +-5%(2512)'                       | 'CHIPR2512'    | ''          | ''            | '20160323'
 '8.2'        | '5%'      | '1W'     | '2512LF'  | 'EMPTY'  | 'CS00828JR00'(!)        = ''              | ''                 | 'CS00828JR00'           |'R2512XK'| '(SMR2512AW)'                  | '8.2'     | '5%'    | '1W'     | 'IO'       | 'RES CHIP 8.2 1W +-5%(2512)'                       | 'CHIPR2512'    | ''          | ''            | '20160323'
 '2.7M'       | '1%'      | '1/8W'   | '0805LF'  | 'CHIP'   | 'CS52704FA00'(!)        = ''              | ''                 | 'CS52704FA00'           |'R0805'| '(SMR0805AW)'                  | '2.7M'    | '1%'    | '1/8W'   | 'DISCRETE' | 'RES CHIP 2.7M(+-1%,1/8W,0805)TAI'                 | 'CHIPR0805'    | ''          | ''            | '20160325'
 '2.7M'       | '1%'      | '1/8W'   | '0805LF'  | 'EMPTY'  | 'CS52704FA00'(!)        = ''              | ''                 | 'CS52704FA00'           |'R0805'| '(SMR0805AW)'                  | '2.7M'    | '1%'    | '1/8W'   | 'IO'       | 'RES CHIP 2.7M(+-1%,1/8W,0805)TAI'                 | 'CHIPR0805'    | ''          | ''            | '20160325'
 '9.31K'      | '0.1%'    | '1/16W'  | '0402LF'  | 'CHIP'   | 'CS29312BB00'(!)        = 'End of Design' | 'Comp-Approve'     | 'CS29312BB00'           |'R0402'| '(R0402-0201)'                 | '9.31K'   | '0.1%'  | '1/16W'  | 'DISCRETE' | 'RES CHIP 9.31K 1/16W +-0.1%(0402)EF'              | 'CHIPR0402'    | ''          | ''            | '20160329'
 '9.31K'      | '0.1%'    | '1/16W'  | '0402LF'  | 'EMPTY'  | 'CS29312BB00'(!)        = 'End of Design' | 'Comp-Approve'     | 'CS29312BB00'           |'R0402'| '(R0402-0201)'                 | '9.31K'   | '0.1%'  | '1/16W'  | 'IO'       | 'RES CHIP 9.31K 1/16W +-0.1%(0402)EF'              | 'CHIPR0402'    | ''          | ''            | '20160329'
 '0.001'      | '1%'      | '1W'     | '2512LF'  | 'CHIP'   | 'CS+0018FR05'(!)        = ''              | ''                 | 'CS+0018FR05'           |'R2512XF'| '(SMR2512AW)'                  | '0.001'   | '1%'    | '1W'     | 'DISCRETE' | 'RES CHIP 0.001(+-1%,1W, 2512)TAI'                 | 'CHIPR2512'    | ''          | ''            | '20160411'
 '0.001'      | '1%'      | '1W'     | '2512LF'  | 'EMPTY'  | 'CS+0018FR05'(!)        = ''              | ''                 | 'CS+0018FR05'           |'R2512XF'| '(SMR2512AW)'                  | '0.001'   | '1%'    | '1W'     | 'IO'       | 'RES CHIP 0.001(+-1%,1W, 2512)TAI'                 | 'CHIPR2512'    | ''          | ''            | '20160411'
 '0.002'      | '1%'      | '1W'     | '2512LF'  | 'CHIP'   | 'CS+0028FR02'(!)        = ''              | ''                 | 'CS+0028FR02'           |'R2512XF'| '(SMR2512AW)'                  | '0.002'   | '1%'    | '1W'     | 'DISCRETE' | 'RES CHIP 0.002( +-1%,1W,2512)TAI'                 | 'CHIPR2512'    | ''          | ''            | '20160411'
 '0.002'      | '1%'      | '1W'     | '2512LF'  | 'EMPTY'  | 'CS+0028FR02'(!)        = ''              | ''                 | 'CS+0028FR02'           |'R2512XF'| '(SMR2512AW)'                  | '0.002'   | '1%'    | '1W'     | 'IO'       | 'RES CHIP 0.002( +-1%,1W,2512)TAI'                 | 'CHIPR2512'    | ''          | ''            | '20160411'
 '0.0005'     | '1%'      | '3W'     | '2512LF'  | 'CHIP'   | 'CS0000DFR04'(!)        = ''              | ''                 | 'CS0000DFR04'           |'R2512XF'| '(SMR2512AW)'                  | '0.0005'  | '1%'    | '3W'     | 'DISCRETE' | 'RES CHIP 0.0005(+-1%,3W,2512)TAI'                 | 'CHIPR2512'    | ''          | ''            | '20160411'
 '0.0005'     | '1%'      | '3W'     | '2512LF'  | 'EMPTY'  | 'CS0000DFR04'(!)        = ''              | ''                 | 'CS0000DFR04'           |'R2512XF'| '(SMR2512AW)'                  | '0.0005'  | '1%'    | '3W'     | 'IO'       | 'RES CHIP 0.0005(+-1%,3W,2512)TAI'                 | 'CHIPR2512'    | ''          | ''            | '20160411'
 '2.26K'      | '0.1%'    | '1/16W'  | '0402LF'  | 'CHIP'   | 'CS22262BB00'(!)        = ''              | ''                 | 'CS22262BB00'           |'R0402'| '(R0402-0201)'                 | '2.26K'   | '0.1%'  | '1/16W'  | 'DISCRETE' | 'RES CHIP 2.26K 1/16W +-0.1%(0402)'                | 'CHIPR0402'    | ''          | ''            | '20160415'
 '2.26K'      | '0.1%'    | '1/16W'  | '0402LF'  | 'EMPTY'  | 'CS22262BB00'(!)        = ''              | ''                 | 'CS22262BB00'           |'R0402'| '(R0402-0201)'                 | '2.26K'   | '0.1%'  | '1/16W'  | 'IO'       | 'RES CHIP 2.26K 1/16W +-0.1%(0402)'                | 'CHIPR0402'    | ''          | ''            | '20160415'
 '0.008'      | '1%'      | '3W'     | '2512LF'  | 'CHIP'   | 'CS+008DFR02'(!)        = ''              | ''                 | 'CS+008DFR02'           |'R2512XL'| '(SMR2512AW)'                  | '0.008'   | '1%'    | '3W'     | 'DISCRETE' | 'RES CHIP 0.008(+-1%,3W,2512)TAI'                  | 'CHIPR2512'    | ''          | ''            | '20160419'
 '0.008'      | '1%'      | '3W'     | '2512LF'  | 'EMPTY'  | 'CS+008DFR02'(!)        = ''              | ''                 | 'CS+008DFR02'           |'R2512XL'| '(SMR2512AW)'                  | '0.008'   | '1%'    | '3W'     | 'IO'       | 'RES CHIP 0.008(+-1%,3W,2512)TAI'                  | 'CHIPR2512'    | ''          | ''            | '20160419'
 '0.02'       | '1%'      | '1/2W'   | '0805LF'  | 'CHIP'   | 'CS+0207FA00'(!)        = 'End of Design' | 'Comp-Approve'     | 'CS+0207FA00'           |'R0805XA'| '(SMR0805AW)'                  | '0.02'    | '1%'    | '1/2W'   | 'DISCRETE' | 'RES CHIP 0.02 1/2W +-1% (0805)'                   | 'CHIPR0805'    | ''          | ''            | '20160420'
 '0.02'       | '1%'      | '1/2W'   | '0805LF'  | 'EMPTY'  | 'CS+0207FA00'(!)        = 'End of Design' | 'Comp-Approve'     | 'CS+0207FA00'           |'R0805XA'| '(SMR0805AW)'                  | '0.02'    | '1%'    | '1/2W'   | 'IO'       | 'RES CHIP 0.02 1/2W +-1% (0805)'                   | 'CHIPR0805'    | ''          | ''            | '20160420'
 '787K'       | '1%'      | '1/16W'  | '0402LF'  | 'CHIP'   | 'CS47872FB00'(!)        = 'End of Design' | 'Comp-Approve'     | 'CS47872FB00'           |'R0402'| '(R0402-0201)'                 | '787K'    | '1%'    | '1/16W'  | 'DISCRETE' | 'RES CHIP 787K 1/16W +-1%(0402)'                   | 'CHIPR0402'    | ''          | ''            | '20160421'
 '787K'       | '1%'      | '1/16W'  | '0402LF'  | 'EMPTY'  | 'CS47872FB00'(!)        = 'End of Design' | 'Comp-Approve'     | 'CS47872FB00'           |'R0402'| '(R0402-0201)'                 | '787K'    | '1%'    | '1/16W'  | 'IO'       | 'RES CHIP 787K 1/16W +-1%(0402)'                   | 'CHIPR0402'    | ''          | ''            | '20160421'
 '7.5'        | '1%'      | '2W'     | '2512LF'  | 'CHIP'   | 'CS-750AFR01'(!)        = ''              | ''                 | 'CS-750AFR01'           |'R2512XK'| '(SMR2512AW)'                  | '7.5'     | '1%'    | '2W'     | 'DISCRETE' | 'RES CHIP 7.5 2W +-1%(2512)'                       | 'CHIPR2512'    | ''          | ''            | '20160426'
 '7.5'        | '1%'      | '2W'     | '2512LF'  | 'EMPTY'  | 'CS-750AFR01'(!)        = ''              | ''                 | 'CS-750AFR01'           |'R2512XK'| '(SMR2512AW)'                  | '7.5'     | '1%'    | '2W'     | 'IO'       | 'RES CHIP 7.5 2W +-1%(2512)'                       | 'CHIPR2512'    | ''          | ''            | '20160426'
 '0.003'      | '1%'      | '4W'     | '2725LF'  | 'CHIP'   | 'CS+003FFT00'(!)        = 'End of Design' | 'Comp-Approve'     | 'CS+003FFT00'           |'R2725'| '(SMR2725AW)'                  | '0.003'   | '1%'    | '4W'     | 'DISCRETE' | 'RES CHIP 0.003 4W +-1% (2725)EF'                  | 'CHIPR2725'    | ''          | ''            | '20160426'
 '0.003'      | '1%'      | '4W'     | '2725LF'  | 'EMPTY'  | 'CS+003FFT00'(!)        = 'End of Design' | 'Comp-Approve'     | 'CS+003FFT00'           |'R2725'| '(SMR2725AW)'                  | '0.003'   | '1%'    | '4W'     | 'IO'       | 'RES CHIP 0.003 4W +-1% (2725)EF'                  | 'CHIPR2725'    | ''          | ''            | '20160426'
 '3.3'        | '1%'      | '1/10W'  | '0603LF'  | 'CHIP'   | 'CS-3303F901'(!)        = ''              | ''                 | 'CS-3303F901'           |'R0603'| '(SMR0603AW)'                  | '3.3'     | '1%'    | '1/10W'  | 'DISCRETE' | 'RES CHIP 3.3 1/10W +-1%(0603)AEC'                 | 'CHIPR0603'    | ''          | ''            | '20160503'
 '3.3'        | '1%'      | '1/10W'  | '0603LF'  | 'EMPTY'  | 'CS-3303F901'(!)        = ''              | ''                 | 'CS-3303F901'           |'R0603'| '(SMR0603AW)'                  | '3.3'     | '1%'    | '1/10W'  | 'IO'       | 'RES CHIP 3.3 1/10W +-1%(0603)AEC'                 | 'CHIPR0603'    | ''          | ''            | '20160503'
 '3.3'        | '1%'      | '1/16W'  | '0402LF'  | 'CHIP'   | 'CS-3302FB02'(!)        = ''              | ''                 | 'CS-3302FB02'           |'R0402'| '(R0402-0201)'                 | '3.3'     | '1%'    | '1/16W'  | 'DISCRETE' | 'RES CHIP 3.3 1/16W +-1%(0402)AEC'                 | 'CHIPR0402'    | ''          | ''            | '20160503'
 '3.3'        | '1%'      | '1/16W'  | '0402LF'  | 'EMPTY'  | 'CS-3302FB02'(!)        = ''              | ''                 | 'CS-3302FB02'           |'R0402'| '(R0402-0201)'                 | '3.3'     | '1%'    | '1/16W'  | 'IO'       | 'RES CHIP 3.3 1/16W +-1%(0402)AEC'                 | 'CHIPR0402'    | ''          | ''            | '20160503'
 '2.2'        | '1%'      | '1/4W'   | '1206LF'  | 'CHIP'   | 'CS-2206F201'(!)        = ''              | ''                 | 'CS-2206F201'           |'R1206'| '(SMR1206AW)'                  | '2.2'     | '1%'    | '1/4W'   | 'DISCRETE' | 'RES CHIP 2.2 1/4W +-1%(1206)AEC'                  | 'CHIPR1206'    | ''          | ''            | '20160503'
 '2.2'        | '1%'      | '1/4W'   | '1206LF'  | 'EMPTY'  | 'CS-2206F201'(!)        = ''              | ''                 | 'CS-2206F201'           |'R1206'| '(SMR1206AW)'                  | '2.2'     | '1%'    | '1/4W'   | 'IO'       | 'RES CHIP 2.2 1/4W +-1%(1206)AEC'                  | 'CHIPR1206'    | ''          | ''            | '20160503'
 '0'          | ''        | '1/8W'   | '0805LF'  | 'CHIP'   | 'CS00004TA02'(!)        = 'End of Design' | 'Comp-Approve'     | 'CS00004TA02'           |'R0805'| '(SMR0805AW)'                  | '0'       | ''      | '1/8W'   | 'DISCRETE' | 'RESISTOR CHIP 0 1/8W(0805)'                       | 'CHIPR0805'    | ''          | ''            | '20160511'
 '0'          | ''        | '1/8W'   | '0805LF'  | 'EMPTY'  | 'CS00004TA02'(!)        = 'End of Design' | 'Comp-Approve'     | 'CS00004TA02'           |'R0805'| '(SMR0805AW)'                  | '0'       | ''      | '1/8W'   | 'IO'       | 'RESISTOR CHIP 0 1/8W(0805)'                       | 'CHIPR0805'    | ''          | ''            | '20160511'
 '825K'       | '1%'      | '1/20W'  | '0201LF'  | 'CHIP'   | 'CS48251FE00'(!)        = ''              | ''                 | 'CS48251FE00'           |'R0201'| '(SMR0201AW)'                  | '825K'    | '1%'    | '1/20W'  | 'DISCRETE' | 'RESISTOR CHIP 825K 1/20W+-1%(0201)'               | 'CHIPR0201'    | ''          | ''            | '20160512'
 '825K'       | '1%'      | '1/20W'  | '0201LF'  | 'EMPTY'  | 'CS48251FE00'(!)        = ''              | ''                 | 'CS48251FE00'           |'R0201'| '(SMR0201AW)'                  | '825K'    | '1%'    | '1/20W'  | 'IO'       | 'RESISTOR CHIP 825K 1/20W+-1%(0201)'               | 'CHIPR0201'    | ''          | ''            | '20160512'
 '220'        | '5%'      | '1/10W'  | '0603LF'  | 'CHIP'   | 'CS12203J947'(!)        = ''              | ''                 | 'CS12203J947'           |'R0603'| '(SMR0603AW)'                  | '220'     | '5%'    | '1/10W'  | 'DISCRETE' | 'RES CHIP 220 1/10W +-5%(0603) EP'                 | 'CHIPR0603'    | ''          | ''            | '20160616'
 '220'        | '5%'      | '1/10W'  | '0603LF'  | 'EMPTY'  | 'CS12203J947'(!)        = ''              | ''                 | 'CS12203J947'           |'R0603'| '(SMR0603AW)'                  | '220'     | '5%'    | '1/10W'  | 'IO'       | 'RES CHIP 220 1/10W +-5%(0603) EP'                 | 'CHIPR0603'    | ''          | ''            | '20160616'
 '267K'       | '1%'      | '1/16W'  | '0402LF'  | 'CHIP'   | 'CS42672FB16'(!)        = 'End of Design' | 'Comp-Approve'     | 'CS42672FB16'           |'R0402'| '(R0402-0201)'                 | '267K'    | '1%'    | '1/16W'  | 'DISCRETE' | 'RES CHIP 267K 1/16W +-1%(0402)'                   | 'CHIPR0402'    | ''          | ''            | '20160617'
 '267K'       | '1%'      | '1/16W'  | '0402LF'  | 'EMPTY'  | 'CS42672FB16'(!)        = 'End of Design' | 'Comp-Approve'     | 'CS42672FB16'           |'R0402'| '(R0402-0201)'                 | '267K'    | '1%'    | '1/16W'  | 'IO'       | 'RES CHIP 267K 1/16W +-1%(0402)'                   | 'CHIPR0402'    | ''          | ''            | '20160617'
 '5.9K'       | '0.1%'    | '1/16W'  | '0402LF'  | 'CHIP'   | 'CS25902BB02'(!)        = 'Non-Preferred' | 'End of Life'      | 'CS25902BB02'           |'R0402_EOL'| '(R0402-0201)'                 | '5.9K'    | '0.1%'  | '1/16W'  | 'DISCRETE' | 'RES CHIP 5.9K 1/16W +-0.1% (0402)DAL_AEC'         | 'CHIPR0402'    | ''          | ''            | '20160628'
 '5.9K'       | '0.1%'    | '1/16W'  | '0402LF'  | 'EMPTY'  | 'CS25902BB02'(!)        = 'Non-Preferred' | 'End of Life'      | 'CS25902BB02'           |'R0402_EOL'| '(R0402-0201)'                 | '5.9K'    | '0.1%'  | '1/16W'  | 'IO'       | 'RES CHIP 5.9K 1/16W +-0.1% (0402)DAL_AEC'         | 'CHIPR0402'    | ''          | ''            | '20160628'
 '10K'        | '0.1%'    | '1/16W'  | '0402LF'  | 'CHIP'   | 'CS31002BB07'(!)        = 'Non-Preferred' | 'End of Life'      | 'CS31002BB07'           |'R0402_EOL'| '(R0402-0201)'                 | '10K'     | '0.1%'  | '1/16W'  | 'DISCRETE' | 'RES CHIP 10K 1/16W +-0.1%(0402)DAL_AEC'           | 'CHIPR0402'    | ''          | ''            | '20160628'
 '10K'        | '0.1%'    | '1/16W'  | '0402LF'  | 'EMPTY'  | 'CS31002BB07'(!)        = 'Non-Preferred' | 'End of Life'      | 'CS31002BB07'           |'R0402_EOL'| '(R0402-0201)'                 | '10K'     | '0.1%'  | '1/16W'  | 'IO'       | 'RES CHIP 10K 1/16W +-0.1%(0402)DAL_AEC'           | 'CHIPR0402'    | ''          | ''            | '20160628'
 '100K'       | '0.1%'    | '1/16W'  | '0402LF'  | 'CHIP'   | 'CS41002BB03'(!)        = 'Non-Preferred' | 'End of Life'      | 'CS41002BB03'           |'R0402_EOL'| '(R0402-0201)'                 | '100K'    | '0.1%'  | '1/16W'  | 'DISCRETE' | 'RES CHIP 100K 1/16W +-0.1%(0402)DAL_AEC'          | 'CHIPR0402'    | ''          | ''            | '20160628'
 '100K'       | '0.1%'    | '1/16W'  | '0402LF'  | 'EMPTY'  | 'CS41002BB03'(!)        = 'Non-Preferred' | 'End of Life'      | 'CS41002BB03'           |'R0402_EOL'| '(R0402-0201)'                 | '100K'    | '0.1%'  | '1/16W'  | 'IO'       | 'RES CHIP 100K 1/16W +-0.1%(0402)DAL_AEC'          | 'CHIPR0402'    | ''          | ''            | '20160628'
 '249'        | '0.1%'    | '1/16W'  | '0402LF'  | 'CHIP'   | 'CS12492BB04'(!)        = 'Non-Preferred' | 'End of Life'      | 'CS12492BB04'           |'R0402_EOL'| '(R0402-0201)'                 | '249'     | '0.1%'  | '1/16W'  | 'DISCRETE' | 'RES CHIP 249 1/16W +-0.1%(0402)DAL_AEC'           | 'CHIPR0402'    | ''          | ''            | '20160628'
 '249'        | '0.1%'    | '1/16W'  | '0402LF'  | 'EMPTY'  | 'CS12492BB04'(!)        = 'Non-Preferred' | 'End of Life'      | 'CS12492BB04'           |'R0402_EOL'| '(R0402-0201)'                 | '249'     | '0.1%'  | '1/16W'  | 'IO'       | 'RES CHIP 249 1/16W +-0.1%(0402)DAL_AEC'           | 'CHIPR0402'    | ''          | ''            | '20160628'
 '15'         | '5%'      | '1/16W'  | '0402LF'  | 'CHIP'   | 'CS01502JB06'(!)        = ''              | ''                 | 'CS01502JB06'           |'R0402'| '(R0402-0201)'                 | '15'      | '5%'    | '1/16W'  | 'DISCRETE' | 'RES CHIP 15 1/16W +-5%(0402)DAL_AEC'              | 'CHIPR0402'    | ''          | ''            | '20160628'
 '15'         | '5%'      | '1/16W'  | '0402LF'  | 'EMPTY'  | 'CS01502JB06'(!)        = ''              | ''                 | 'CS01502JB06'           |'R0402'| '(R0402-0201)'                 | '15'      | '5%'    | '1/16W'  | 'IO'       | 'RES CHIP 15 1/16W +-5%(0402)DAL_AEC'              | 'CHIPR0402'    | ''          | ''            | '20160628'
 '10'         | '5%'      | '1/16W'  | '0402LF'  | 'CHIP'   | 'CS01002JB08'(!)        = ''              | ''                 | 'CS01002JB08'           |'R0402'| '(R0402-0201)'                 | '10'      | '5%'    | '1/16W'  | 'DISCRETE' | 'RES CHIP 10 1/16W +5%(0402)DAL_AEC'               | 'CHIPR0402'    | ''          | ''            | '20160628'
 '10'         | '5%'      | '1/16W'  | '0402LF'  | 'EMPTY'  | 'CS01002JB08'(!)        = ''              | ''                 | 'CS01002JB08'           |'R0402'| '(R0402-0201)'                 | '10'      | '5%'    | '1/16W'  | 'IO'       | 'RES CHIP 10 1/16W +5%(0402)DAL_AEC'               | 'CHIPR0402'    | ''          | ''            | '20160628'
 '200'        | '0.1%'    | '1/16W'  | '0402LF'  | 'CHIP'   | 'CS12002BB02'(!)        = 'Non-Preferred' | 'End of Life'      | 'CS12002BB02'           |'R0402_EOL'| '(R0402-0201)'                 | '200'     | '0.1%'  | '1/16W'  | 'DISCRETE' | 'RES CHIP 200 1/16W +0.1% (0402)DAL_AEC'           | 'CHIPR0402'    | ''          | ''            | '20160629'
 '200'        | '0.1%'    | '1/16W'  | '0402LF'  | 'EMPTY'  | 'CS12002BB02'(!)        = 'Non-Preferred' | 'End of Life'      | 'CS12002BB02'           |'R0402_EOL'| '(R0402-0201)'                 | '200'     | '0.1%'  | '1/16W'  | 'IO'       | 'RES CHIP 200 1/16W +0.1% (0402)DAL_AEC'           | 'CHIPR0402'    | ''          | ''            | '20160629'
 '1'          | '5%'      | '1/16W'  | '0402LF'  | 'CHIP'   | 'CS-1002JB07'(!)        = ''              | ''                 | 'CS-1002JB07'           |'R0402'| '(R0402-0201)'                 | '1'       | '5%'    | '1/16W'  | 'DISCRETE' | 'RES CHIP 1 1/16W +-5%(0402) DAL_AEC'              | 'CHIPR0402'    | ''          | ''            | '20160629'
 '1'          | '5%'      | '1/16W'  | '0402LF'  | 'EMPTY'  | 'CS-1002JB07'(!)        = ''              | ''                 | 'CS-1002JB07'           |'R0402'| '(R0402-0201)'                 | '1'       | '5%'    | '1/16W'  | 'IO'       | 'RES CHIP 1 1/16W +-5%(0402) DAL_AEC'              | 'CHIPR0402'    | ''          | ''            | '20160629'
 '100'        | '0.1%'    | '1/16W'  | '0402LF'  | 'CHIP'   | 'CS11002BB03'(!)        = 'Non-Preferred' | 'End of Life'      | 'CS11002BB03'           |'R0402_EOL'| '(R0402-0201)'                 | '100'     | '0.1%'  | '1/16W'  | 'DISCRETE' | 'RES CHIP 100 1/16W +-0.1%(0402) DAL_AEC'          | 'CHIPR0402'    | ''          | ''            | '20160629'
 '100'        | '0.1%'    | '1/16W'  | '0402LF'  | 'EMPTY'  | 'CS11002BB03'(!)        = 'Non-Preferred' | 'End of Life'      | 'CS11002BB03'           |'R0402_EOL'| '(R0402-0201)'                 | '100'     | '0.1%'  | '1/16W'  | 'IO'       | 'RES CHIP 100 1/16W +-0.1%(0402) DAL_AEC'          | 'CHIPR0402'    | ''          | ''            | '20160629'
 '220'        | '5%'      | '1/16W'  | '0402LF'  | 'CHIP'   | 'CS12202JB05'(!)        = ''              | ''                 | 'CS12202JB05'           |'R0402'| '(R0402-0201)'                 | '220'     | '5%'    | '1/16W'  | 'DISCRETE' | 'RES CHIP 220 1/16W +-5%(0402)DAL_AEC'             | 'CHIPR0402'    | ''          | ''            | '20160629'
 '220'        | '5%'      | '1/16W'  | '0402LF'  | 'EMPTY'  | 'CS12202JB05'(!)        = ''              | ''                 | 'CS12202JB05'           |'R0402'| '(R0402-0201)'                 | '220'     | '5%'    | '1/16W'  | 'IO'       | 'RES CHIP 220 1/16W +-5%(0402)DAL_AEC'             | 'CHIPR0402'    | ''          | ''            | '20160629'
 '0'          | ''        | '1/16W'  | '0402LF'  | 'CHIP'   | 'CS00002TB01'(!)        = ''              | ''                 | 'CS00002TB01'           |'R0402'| '(R0402-0201)'                 | '0'       | ''      | '1/16W'  | 'DISCRETE' | 'RES CHIP 0 1/16W (0402) DAL_AEC'                  | 'CHIPR0402'    | ''          | ''            | '20160630'
 '0'          | ''        | '1/16W'  | '0402LF'  | 'EMPTY'  | 'CS00002TB01'(!)        = ''              | ''                 | 'CS00002TB01'           |'R0402'| '(R0402-0201)'                 | '0'       | ''      | '1/16W'  | 'IO'       | 'RES CHIP 0 1/16W (0402) DAL_AEC'                  | 'CHIPR0402'    | ''          | ''            | '20160630'
 '10'         | '1%'      | '1/16W'  | '0402LF'  | 'CHIP'   | 'CS01002FB13'(!)        = ''              | ''                 | 'CS01002FB13'           |'R0402'| '(R0402-0201)'                 | '10'      | '1%'    | '1/16W'  | 'DISCRETE' | 'RES CHIP 10 1/16W +-1%(0402) DAL_AEC'             | 'CHIPR0402'    | ''          | ''            | '20160630'
 '10'         | '1%'      | '1/16W'  | '0402LF'  | 'EMPTY'  | 'CS01002FB13'(!)        = ''              | ''                 | 'CS01002FB13'           |'R0402'| '(R0402-0201)'                 | '10'      | '1%'    | '1/16W'  | 'IO'       | 'RES CHIP 10 1/16W +-1%(0402) DAL_AEC'             | 'CHIPR0402'    | ''          | ''            | '20160630'
 '15'         | '1%'      | '1/16W'  | '0402LF'  | 'CHIP'   | 'CS01502FB05'(!)        = ''              | ''                 | 'CS01502FB05'           |'R0402'| '(R0402-0201)'                 | '15'      | '1%'    | '1/16W'  | 'DISCRETE' | 'RES CHIP 15 1/16W +-1%(0402)DAL_AEC'              | 'CHIPR0402'    | ''          | ''            | '20160630'
 '15'         | '1%'      | '1/16W'  | '0402LF'  | 'EMPTY'  | 'CS01502FB05'(!)        = ''              | ''                 | 'CS01502FB05'           |'R0402'| '(R0402-0201)'                 | '15'      | '1%'    | '1/16W'  | 'IO'       | 'RES CHIP 15 1/16W +-1%(0402)DAL_AEC'              | 'CHIPR0402'    | ''          | ''            | '20160630'
 '21'         | '1%'      | '1/16W'  | '0402LF'  | 'CHIP'   | 'CS02102FB05'(!)        = ''              | ''                 | 'CS02102FB05'           |'R0402'| '(R0402-0201)'                 | '21'      | '1%'    | '1/16W'  | 'DISCRETE' | 'RES CHIP 21 1/16W +-1%(0402)DAL_AEC'              | 'CHIPR0402'    | ''          | ''            | '20160630'
 '21'         | '1%'      | '1/16W'  | '0402LF'  | 'EMPTY'  | 'CS02102FB05'(!)        = ''              | ''                 | 'CS02102FB05'           |'R0402'| '(R0402-0201)'                 | '21'      | '1%'    | '1/16W'  | 'IO'       | 'RES CHIP 21 1/16W +-1%(0402)DAL_AEC'              | 'CHIPR0402'    | ''          | ''            | '20160630'
 '22'         | '1%'      | '1/16W'  | '0402LF'  | 'CHIP'   | 'CS02202FB05'(!)        = ''              | ''                 | 'CS02202FB05'           |'R0402'| '(R0402-0201)'                 | '22'      | '1%'    | '1/16W'  | 'DISCRETE' | 'RES CHIP 22 1/16W +-1%(0402)DAL_AEC'              | 'CHIPR0402'    | ''          | ''            | '20160630'
 '22'         | '1%'      | '1/16W'  | '0402LF'  | 'EMPTY'  | 'CS02202FB05'(!)        = ''              | ''                 | 'CS02202FB05'           |'R0402'| '(R0402-0201)'                 | '22'      | '1%'    | '1/16W'  | 'IO'       | 'RES CHIP 22 1/16W +-1%(0402)DAL_AEC'              | 'CHIPR0402'    | ''          | ''            | '20160630'
 '27.4'       | '1%'      | '1/16W'  | '0402LF'  | 'CHIP'   | 'CS02742FB05'(!)        = ''              | ''                 | 'CS02742FB05'           |'R0402'| '(R0402-0201)'                 | '27.4'    | '1%'    | '1/16W'  | 'DISCRETE' | 'RES CHIP 27.4 1/16W +-1%(0402)DAL_AEC'            | 'CHIPR0402'    | ''          | ''            | '20160630'
 '27.4'       | '1%'      | '1/16W'  | '0402LF'  | 'EMPTY'  | 'CS02742FB05'(!)        = ''              | ''                 | 'CS02742FB05'           |'R0402'| '(R0402-0201)'                 | '27.4'    | '1%'    | '1/16W'  | 'IO'       | 'RES CHIP 27.4 1/16W +-1%(0402)DAL_AEC'            | 'CHIPR0402'    | ''          | ''            | '20160630'
 '0.001'      | '1%'      | '1W'     | '2512LF'  | 'CHIP'   | 'CS+0018FR04'(!)        = ''              | ''                 | 'CS+0018FR04'           |'R2512A'| '(SMR2512AW)'                  | '0.001'   | '1%'    | '1W'     | 'DISCRETE' | 'RES CHIP 0.001 1W +-1% (2512)'                    | 'CHIPR2512'    | ''          | ''            | '20160705'
 '0.001'      | '1%'      | '1W'     | '2512LF'  | 'EMPTY'  | 'CS+0018FR04'(!)        = ''              | ''                 | 'CS+0018FR04'           |'R2512A'| '(SMR2512AW)'                  | '0.001'   | '1%'    | '1W'     | 'IO'       | 'RES CHIP 0.001 1W +-1% (2512)'                    | 'CHIPR2512'    | ''          | ''            | '20160705'
 '20'         | '1%'      | '1/16W'  | '0402LF'  | 'CHIP'   | 'CS02002FB05'(!)        = ''              | ''                 | 'CS02002FB05'           |'R0402'| '(R0402-0201)'                 | '20'      | '1%'    | '1/16W'  | 'DISCRETE' | 'RES CHIP 20 1/16W +-1%(0402)DAL_AEC'              | 'CHIPR0402'    | ''          | ''            | '20160706'
 '20'         | '1%'      | '1/16W'  | '0402LF'  | 'EMPTY'  | 'CS02002FB05'(!)        = ''              | ''                 | 'CS02002FB05'           |'R0402'| '(R0402-0201)'                 | '20'      | '1%'    | '1/16W'  | 'IO'       | 'RES CHIP 20 1/16W +-1%(0402)DAL_AEC'              | 'CHIPR0402'    | ''          | ''            | '20160706'
 '33'         | '1%'      | '1/16W'  | '0402LF'  | 'CHIP'   | 'CS03302FB05'(!)        = ''              | ''                 | 'CS03302FB05'           |'R0402'| '(R0402-0201)'                 | '33'      | '1%'    | '1/16W'  | 'DISCRETE' | 'RES CHIP 33 1/16W +-1%(0402)DAL_AEC'              | 'CHIPR0402'    | ''          | ''            | '20160706'
 '33'         | '1%'      | '1/16W'  | '0402LF'  | 'EMPTY'  | 'CS03302FB05'(!)        = ''              | ''                 | 'CS03302FB05'           |'R0402'| '(R0402-0201)'                 | '33'      | '1%'    | '1/16W'  | 'IO'       | 'RES CHIP 33 1/16W +-1%(0402)DAL_AEC'              | 'CHIPR0402'    | ''          | ''            | '20160706'
 '33.2'       | '1%'      | '1/16W'  | '0402LF'  | 'CHIP'   | 'CS03322FB09'(!)        = ''              | ''                 | 'CS03322FB09'           |'R0402'| '(R0402-0201)'                 | '33.2'    | '1%'    | '1/16W'  | 'DISCRETE' | 'RES CHIP 33.2 1/16W +-1%(0402)DAL_AEC'            | 'CHIPR0402'    | ''          | ''            | '20160706'
 '33.2'       | '1%'      | '1/16W'  | '0402LF'  | 'EMPTY'  | 'CS03322FB09'(!)        = ''              | ''                 | 'CS03322FB09'           |'R0402'| '(R0402-0201)'                 | '33.2'    | '1%'    | '1/16W'  | 'IO'       | 'RES CHIP 33.2 1/16W +-1%(0402)DAL_AEC'            | 'CHIPR0402'    | ''          | ''            | '20160706'
 '36'         | '1%'      | '1/16W'  | '0402LF'  | 'CHIP'   | 'CS03602FB03'(!)        = ''              | ''                 | 'CS03602FB03'           |'R0402'| '(R0402-0201)'                 | '36'      | '1%'    | '1/16W'  | 'DISCRETE' | 'RES CHIP 36 1/16W +-1%(0402)DAL_AEC'              | 'CHIPR0402'    | ''          | ''            | '20160706'
 '36'         | '1%'      | '1/16W'  | '0402LF'  | 'EMPTY'  | 'CS03602FB03'(!)        = ''              | ''                 | 'CS03602FB03'           |'R0402'| '(R0402-0201)'                 | '36'      | '1%'    | '1/16W'  | 'IO'       | 'RES CHIP 36 1/16W +-1%(0402)DAL_AEC'              | 'CHIPR0402'    | ''          | ''            | '20160706'
 '39'         | '1%'      | '1/16W'  | '0402LF'  | 'CHIP'   | 'CS03902FB03'(!)        = ''              | ''                 | 'CS03902FB03'           |'R0402'| '(R0402-0201)'                 | '39'      | '1%'    | '1/16W'  | 'DISCRETE' | 'RES CHIP 39 1/16W +-1%(0402)DAL_AEC'              | 'CHIPR0402'    | ''          | ''            | '20160706'
 '39'         | '1%'      | '1/16W'  | '0402LF'  | 'EMPTY'  | 'CS03902FB03'(!)        = ''              | ''                 | 'CS03902FB03'           |'R0402'| '(R0402-0201)'                 | '39'      | '1%'    | '1/16W'  | 'IO'       | 'RES CHIP 39 1/16W +-1%(0402)DAL_AEC'              | 'CHIPR0402'    | ''          | ''            | '20160706'
 '42.2'       | '1%'      | '1/16W'  | '0402LF'  | 'CHIP'   | 'CS04222FB04'(!)        = ''              | ''                 | 'CS04222FB04'           |'R0402'| '(R0402-0201)'                 | '42.2'    | '1%'    | '1/16W'  | 'DISCRETE' | 'RES CHIP 42.2 1/16W +-1%(0402)DAL_AEC'            | 'CHIPR0402'    | ''          | ''            | '20160706'
 '42.2'       | '1%'      | '1/16W'  | '0402LF'  | 'EMPTY'  | 'CS04222FB04'(!)        = ''              | ''                 | 'CS04222FB04'           |'R0402'| '(R0402-0201)'                 | '42.2'    | '1%'    | '1/16W'  | 'IO'       | 'RES CHIP 42.2 1/16W +-1%(0402)DAL_AEC'            | 'CHIPR0402'    | ''          | ''            | '20160706'
 '43'         | '1%'      | '1/16W'  | '0402LF'  | 'CHIP'   | 'CS04302FB02'(!)        = ''              | ''                 | 'CS04302FB02'           |'R0402'| '(R0402-0201)'                 | '43'      | '1%'    | '1/16W'  | 'DISCRETE' | 'RES CHIP 43 1/16W +-1%(0402)DAL_AEC'              | 'CHIPR0402'    | ''          | ''            | '20160706'
 '43'         | '1%'      | '1/16W'  | '0402LF'  | 'EMPTY'  | 'CS04302FB02'(!)        = ''              | ''                 | 'CS04302FB02'           |'R0402'| '(R0402-0201)'                 | '43'      | '1%'    | '1/16W'  | 'IO'       | 'RES CHIP 43 1/16W +-1%(0402)DAL_AEC'              | 'CHIPR0402'    | ''          | ''            | '20160706'
 '64.9'       | '1%'      | '1/16W'  | '0402LF'  | 'CHIP'   | 'CS06492FB04'(!)        = ''              | ''                 | 'CS06492FB04'           |'R0402'| '(R0402-0201)'                 | '64.9'    | '1%'    | '1/16W'  | 'DISCRETE' | 'RES CHIP 64.9 1/16W +-1%(0402)DAL_AEC'            | 'CHIPR0402'    | ''          | ''            | '20160706'
 '64.9'       | '1%'      | '1/16W'  | '0402LF'  | 'EMPTY'  | 'CS06492FB04'(!)        = ''              | ''                 | 'CS06492FB04'           |'R0402'| '(R0402-0201)'                 | '64.9'    | '1%'    | '1/16W'  | 'IO'       | 'RES CHIP 64.9 1/16W +-1%(0402)DAL_AEC'            | 'CHIPR0402'    | ''          | ''            | '20160706'
 '75'         | '1%'      | '1/16W'  | '0402LF'  | 'CHIP'   | 'CS07502FB06'(!)        = ''              | ''                 | 'CS07502FB06'           |'R0402'| '(R0402-0201)'                 | '75'      | '1%'    | '1/16W'  | 'DISCRETE' | 'RES CHIP 75 1/16W +-1%(0402)DAL_AEC'              | 'CHIPR0402'    | ''          | ''            | '20160706'
 '75'         | '1%'      | '1/16W'  | '0402LF'  | 'EMPTY'  | 'CS07502FB06'(!)        = ''              | ''                 | 'CS07502FB06'           |'R0402'| '(R0402-0201)'                 | '75'      | '1%'    | '1/16W'  | 'IO'       | 'RES CHIP 75 1/16W +-1%(0402)DAL_AEC'              | 'CHIPR0402'    | ''          | ''            | '20160706'
 '90.9'       | '1%'      | '1/16W'  | '0402LF'  | 'CHIP'   | 'CS09092FB05'(!)        = ''              | ''                 | 'CS09092FB05'           |'R0402'| '(R0402-0201)'                 | '90.9'    | '1%'    | '1/16W'  | 'DISCRETE' | 'RES CHIP 90.9 1/16W +-1%(0402)DAL_AEC'            | 'CHIPR0402'    | ''          | ''            | '20160706'
 '90.9'       | '1%'      | '1/16W'  | '0402LF'  | 'EMPTY'  | 'CS09092FB05'(!)        = ''              | ''                 | 'CS09092FB05'           |'R0402'| '(R0402-0201)'                 | '90.9'    | '1%'    | '1/16W'  | 'IO'       | 'RES CHIP 90.9 1/16W +-1%(0402)DAL_AEC'            | 'CHIPR0402'    | ''          | ''            | '20160706'
 '1'          | '1%'      | '1/16W'  | '0402LF'  | 'CHIP'   | 'CS-1002FB10'(!)        = 'Non-Preferred' | 'End of Life'      | 'CS-1002FB10'           |'R0402_EOL'| '(R0402-0201)'                 | '1'       | '1%'    | '1/16W'  | 'DISCRETE' | 'RES CHIP 1 1/16W +-1%(0402) DAL_AEC'              | 'CHIPR0402'    | ''          | ''            | '20160706'
 '1'          | '1%'      | '1/16W'  | '0402LF'  | 'EMPTY'  | 'CS-1002FB10'(!)        = 'Non-Preferred' | 'End of Life'      | 'CS-1002FB10'           |'R0402_EOL'| '(R0402-0201)'                 | '1'       | '1%'    | '1/16W'  | 'IO'       | 'RES CHIP 1 1/16W +-1%(0402) DAL_AEC'              | 'CHIPR0402'    | ''          | ''            | '20160706'
 '100'        | '1%'      | '1/16W'  | '0402LF'  | 'CHIP'   | 'CS11002FB12'(!)        = ''              | ''                 | 'CS11002FB12'           |'R0402'| '(R0402-0201)'                 | '100'     | '1%'    | '1/16W'  | 'DISCRETE' | 'RES CHIP 100 1/16W +-1%(0402) DAL_AEC'            | 'CHIPR0402'    | ''          | ''            | '20160706'
 '100'        | '1%'      | '1/16W'  | '0402LF'  | 'EMPTY'  | 'CS11002FB12'(!)        = ''              | ''                 | 'CS11002FB12'           |'R0402'| '(R0402-0201)'                 | '100'     | '1%'    | '1/16W'  | 'IO'       | 'RES CHIP 100 1/16W +-1%(0402) DAL_AEC'            | 'CHIPR0402'    | ''          | ''            | '20160706'
 '113'        | '1%'      | '1/16W'  | '0402LF'  | 'CHIP'   | 'CS11132FB05'(!)        = ''              | ''                 | 'CS11132FB05'           |'R0402'| '(R0402-0201)'                 | '113'     | '1%'    | '1/16W'  | 'DISCRETE' | 'RES CHIP 113 1/16W +-1%(0402)DAL_AEC'             | 'CHIPR0402'    | ''          | ''            | '20160706'
 '113'        | '1%'      | '1/16W'  | '0402LF'  | 'EMPTY'  | 'CS11132FB05'(!)        = ''              | ''                 | 'CS11132FB05'           |'R0402'| '(R0402-0201)'                 | '113'     | '1%'    | '1/16W'  | 'IO'       | 'RES CHIP 113 1/16W +-1%(0402)DAL_AEC'             | 'CHIPR0402'    | ''          | ''            | '20160706'
 '120'        | '1%'      | '1/16W'  | '0402LF'  | 'CHIP'   | 'CS11202FB05'(!)        = ''              | ''                 | 'CS11202FB05'           |'R0402'| '(R0402-0201)'                 | '120'     | '1%'    | '1/16W'  | 'DISCRETE' | 'RES CHIP 120 1/16W +-1%(0402)DAL_AEC'             | 'CHIPR0402'    | ''          | ''            | '20160706'
 '120'        | '1%'      | '1/16W'  | '0402LF'  | 'EMPTY'  | 'CS11202FB05'(!)        = ''              | ''                 | 'CS11202FB05'           |'R0402'| '(R0402-0201)'                 | '120'     | '1%'    | '1/16W'  | 'IO'       | 'RES CHIP 120 1/16W +-1%(0402)DAL_AEC'             | 'CHIPR0402'    | ''          | ''            | '20160706'
 '137'        | '1%'      | '1/16W'  | '0402LF'  | 'CHIP'   | 'CS11372FB02'(!)        = ''              | ''                 | 'CS11372FB02'           |'R0402'| '(R0402-0201)'                 | '137'     | '1%'    | '1/16W'  | 'DISCRETE' | 'RES CHIP 137 1/16W +1%(0402)DAL_AEC'              | 'CHIPR0402'    | ''          | ''            | '20160706'
 '137'        | '1%'      | '1/16W'  | '0402LF'  | 'EMPTY'  | 'CS11372FB02'(!)        = ''              | ''                 | 'CS11372FB02'           |'R0402'| '(R0402-0201)'                 | '137'     | '1%'    | '1/16W'  | 'IO'       | 'RES CHIP 137 1/16W +1%(0402)DAL_AEC'              | 'CHIPR0402'    | ''          | ''            | '20160706'
 '150'        | '1%'      | '1/16W'  | '0402LF'  | 'CHIP'   | 'CS11502FB09'(!)        = ''              | ''                 | 'CS11502FB09'           |'R0402'| '(R0402-0201)'                 | '150'     | '1%'    | '1/16W'  | 'DISCRETE' | 'RES CHIP 150 1/16W +-1%(0402)DAL_AEC'             | 'CHIPR0402'    | ''          | ''            | '20160706'
 '150'        | '1%'      | '1/16W'  | '0402LF'  | 'EMPTY'  | 'CS11502FB09'(!)        = ''              | ''                 | 'CS11502FB09'           |'R0402'| '(R0402-0201)'                 | '150'     | '1%'    | '1/16W'  | 'IO'       | 'RES CHIP 150 1/16W +-1%(0402)DAL_AEC'             | 'CHIPR0402'    | ''          | ''            | '20160706'
 '169'        | '1%'      | '1/16W'  | '0402LF'  | 'CHIP'   | 'CS11692FB03'(!)        = ''              | ''                 | 'CS11692FB03'           |'R0402'| '(R0402-0201)'                 | '169'     | '1%'    | '1/16W'  | 'DISCRETE' | 'RES CHIP 169 1/16W +-1%(0402)DAL_AEC'             | 'CHIPR0402'    | ''          | ''            | '20160706'
 '169'        | '1%'      | '1/16W'  | '0402LF'  | 'EMPTY'  | 'CS11692FB03'(!)        = ''              | ''                 | 'CS11692FB03'           |'R0402'| '(R0402-0201)'                 | '169'     | '1%'    | '1/16W'  | 'IO'       | 'RES CHIP 169 1/16W +-1%(0402)DAL_AEC'             | 'CHIPR0402'    | ''          | ''            | '20160706'
 '200'        | '1%'      | '1/16W'  | '0402LF'  | 'CHIP'   | 'CS12002FB13'(!)        = ''              | ''                 | 'CS12002FB13'           |'R0402'| '(R0402-0201)'                 | '200'     | '1%'    | '1/16W'  | 'DISCRETE' | 'RES CHIP 200 1/16W +-1%(0402)DAL_AEC'             | 'CHIPR0402'    | ''          | ''            | '20160706'
 '200'        | '1%'      | '1/16W'  | '0402LF'  | 'EMPTY'  | 'CS12002FB13'(!)        = ''              | ''                 | 'CS12002FB13'           |'R0402'| '(R0402-0201)'                 | '200'     | '1%'    | '1/16W'  | 'IO'       | 'RES CHIP 200 1/16W +-1%(0402)DAL_AEC'             | 'CHIPR0402'    | ''          | ''            | '20160706'
 '220'        | '1%'      | '1/16W'  | '0402LF'  | 'CHIP'   | 'CS12202FB02'(!)        = ''              | ''                 | 'CS12202FB02'           |'R0402'| '(R0402-0201)'                 | '220'     | '1%'    | '1/16W'  | 'DISCRETE' | 'RES CHIP 220 1/16W +-1%(0402)DAL_AEC'             | 'CHIPR0402'    | ''          | ''            | '20160706'
 '220'        | '1%'      | '1/16W'  | '0402LF'  | 'EMPTY'  | 'CS12202FB02'(!)        = ''              | ''                 | 'CS12202FB02'           |'R0402'| '(R0402-0201)'                 | '220'     | '1%'    | '1/16W'  | 'IO'       | 'RES CHIP 220 1/16W +-1%(0402)DAL_AEC'             | 'CHIPR0402'    | ''          | ''            | '20160706'
 '240'        | '1%'      | '1/16W'  | '0402LF'  | 'CHIP'   | 'CS12402FB04'(!)        = ''              | ''                 | 'CS12402FB04'           |'R0402'| '(R0402-0201)'                 | '240'     | '1%'    | '1/16W'  | 'DISCRETE' | 'RES CHIP 240 1/16W +-1%(0402)DAL_AEC'             | 'CHIPR0402'    | ''          | ''            | '20160706'
 '240'        | '1%'      | '1/16W'  | '0402LF'  | 'EMPTY'  | 'CS12402FB04'(!)        = ''              | ''                 | 'CS12402FB04'           |'R0402'| '(R0402-0201)'                 | '240'     | '1%'    | '1/16W'  | 'IO'       | 'RES CHIP 240 1/16W +-1%(0402)DAL_AEC'             | 'CHIPR0402'    | ''          | ''            | '20160706'
 '330'        | '1%'      | '1/16W'  | '0402LF'  | 'CHIP'   | 'CS13302FB03'(!)        = ''              | ''                 | 'CS13302FB03'           |'R0402'| '(R0402-0201)'                 | '330'     | '1%'    | '1/16W'  | 'DISCRETE' | 'RES CHIP 330 1/16W +-1%(0402)DAL_AEC'             | 'CHIPR0402'    | ''          | ''            | '20160706'
 '330'        | '1%'      | '1/16W'  | '0402LF'  | 'EMPTY'  | 'CS13302FB03'(!)        = ''              | ''                 | 'CS13302FB03'           |'R0402'| '(R0402-0201)'                 | '330'     | '1%'    | '1/16W'  | 'IO'       | 'RES CHIP 330 1/16W +-1%(0402)DAL_AEC'             | 'CHIPR0402'    | ''          | ''            | '20160706'
 '332'        | '1%'      | '1/16W'  | '0402LF'  | 'CHIP'   | 'CS13322FB07'(!)        = ''              | ''                 | 'CS13322FB07'           |'R0402'| '(R0402-0201)'                 | '332'     | '1%'    | '1/16W'  | 'DISCRETE' | 'RES CHIP 332 1/16W +-1%(0402)DAL_AEC'             | 'CHIPR0402'    | ''          | ''            | '20160706'
 '332'        | '1%'      | '1/16W'  | '0402LF'  | 'EMPTY'  | 'CS13322FB07'(!)        = ''              | ''                 | 'CS13322FB07'           |'R0402'| '(R0402-0201)'                 | '332'     | '1%'    | '1/16W'  | 'IO'       | 'RES CHIP 332 1/16W +-1%(0402)DAL_AEC'             | 'CHIPR0402'    | ''          | ''            | '20160706'
 '348'        | '1%'      | '1/16W'  | '0402LF'  | 'CHIP'   | 'CS13482FB05'(!)        = ''              | ''                 | 'CS13482FB05'           |'R0402'| '(R0402-0201)'                 | '348'     | '1%'    | '1/16W'  | 'DISCRETE' | 'RES CHIP 348 1/16W +-1%(0402)DAL_AEC'             | 'CHIPR0402'    | ''          | ''            | '20160706'
 '348'        | '1%'      | '1/16W'  | '0402LF'  | 'EMPTY'  | 'CS13482FB05'(!)        = ''              | ''                 | 'CS13482FB05'           |'R0402'| '(R0402-0201)'                 | '348'     | '1%'    | '1/16W'  | 'IO'       | 'RES CHIP 348 1/16W +-1%(0402)DAL_AEC'             | 'CHIPR0402'    | ''          | ''            | '20160706'
 '412'        | '1%'      | '1/16W'  | '0402LF'  | 'CHIP'   | 'CS14122FB03'(!)        = ''              | ''                 | 'CS14122FB03'           |'R0402'| '(R0402-0201)'                 | '412'     | '1%'    | '1/16W'  | 'DISCRETE' | 'RES CHIP 412 1/16W +-1%(0402)DAL_AEC'             | 'CHIPR0402'    | ''          | ''            | '20160706'
 '412'        | '1%'      | '1/16W'  | '0402LF'  | 'EMPTY'  | 'CS14122FB03'(!)        = ''              | ''                 | 'CS14122FB03'           |'R0402'| '(R0402-0201)'                 | '412'     | '1%'    | '1/16W'  | 'IO'       | 'RES CHIP 412 1/16W +-1%(0402)DAL_AEC'             | 'CHIPR0402'    | ''          | ''            | '20160706'
 '475'        | '1%'      | '1/16W'  | '0402LF'  | 'CHIP'   | 'CS14752FB10'(!)        = ''              | ''                 | 'CS14752FB10'           |'R0402'| '(R0402-0201)'                 | '475'     | '1%'    | '1/16W'  | 'DISCRETE' | 'RES CHIP 475 1/16W +-1%(0402)DAL_AEC'             | 'CHIPR0402'    | ''          | ''            | '20160711'
 '475'        | '1%'      | '1/16W'  | '0402LF'  | 'EMPTY'  | 'CS14752FB10'(!)        = ''              | ''                 | 'CS14752FB10'           |'R0402'| '(R0402-0201)'                 | '475'     | '1%'    | '1/16W'  | 'IO'       | 'RES CHIP 475 1/16W +-1%(0402)DAL_AEC'             | 'CHIPR0402'    | ''          | ''            | '20160711'
 '511'        | '1%'      | '1/16W'  | '0402LF'  | 'CHIP'   | 'CS15112FB06'(!)        = ''              | ''                 | 'CS15112FB06'           |'R0402'| '(R0402-0201)'                 | '511'     | '1%'    | '1/16W'  | 'DISCRETE' | 'RES CHIP 511 1/16W +-1%(0402)DAL_AEC'             | 'CHIPR0402'    | ''          | ''            | '20160711'
 '511'        | '1%'      | '1/16W'  | '0402LF'  | 'EMPTY'  | 'CS15112FB06'(!)        = ''              | ''                 | 'CS15112FB06'           |'R0402'| '(R0402-0201)'                 | '511'     | '1%'    | '1/16W'  | 'IO'       | 'RES CHIP 511 1/16W +-1%(0402)DAL_AEC'             | 'CHIPR0402'    | ''          | ''            | '20160711'
 '845'        | '1%'      | '1/16W'  | '0402LF'  | 'CHIP'   | 'CS18452FB04'(!)        = ''              | ''                 | 'CS18452FB04'           |'R0402'| '(R0402-0201)'                 | '845'     | '1%'    | '1/16W'  | 'DISCRETE' | 'RES CHIP 845 1/16W +-1%(0402)DAL_AEC'             | 'CHIPR0402'    | ''          | ''            | '20160713'
 '845'        | '1%'      | '1/16W'  | '0402LF'  | 'EMPTY'  | 'CS18452FB04'(!)        = ''              | ''                 | 'CS18452FB04'           |'R0402'| '(R0402-0201)'                 | '845'     | '1%'    | '1/16W'  | 'IO'       | 'RES CHIP 845 1/16W +-1%(0402)DAL_AEC'             | 'CHIPR0402'    | ''          | ''            | '20160713'
 '2'          | '1%'      | '1/16W'  | '0402LF'  | 'CHIP'   | 'CS-2002FB04'(!)        = 'End of Design' | 'Comp-Approve'     | 'CS-2002FB04'           |'R0402'| '(R0402-0201)'                 | '2'       | '1%'    | '1/16W'  | 'DISCRETE' | 'RES CHIP 2 1/16W +-1%(0402)DAL_AEC'               | 'CHIPR0402'    | ''          | ''            | '20160713'
 '2'          | '1%'      | '1/16W'  | '0402LF'  | 'EMPTY'  | 'CS-2002FB04'(!)        = 'End of Design' | 'Comp-Approve'     | 'CS-2002FB04'           |'R0402'| '(R0402-0201)'                 | '2'       | '1%'    | '1/16W'  | 'IO'       | 'RES CHIP 2 1/16W +-1%(0402)DAL_AEC'               | 'CHIPR0402'    | ''          | ''            | '20160713'
 '2.2K'       | '1%'      | '1/16W'  | '0402LF'  | 'CHIP'   | 'CS22202FB03'(!)        = ''              | ''                 | 'CS22202FB03'           |'R0402'| '(R0402-0201)'                 | '2.2K'    | '1%'    | '1/16W'  | 'DISCRETE' | 'RES CHIP 2.2K 1/16W +-1%(0402)DAL_AEC'            | 'CHIPR0402'    | ''          | ''            | '20160713'
 '2.2K'       | '1%'      | '1/16W'  | '0402LF'  | 'EMPTY'  | 'CS22202FB03'(!)        = ''              | ''                 | 'CS22202FB03'           |'R0402'| '(R0402-0201)'                 | '2.2K'    | '1%'    | '1/16W'  | 'IO'       | 'RES CHIP 2.2K 1/16W +-1%(0402)DAL_AEC'            | 'CHIPR0402'    | ''          | ''            | '20160713'
 '2.21K'      | '1%'      | '1/16W'  | '0402LF'  | 'CHIP'   | 'CS22212FB08'(!)        = ''              | ''                 | 'CS22212FB08'           |'R0402'| '(R0402-0201)'                 | '2.21K'   | '1%'    | '1/16W'  | 'DISCRETE' | 'RES CHIP 2.21K 1/16W +-1%(0402)DAL_AEC'           | 'CHIPR0402'    | ''          | ''            | '20160713'
 '2.21K'      | '1%'      | '1/16W'  | '0402LF'  | 'EMPTY'  | 'CS22212FB08'(!)        = ''              | ''                 | 'CS22212FB08'           |'R0402'| '(R0402-0201)'                 | '2.21K'   | '1%'    | '1/16W'  | 'IO'       | 'RES CHIP 2.21K 1/16W +-1%(0402)DAL_AEC'           | 'CHIPR0402'    | ''          | ''            | '20160713'
 '49.9'       | '1%'      | '1/10W'  | '0603LF'  | 'CHIP'   | 'CS04993F908'(!)        = ''              | ''                 | 'CS04993F908'           |'R0603'| '(SMR0603AW)'                  | '49.9'    | '1%'    | '1/10W'  | 'DISCRETE' | 'RES CHIP 49.9 1/10W +-1%(0603)DAL_AEC'            | 'CHIPR0603'    | ''          | ''            | '20160713'
 '49.9'       | '1%'      | '1/10W'  | '0603LF'  | 'EMPTY'  | 'CS04993F908'(!)        = ''              | ''                 | 'CS04993F908'           |'R0603'| '(SMR0603AW)'                  | '49.9'    | '1%'    | '1/10W'  | 'IO'       | 'RES CHIP 49.9 1/10W +-1%(0603)DAL_AEC'            | 'CHIPR0603'    | ''          | ''            | '20160713'
 '0.0002'     | '1%'      | '9W'     | '3921LF'  | 'CHIP'   | 'CS0000KFY00'(!)        = ''              | ''                 | 'CS0000KFY00'           |'R3921'| '(SMR3921AW)'                  | '0.0002'  | '1%'    | '9W'     | 'DISCRETE' | 'RES CHIP 0.0002 9W +-1%(3921)DAL_AEC'             | 'CHIPR3921'    | ''          | ''            | '20160725'
 '0.0002'     | '1%'      | '9W'     | '3921LF'  | 'EMPTY'  | 'CS0000KFY00'(!)        = ''              | ''                 | 'CS0000KFY00'           |'R3921'| '(SMR3921AW)'                  | '0.0002'  | '1%'    | '9W'     | 'IO'       | 'RES CHIP 0.0002 9W +-1%(3921)DAL_AEC'             | 'CHIPR3921'    | ''          | ''            | '20160725'
 '1K'         | '1%'      | '1/16W'  | '0402LF'  | 'CHIP'   | 'CS21002FB13'(!)        = ''              | ''                 | 'CS21002FB13'           |'R0402'| '(R0402-0201)'                 | '1K'      | '1%'    | '1/16W'  | 'DISCRETE' | 'RES CHIP 1K 1/16W +-1%(0402)DAL_AEC'              | 'CHIPR0402'    | ''          | ''            | '20160725'
 '1K'         | '1%'      | '1/16W'  | '0402LF'  | 'EMPTY'  | 'CS21002FB13'(!)        = ''              | ''                 | 'CS21002FB13'           |'R0402'| '(R0402-0201)'                 | '1K'      | '1%'    | '1/16W'  | 'IO'       | 'RES CHIP 1K 1/16W +-1%(0402)DAL_AEC'              | 'CHIPR0402'    | ''          | ''            | '20160725'
 '2.55K'      | '1%'      | '1/16W'  | '0402LF'  | 'CHIP'   | 'CS22552FB03'(!)        = ''              | ''                 | 'CS22552FB03'           |'R0402'| '(R0402-0201)'                 | '2.55K'   | '1%'    | '1/16W'  | 'DISCRETE' | 'RES CHIP 2.55K 1/16W +-1%(0402)DAL_AEC'           | 'CHIPR0402'    | ''          | ''            | '20160725'
 '2.55K'      | '1%'      | '1/16W'  | '0402LF'  | 'EMPTY'  | 'CS22552FB03'(!)        = ''              | ''                 | 'CS22552FB03'           |'R0402'| '(R0402-0201)'                 | '2.55K'   | '1%'    | '1/16W'  | 'IO'       | 'RES CHIP 2.55K 1/16W +-1%(0402)DAL_AEC'           | 'CHIPR0402'    | ''          | ''            | '20160725'
 '3.01K'      | '1%'      | '1/16W'  | '0402LF'  | 'CHIP'   | 'CS23012FB10'(!)        = ''              | ''                 | 'CS23012FB10'           |'R0402'| '(R0402-0201)'                 | '3.01K'   | '1%'    | '1/16W'  | 'DISCRETE' | 'RES CHIP 3.01K 1/16W +-1%(0402)DAL_AEC'           | 'CHIPR0402'    | ''          | ''            | '20160725'
 '3.01K'      | '1%'      | '1/16W'  | '0402LF'  | 'EMPTY'  | 'CS23012FB10'(!)        = ''              | ''                 | 'CS23012FB10'           |'R0402'| '(R0402-0201)'                 | '3.01K'   | '1%'    | '1/16W'  | 'IO'       | 'RES CHIP 3.01K 1/16W +-1%(0402)DAL_AEC'           | 'CHIPR0402'    | ''          | ''            | '20160725'
 '3.3K'       | '1%'      | '1/16W'  | '0402LF'  | 'CHIP'   | 'CS23302FB03'(!)        = ''              | ''                 | 'CS23302FB03'           |'R0402'| '(R0402-0201)'                 | '3.3K'    | '1%'    | '1/16W'  | 'DISCRETE' | 'RES CHIP 3.3K 1/16W +-1%(0402)DAL_AEC'            | 'CHIPR0402'    | ''          | ''            | '20160725'
 '3.3K'       | '1%'      | '1/16W'  | '0402LF'  | 'EMPTY'  | 'CS23302FB03'(!)        = ''              | ''                 | 'CS23302FB03'           |'R0402'| '(R0402-0201)'                 | '3.3K'    | '1%'    | '1/16W'  | 'IO'       | 'RES CHIP 3.3K 1/16W +-1%(0402)DAL_AEC'            | 'CHIPR0402'    | ''          | ''            | '20160725'
 '3.32K'      | '1%'      | '1/16W'  | '0402LF'  | 'CHIP'   | 'CS23322FB07'(!)        = ''              | ''                 | 'CS23322FB07'           |'R0402'| '(R0402-0201)'                 | '3.32K'   | '1%'    | '1/16W'  | 'DISCRETE' | 'RES CHIP 3.32K 1/16W +-1% (0402)DAL_AEC'          | 'CHIPR0402'    | ''          | ''            | '20160725'
 '3.32K'      | '1%'      | '1/16W'  | '0402LF'  | 'EMPTY'  | 'CS23322FB07'(!)        = ''              | ''                 | 'CS23322FB07'           |'R0402'| '(R0402-0201)'                 | '3.32K'   | '1%'    | '1/16W'  | 'IO'       | 'RES CHIP 3.32K 1/16W +-1% (0402)DAL_AEC'          | 'CHIPR0402'    | ''          | ''            | '20160725'
 '3.4K'       | '1%'      | '1/16W'  | '0402LF'  | 'CHIP'   | 'CS23402FB03'(!)        = ''              | ''                 | 'CS23402FB03'           |'R0402'| '(R0402-0201)'                 | '3.4K'    | '1%'    | '1/16W'  | 'DISCRETE' | 'RES CHIP 3.4K 1/16W +-1%(0402)DAL_AEC'            | 'CHIPR0402'    | ''          | ''            | '20160725'
 '3.4K'       | '1%'      | '1/16W'  | '0402LF'  | 'EMPTY'  | 'CS23402FB03'(!)        = ''              | ''                 | 'CS23402FB03'           |'R0402'| '(R0402-0201)'                 | '3.4K'    | '1%'    | '1/16W'  | 'IO'       | 'RES CHIP 3.4K 1/16W +-1%(0402)DAL_AEC'            | 'CHIPR0402'    | ''          | ''            | '20160725'
 '3.57K'      | '1%'      | '1/16W'  | '0402LF'  | 'CHIP'   | 'CS23572FB07'(!)        = ''              | ''                 | 'CS23572FB07'           |'R0402'| '(R0402-0201)'                 | '3.57K'   | '1%'    | '1/16W'  | 'DISCRETE' | 'RES CHIP 3.57K 1/16W +-1%(0402)DAL_AEC'           | 'CHIPR0402'    | ''          | ''            | '20160725'
 '3.57K'      | '1%'      | '1/16W'  | '0402LF'  | 'EMPTY'  | 'CS23572FB07'(!)        = ''              | ''                 | 'CS23572FB07'           |'R0402'| '(R0402-0201)'                 | '3.57K'   | '1%'    | '1/16W'  | 'IO'       | 'RES CHIP 3.57K 1/16W +-1%(0402)DAL_AEC'           | 'CHIPR0402'    | ''          | ''            | '20160725'
 '4.02K'      | '1%'      | '1/16W'  | '0402LF'  | 'CHIP'   | 'CS24022FB07'(!)        = ''              | ''                 | 'CS24022FB07'           |'R0402'| '(R0402-0201)'                 | '4.02K'   | '1%'    | '1/16W'  | 'DISCRETE' | 'RES CHIP 4.02K 1/16W +-1%(0402)DAL_AEC'           | 'CHIPR0402'    | ''          | ''            | '20160725'
 '4.02K'      | '1%'      | '1/16W'  | '0402LF'  | 'EMPTY'  | 'CS24022FB07'(!)        = ''              | ''                 | 'CS24022FB07'           |'R0402'| '(R0402-0201)'                 | '4.02K'   | '1%'    | '1/16W'  | 'IO'       | 'RES CHIP 4.02K 1/16W +-1%(0402)DAL_AEC'           | 'CHIPR0402'    | ''          | ''            | '20160725'
 '4.12K'      | '1%'      | '1/16W'  | '0402LF'  | 'CHIP'   | 'CS24122FB03'(!)        = ''              | ''                 | 'CS24122FB03'           |'R0402'| '(R0402-0201)'                 | '4.12K'   | '1%'    | '1/16W'  | 'DISCRETE' | 'RES CHIP 4.12K 1/16W +-1%(0402)DAL_AEC'           | 'CHIPR0402'    | ''          | ''            | '20160725'
 '4.12K'      | '1%'      | '1/16W'  | '0402LF'  | 'EMPTY'  | 'CS24122FB03'(!)        = ''              | ''                 | 'CS24122FB03'           |'R0402'| '(R0402-0201)'                 | '4.12K'   | '1%'    | '1/16W'  | 'IO'       | 'RES CHIP 4.12K 1/16W +-1%(0402)DAL_AEC'           | 'CHIPR0402'    | ''          | ''            | '20160725'
 '1.1K'       | '1%'      | '1/16W'  | '0402LF'  | 'CHIP'   | 'CS21102FB06'(!)        = ''              | ''                 | 'CS21102FB06'           |'R0402'| '(R0402-0201)'                 | '1.1K'    | '1%'    | '1/16W'  | 'DISCRETE' | 'RES CHIP 1.1K 1/16W +1% (0402)DAL_AEC'            | 'CHIPR0402'    | ''          | ''            | '20160725'
 '1.1K'       | '1%'      | '1/16W'  | '0402LF'  | 'EMPTY'  | 'CS21102FB06'(!)        = ''              | ''                 | 'CS21102FB06'           |'R0402'| '(R0402-0201)'                 | '1.1K'    | '1%'    | '1/16W'  | 'IO'       | 'RES CHIP 1.1K 1/16W +1% (0402)DAL_AEC'            | 'CHIPR0402'    | ''          | ''            | '20160725'
 '51.1'       | '1%'      | '1/20W'  | '0201LF'  | 'CHIP'   | 'CS05111FE00'(!)        = ''              | ''                 | 'CS05111FE00'           |'R0201'| '(SMR0201AW)'                  | '51.1'    | '1%'    | '1/20W'  | 'DISCRETE' | 'RES CHIP 51.1 1/20W +-1%(0201)'                   | 'CHIPR0201'    | ''          | ''            | '20160725'
 '51.1'       | '1%'      | '1/20W'  | '0201LF'  | 'EMPTY'  | 'CS05111FE00'(!)        = ''              | ''                 | 'CS05111FE00'           |'R0201'| '(SMR0201AW)'                  | '51.1'    | '1%'    | '1/20W'  | 'IO'       | 'RES CHIP 51.1 1/20W +-1%(0201)'                   | 'CHIPR0201'    | ''          | ''            | '20160725'
 '1.5K'       | '1%'      | '1/16W'  | '0402LF'  | 'CHIP'   | 'CS21502FB09'(!)        = ''              | ''                 | 'CS21502FB09'           |'R0402'| '(R0402-0201)'                 | '1.5K'    | '1%'    | '1/16W'  | 'DISCRETE' | 'RES CHIP 1.5K 1/16W +1% (0402)DAL_AEC'            | 'CHIPR0402'    | ''          | ''            | '20160727'
 '1.5K'       | '1%'      | '1/16W'  | '0402LF'  | 'EMPTY'  | 'CS21502FB09'(!)        = ''              | ''                 | 'CS21502FB09'           |'R0402'| '(R0402-0201)'                 | '1.5K'    | '1%'    | '1/16W'  | 'IO'       | 'RES CHIP 1.5K 1/16W +1% (0402)DAL_AEC'            | 'CHIPR0402'    | ''          | ''            | '20160727'
 '1.69K'      | '1%'      | '1/16W'  | '0402LF'  | 'CHIP'   | 'CS21692FB03'(!)        = ''              | ''                 | 'CS21692FB03'           |'R0402'| '(R0402-0201)'                 | '1.69K'   | '1%'    | '1/16W'  | 'DISCRETE' | 'RES CHIP 1.69K 1/16W +-1%(0402)DAL_AEC'           | 'CHIPR0402'    | ''          | ''            | '20160727'
 '1.69K'      | '1%'      | '1/16W'  | '0402LF'  | 'EMPTY'  | 'CS21692FB03'(!)        = ''              | ''                 | 'CS21692FB03'           |'R0402'| '(R0402-0201)'                 | '1.69K'   | '1%'    | '1/16W'  | 'IO'       | 'RES CHIP 1.69K 1/16W +-1%(0402)DAL_AEC'           | 'CHIPR0402'    | ''          | ''            | '20160727'
 '1.8K'       | '1%'      | '1/16W'  | '0402LF'  | 'CHIP'   | 'CS21802FB04'(!)        = ''              | ''                 | 'CS21802FB04'           |'R0402'| '(R0402-0201)'                 | '1.8K'    | '1%'    | '1/16W'  | 'DISCRETE' | 'RES CHIP 1.8K 1/16W +-1%(0402) DAL_AEC'           | 'CHIPR0402'    | ''          | ''            | '20160727'
 '1.8K'       | '1%'      | '1/16W'  | '0402LF'  | 'EMPTY'  | 'CS21802FB04'(!)        = ''              | ''                 | 'CS21802FB04'           |'R0402'| '(R0402-0201)'                 | '1.8K'    | '1%'    | '1/16W'  | 'IO'       | 'RES CHIP 1.8K 1/16W +-1%(0402) DAL_AEC'           | 'CHIPR0402'    | ''          | ''            | '20160727'
 '2K'         | '1%'      | '1/16W'  | '0402LF'  | 'CHIP'   | 'CS22002FB12'(!)        = ''              | ''                 | 'CS22002FB12'           |'R0402'| '(R0402-0201)'                 | '2K'      | '1%'    | '1/16W'  | 'DISCRETE' | 'RES CHIP 2K 1/16W +-1%(0402)DAL_AEC'              | 'CHIPR0402'    | ''          | ''            | '20160727'
 '2K'         | '1%'      | '1/16W'  | '0402LF'  | 'EMPTY'  | 'CS22002FB12'(!)        = ''              | ''                 | 'CS22002FB12'           |'R0402'| '(R0402-0201)'                 | '2K'      | '1%'    | '1/16W'  | 'IO'       | 'RES CHIP 2K 1/16W +-1%(0402)DAL_AEC'              | 'CHIPR0402'    | ''          | ''            | '20160727'
 '2.2'        | '1%'      | '1/16W'  | '0402LF'  | 'CHIP'   | 'CS-2202FB03'(!)        = 'End of Design' | 'Comp-Approve'     | 'CS-2202FB03'           |'R0402'| '(R0402-0201)'                 | '2.2'     | '1%'    | '1/16W'  | 'DISCRETE' | 'RES CHIP 2.2 1/16W +-1%(0402)DAL_AEC'             | 'CHIPR0402'    | ''          | ''            | '20160727'
 '2.2'        | '1%'      | '1/16W'  | '0402LF'  | 'EMPTY'  | 'CS-2202FB03'(!)        = 'End of Design' | 'Comp-Approve'     | 'CS-2202FB03'           |'R0402'| '(R0402-0201)'                 | '2.2'     | '1%'    | '1/16W'  | 'IO'       | 'RES CHIP 2.2 1/16W +-1%(0402)DAL_AEC'             | 'CHIPR0402'    | ''          | ''            | '20160727'
 '4.75K'      | '1%'      | '1/16W'  | '0402LF'  | 'CHIP'   | 'CS24752FB06'(!)        = ''              | ''                 | 'CS24752FB06'           |'R0402'| '(R0402-0201)'                 | '4.75K'   | '1%'    | '1/16W'  | 'DISCRETE' | 'RES CHIP 4.75K 1/16W +-1%(0402)DAL_AEC'           | 'CHIPR0402'    | ''          | ''            | '20160727'
 '4.75K'      | '1%'      | '1/16W'  | '0402LF'  | 'EMPTY'  | 'CS24752FB06'(!)        = ''              | ''                 | 'CS24752FB06'           |'R0402'| '(R0402-0201)'                 | '4.75K'   | '1%'    | '1/16W'  | 'IO'       | 'RES CHIP 4.75K 1/16W +-1%(0402)DAL_AEC'           | 'CHIPR0402'    | ''          | ''            | '20160727'
 '4.87K'      | '1%'      | '1/16W'  | '0402LF'  | 'CHIP'   | 'CS24872FB03'(!)        = ''              | ''                 | 'CS24872FB03'           |'R0402'| '(R0402-0201)'                 | '4.87K'   | '1%'    | '1/16W'  | 'DISCRETE' | 'RES CHIP 4.87K 1/16W+-1%(0402)DAL_AEC'            | 'CHIPR0402'    | ''          | ''            | '20160727'
 '4.87K'      | '1%'      | '1/16W'  | '0402LF'  | 'EMPTY'  | 'CS24872FB03'(!)        = ''              | ''                 | 'CS24872FB03'           |'R0402'| '(R0402-0201)'                 | '4.87K'   | '1%'    | '1/16W'  | 'IO'       | 'RES CHIP 4.87K 1/16W+-1%(0402)DAL_AEC'            | 'CHIPR0402'    | ''          | ''            | '20160727'
 '4.99K'      | '1%'      | '1/16W'  | '0402LF'  | 'CHIP'   | 'CS24992FB09'(!)        = ''              | ''                 | 'CS24992FB09'           |'R0402'| '(R0402-0201)'                 | '4.99K'   | '1%'    | '1/16W'  | 'DISCRETE' | 'RES CHIP 4.99K 1/16W +-1%(0402)DAL_AEC'           | 'CHIPR0402'    | ''          | ''            | '20160727'
 '4.99K'      | '1%'      | '1/16W'  | '0402LF'  | 'EMPTY'  | 'CS24992FB09'(!)        = ''              | ''                 | 'CS24992FB09'           |'R0402'| '(R0402-0201)'                 | '4.99K'   | '1%'    | '1/16W'  | 'IO'       | 'RES CHIP 4.99K 1/16W +-1%(0402)DAL_AEC'           | 'CHIPR0402'    | ''          | ''            | '20160727'
 '5.76K'      | '1%'      | '1/16W'  | '0402LF'  | 'CHIP'   | 'CS25762FB05'(!)        = ''              | ''                 | 'CS25762FB05'           |'R0402'| '(R0402-0201)'                 | '5.76K'   | '1%'    | '1/16W'  | 'DISCRETE' | 'RES CHIP 5.76K 1/16W +-1%(0402)DAL_AEC'           | 'CHIPR0402'    | ''          | ''            | '20160727'
 '5.76K'      | '1%'      | '1/16W'  | '0402LF'  | 'EMPTY'  | 'CS25762FB05'(!)        = ''              | ''                 | 'CS25762FB05'           |'R0402'| '(R0402-0201)'                 | '5.76K'   | '1%'    | '1/16W'  | 'IO'       | 'RES CHIP 5.76K 1/16W +-1%(0402)DAL_AEC'           | 'CHIPR0402'    | ''          | ''            | '20160727'
 '6.81K'      | '1%'      | '1/16W'  | '0402LF'  | 'CHIP'   | 'CS26812FB07'(!)        = ''              | ''                 | 'CS26812FB07'           |'R0402'| '(R0402-0201)'                 | '6.81K'   | '1%'    | '1/16W'  | 'DISCRETE' | 'RES CHIP 6.81K 1/16W +-1%(0402)DAL_AEC'           | 'CHIPR0402'    | ''          | ''            | '20160727'
 '6.81K'      | '1%'      | '1/16W'  | '0402LF'  | 'EMPTY'  | 'CS26812FB07'(!)        = ''              | ''                 | 'CS26812FB07'           |'R0402'| '(R0402-0201)'                 | '6.81K'   | '1%'    | '1/16W'  | 'IO'       | 'RES CHIP 6.81K 1/16W +-1%(0402)DAL_AEC'           | 'CHIPR0402'    | ''          | ''            | '20160727'
 '6.98K'      | '1%'      | '1/16W'  | '0402LF'  | 'CHIP'   | 'CS26982FB05'(!)        = ''              | ''                 | 'CS26982FB05'           |'R0402'| '(R0402-0201)'                 | '6.98K'   | '1%'    | '1/16W'  | 'DISCRETE' | 'RES CHIP 6.98K 1/16W +-1% (0402)DAL_AEC'          | 'CHIPR0402'    | ''          | ''            | '20160727'
 '6.98K'      | '1%'      | '1/16W'  | '0402LF'  | 'EMPTY'  | 'CS26982FB05'(!)        = ''              | ''                 | 'CS26982FB05'           |'R0402'| '(R0402-0201)'                 | '6.98K'   | '1%'    | '1/16W'  | 'IO'       | 'RES CHIP 6.98K 1/16W +-1% (0402)DAL_AEC'          | 'CHIPR0402'    | ''          | ''            | '20160727'
 '8.25K'      | '1%'      | '1/16W'  | '0402LF'  | 'CHIP'   | 'CS28252FB05'(!)        = ''              | ''                 | 'CS28252FB05'           |'R0402'| '(R0402-0201)'                 | '8.25K'   | '1%'    | '1/16W'  | 'DISCRETE' | 'RES CHIP 8.25K 1/16W+-1%(0402)DAL_AEC'            | 'CHIPR0402'    | ''          | ''            | '20160727'
 '8.25K'      | '1%'      | '1/16W'  | '0402LF'  | 'EMPTY'  | 'CS28252FB05'(!)        = ''              | ''                 | 'CS28252FB05'           |'R0402'| '(R0402-0201)'                 | '8.25K'   | '1%'    | '1/16W'  | 'IO'       | 'RES CHIP 8.25K 1/16W+-1%(0402)DAL_AEC'            | 'CHIPR0402'    | ''          | ''            | '20160727'
 '10K'        | '1%'      | '1/16W'  | '0402LF'  | 'CHIP'   | 'CS31002FB14'(!)        = ''              | ''                 | 'CS31002FB14'           |'R0402'| '(R0402-0201)'                 | '10K'     | '1%'    | '1/16W'  | 'DISCRETE' | 'RES CHIP 10K 1/16W +-1%(0402)DAL_AEC'             | 'CHIPR0402'    | ''          | ''            | '20160727'
 '10K'        | '1%'      | '1/16W'  | '0402LF'  | 'EMPTY'  | 'CS31002FB14'(!)        = ''              | ''                 | 'CS31002FB14'           |'R0402'| '(R0402-0201)'                 | '10K'     | '1%'    | '1/16W'  | 'IO'       | 'RES CHIP 10K 1/16W +-1%(0402)DAL_AEC'             | 'CHIPR0402'    | ''          | ''            | '20160727'
 '11K'        | '1%'      | '1/16W'  | '0402LF'  | 'CHIP'   | 'CS31102FB07'(!)        = ''              | ''                 | 'CS31102FB07'           |'R0402'| '(R0402-0201)'                 | '11K'     | '1%'    | '1/16W'  | 'DISCRETE' | 'RES CHIP 11K 1/16W +-1% (0402)DAL_AEC'            | 'CHIPR0402'    | ''          | ''            | '20160727'
 '11K'        | '1%'      | '1/16W'  | '0402LF'  | 'EMPTY'  | 'CS31102FB07'(!)        = ''              | ''                 | 'CS31102FB07'           |'R0402'| '(R0402-0201)'                 | '11K'     | '1%'    | '1/16W'  | 'IO'       | 'RES CHIP 11K 1/16W +-1% (0402)DAL_AEC'            | 'CHIPR0402'    | ''          | ''            | '20160727'
 '12K'        | '1%'      | '1/16W'  | '0402LF'  | 'CHIP'   | 'CS31202FB06'(!)        = ''              | ''                 | 'CS31202FB06'           |'R0402'| '(R0402-0201)'                 | '12K'     | '1%'    | '1/16W'  | 'DISCRETE' | 'RES CHIP 12K 1/16W +-1%(0402)DAL_AEC'             | 'CHIPR0402'    | ''          | ''            | '20160727'
 '12K'        | '1%'      | '1/16W'  | '0402LF'  | 'EMPTY'  | 'CS31202FB06'(!)        = ''              | ''                 | 'CS31202FB06'           |'R0402'| '(R0402-0201)'                 | '12K'     | '1%'    | '1/16W'  | 'IO'       | 'RES CHIP 12K 1/16W +-1%(0402)DAL_AEC'             | 'CHIPR0402'    | ''          | ''            | '20160727'
 '12.1K'      | '1%'      | '1/16W'  | '0402LF'  | 'CHIP'   | 'CS31212FB07'(!)        = ''              | ''                 | 'CS31212FB07'           |'R0402'| '(R0402-0201)'                 | '12.1K'   | '1%'    | '1/16W'  | 'DISCRETE' | 'RES CHIP 12.1K 1/16W +1%(0402)DAL_AEC'            | 'CHIPR0402'    | ''          | ''            | '20160727'
 '12.1K'      | '1%'      | '1/16W'  | '0402LF'  | 'EMPTY'  | 'CS31212FB07'(!)        = ''              | ''                 | 'CS31212FB07'           |'R0402'| '(R0402-0201)'                 | '12.1K'   | '1%'    | '1/16W'  | 'IO'       | 'RES CHIP 12.1K 1/16W +1%(0402)DAL_AEC'            | 'CHIPR0402'    | ''          | ''            | '20160727'
 '13.7K'      | '1%'      | '1/16W'  | '0402LF'  | 'CHIP'   | 'CS31372FB04'(!)        = ''              | ''                 | 'CS31372FB04'           |'R0402'| '(R0402-0201)'                 | '13.7K'   | '1%'    | '1/16W'  | 'DISCRETE' | 'RES CHIP 13.7K 1/16W +-1%(0402)DAL_AEC'           | 'CHIPR0402'    | ''          | ''            | '20160727'
 '13.7K'      | '1%'      | '1/16W'  | '0402LF'  | 'EMPTY'  | 'CS31372FB04'(!)        = ''              | ''                 | 'CS31372FB04'           |'R0402'| '(R0402-0201)'                 | '13.7K'   | '1%'    | '1/16W'  | 'IO'       | 'RES CHIP 13.7K 1/16W +-1%(0402)DAL_AEC'           | 'CHIPR0402'    | ''          | ''            | '20160727'
 '15K'        | '1%'      | '1/16W'  | '0402LF'  | 'CHIP'   | 'CS31502FB07'(!)        = ''              | ''                 | 'CS31502FB07'           |'R0402'| '(R0402-0201)'                 | '15K'     | '1%'    | '1/16W'  | 'DISCRETE' | 'RES CHIP 15K 1/16W +-1%(0402)DAL_AEC'             | 'CHIPR0402'    | ''          | ''            | '20160727'
 '15K'        | '1%'      | '1/16W'  | '0402LF'  | 'EMPTY'  | 'CS31502FB07'(!)        = ''              | ''                 | 'CS31502FB07'           |'R0402'| '(R0402-0201)'                 | '15K'     | '1%'    | '1/16W'  | 'IO'       | 'RES CHIP 15K 1/16W +-1%(0402)DAL_AEC'             | 'CHIPR0402'    | ''          | ''            | '20160727'
 '15.4K'      | '1%'      | '1/16W'  | '0402LF'  | 'CHIP'   | 'CS31542FB03'(!)        = ''              | ''                 | 'CS31542FB03'           |'R0402'| '(R0402-0201)'                 | '15.4K'   | '1%'    | '1/16W'  | 'DISCRETE' | 'RES CHIP 15.4K 1/16W +1%(0402)DAL_AEC'            | 'CHIPR0402'    | ''          | ''            | '20160727'
 '15.4K'      | '1%'      | '1/16W'  | '0402LF'  | 'EMPTY'  | 'CS31542FB03'(!)        = ''              | ''                 | 'CS31542FB03'           |'R0402'| '(R0402-0201)'                 | '15.4K'   | '1%'    | '1/16W'  | 'IO'       | 'RES CHIP 15.4K 1/16W +1%(0402)DAL_AEC'            | 'CHIPR0402'    | ''          | ''            | '20160727'
 '15.8K'      | '1%'      | '1/16W'  | '0402LF'  | 'CHIP'   | 'CS31582FB05'(!)        = ''              | ''                 | 'CS31582FB05'           |'R0402'| '(R0402-0201)'                 | '15.8K'   | '1%'    | '1/16W'  | 'DISCRETE' | 'RES CHIP 15.8K 1/16W +-1% (0402)DAL_AEC'          | 'CHIPR0402'    | ''          | ''            | '20160727'
 '15.8K'      | '1%'      | '1/16W'  | '0402LF'  | 'EMPTY'  | 'CS31582FB05'(!)        = ''              | ''                 | 'CS31582FB05'           |'R0402'| '(R0402-0201)'                 | '15.8K'   | '1%'    | '1/16W'  | 'IO'       | 'RES CHIP 15.8K 1/16W +-1% (0402)DAL_AEC'          | 'CHIPR0402'    | ''          | ''            | '20160727'
 '16K'        | '1%'      | '1/16W'  | '0402LF'  | 'CHIP'   | 'CS31602FB03'(!)        = ''              | ''                 | 'CS31602FB03'           |'R0402'| '(R0402-0201)'                 | '16K'     | '1%'    | '1/16W'  | 'DISCRETE' | 'RES CHIP 16K 1/16W +-1%(0402)DAL_AEC'             | 'CHIPR0402'    | ''          | ''            | '20160727'
 '16K'        | '1%'      | '1/16W'  | '0402LF'  | 'EMPTY'  | 'CS31602FB03'(!)        = ''              | ''                 | 'CS31602FB03'           |'R0402'| '(R0402-0201)'                 | '16K'     | '1%'    | '1/16W'  | 'IO'       | 'RES CHIP 16K 1/16W +-1%(0402)DAL_AEC'             | 'CHIPR0402'    | ''          | ''            | '20160727'
 '20K'        | '1%'      | '1/16W'  | '0402LF'  | 'CHIP'   | 'CS32002FB13'(!)        = ''              | ''                 | 'CS32002FB13'           |'R0402'| '(R0402-0201)'                 | '20K'     | '1%'    | '1/16W'  | 'DISCRETE' | 'RES CHIP 20K 1/16W +-1%(0402)DAL_AEC'             | 'CHIPR0402'    | ''          | ''            | '20160727'
 '20K'        | '1%'      | '1/16W'  | '0402LF'  | 'EMPTY'  | 'CS32002FB13'(!)        = ''              | ''                 | 'CS32002FB13'           |'R0402'| '(R0402-0201)'                 | '20K'     | '1%'    | '1/16W'  | 'IO'       | 'RES CHIP 20K 1/16W +-1%(0402)DAL_AEC'             | 'CHIPR0402'    | ''          | ''            | '20160727'
 '21K'        | '1%'      | '1/16W'  | '0402LF'  | 'CHIP'   | 'CS32102FB04'(!)        = ''              | ''                 | 'CS32102FB04'           |'R0402'| '(R0402-0201)'                 | '21K'     | '1%'    | '1/16W'  | 'DISCRETE' | 'RES CHIP 21K 1/16W +-1%(0402)DAL_AEC'             | 'CHIPR0402'    | ''          | ''            | '20160727'
 '21K'        | '1%'      | '1/16W'  | '0402LF'  | 'EMPTY'  | 'CS32102FB04'(!)        = ''              | ''                 | 'CS32102FB04'           |'R0402'| '(R0402-0201)'                 | '21K'     | '1%'    | '1/16W'  | 'IO'       | 'RES CHIP 21K 1/16W +-1%(0402)DAL_AEC'             | 'CHIPR0402'    | ''          | ''            | '20160727'
 '22.1K'      | '1%'      | '1/16W'  | '0402LF'  | 'CHIP'   | 'CS32212FB03'(!)        = ''              | ''                 | 'CS32212FB03'           |'R0402'| '(R0402-0201)'                 | '22.1K'   | '1%'    | '1/16W'  | 'DISCRETE' | 'RES CHIP 22.1K 1/16W +-1%(0402)DAL_AEC'           | 'CHIPR0402'    | ''          | ''            | '20160727'
 '22.1K'      | '1%'      | '1/16W'  | '0402LF'  | 'EMPTY'  | 'CS32212FB03'(!)        = ''              | ''                 | 'CS32212FB03'           |'R0402'| '(R0402-0201)'                 | '22.1K'   | '1%'    | '1/16W'  | 'IO'       | 'RES CHIP 22.1K 1/16W +-1%(0402)DAL_AEC'           | 'CHIPR0402'    | ''          | ''            | '20160727'
 '3.3'        | '1%'      | '1/16W'  | '0402LF'  | 'CHIP'   | 'CS-3302FB03'(!)        = ''              | ''                 | 'CS-3302FB03'           |'R0402'| '(R0402-0201)'                 | '3.3'     | '1%'    | '1/16W'  | 'DISCRETE' | 'RES CHIP 3.3 1/16W +-1%(0402)DAL_AEC'             | 'CHIPR0402'    | ''          | ''            | '20160727'
 '3.3'        | '1%'      | '1/16W'  | '0402LF'  | 'EMPTY'  | 'CS-3302FB03'(!)        = ''              | ''                 | 'CS-3302FB03'           |'R0402'| '(R0402-0201)'                 | '3.3'     | '1%'    | '1/16W'  | 'IO'       | 'RES CHIP 3.3 1/16W +-1%(0402)DAL_AEC'             | 'CHIPR0402'    | ''          | ''            | '20160727'
 '237'        | '1%'      | '1/16W'  | '0402LF'  | 'CHIP'   | 'CS12372FB00'(!)        = 'End of Design' | 'Comp-Approve'     | 'CS12372FB00'           |'R0402'| '(R0402-0201)'                 | '237'     | '1%'    | '1/16W'  | 'DISCRETE' | 'RES CHIP 237 1/16W +-1%(0402)'                    | 'CHIPR0402'    | ''          | ''            | '20160727'
 '237'        | '1%'      | '1/16W'  | '0402LF'  | 'EMPTY'  | 'CS12372FB00'(!)        = 'End of Design' | 'Comp-Approve'     | 'CS12372FB00'           |'R0402'| '(R0402-0201)'                 | '237'     | '1%'    | '1/16W'  | 'IO'       | 'RES CHIP 237 1/16W +-1%(0402)'                    | 'CHIPR0402'    | ''          | ''            | '20160727'
 '31.6K'      | '1%'      | '1/16W'  | '0402LF'  | 'CHIP'   | 'CS33162FB03'(!)        = ''              | ''                 | 'CS33162FB03'           |'R0402'| '(R0402-0201)'                 | '31.6K'   | '1%'    | '1/16W'  | 'DISCRETE' | 'RES CHIP 31.6K 1/16W +1%(0402)DAL_AEC'            | 'CHIPR0402'    | ''          | ''            | '20160802'
 '31.6K'      | '1%'      | '1/16W'  | '0402LF'  | 'EMPTY'  | 'CS33162FB03'(!)        = ''              | ''                 | 'CS33162FB03'           |'R0402'| '(R0402-0201)'                 | '31.6K'   | '1%'    | '1/16W'  | 'IO'       | 'RES CHIP 31.6K 1/16W +1%(0402)DAL_AEC'            | 'CHIPR0402'    | ''          | ''            | '20160802'
 '27K'        | '1%'      | '1/16W'  | '0402LF'  | 'CHIP'   | 'CS32702FB02'(!)        = ''              | ''                 | 'CS32702FB02'           |'R0402'| '(R0402-0201)'                 | '27K'     | '1%'    | '1/16W'  | 'DISCRETE' | 'RES CHIP 27K 1/16W +-1%(0402)DAL_AEC'             | 'CHIPR0402'    | ''          | ''            | '20160802'
 '27K'        | '1%'      | '1/16W'  | '0402LF'  | 'EMPTY'  | 'CS32702FB02'(!)        = ''              | ''                 | 'CS32702FB02'           |'R0402'| '(R0402-0201)'                 | '27K'     | '1%'    | '1/16W'  | 'IO'       | 'RES CHIP 27K 1/16W +-1%(0402)DAL_AEC'             | 'CHIPR0402'    | ''          | ''            | '20160802'
 '27.4K'      | '1%'      | '1/16W'  | '0402LF'  | 'CHIP'   | 'CS32742FB05'(!)        = ''              | ''                 | 'CS32742FB05'           |'R0402'| '(R0402-0201)'                 | '27.4K'   | '1%'    | '1/16W'  | 'DISCRETE' | 'RES CHIP 27.4K 1/16W +-1%(0402)DAL_AEC'           | 'CHIPR0402'    | ''          | ''            | '20160802'
 '27.4K'      | '1%'      | '1/16W'  | '0402LF'  | 'EMPTY'  | 'CS32742FB05'(!)        = ''              | ''                 | 'CS32742FB05'           |'R0402'| '(R0402-0201)'                 | '27.4K'   | '1%'    | '1/16W'  | 'IO'       | 'RES CHIP 27.4K 1/16W +-1%(0402)DAL_AEC'           | 'CHIPR0402'    | ''          | ''            | '20160802'
 '25.5K'      | '1%'      | '1/16W'  | '0402LF'  | 'CHIP'   | 'CS32552FB05'(!)        = ''              | ''                 | 'CS32552FB05'           |'R0402'| '(R0402-0201)'                 | '25.5K'   | '1%'    | '1/16W'  | 'DISCRETE' | 'RES CHIP 25.5K 1/16W +-1%(0402)DAL_AEC'           | 'CHIPR0402'    | ''          | ''            | '20160802'
 '25.5K'      | '1%'      | '1/16W'  | '0402LF'  | 'EMPTY'  | 'CS32552FB05'(!)        = ''              | ''                 | 'CS32552FB05'           |'R0402'| '(R0402-0201)'                 | '25.5K'   | '1%'    | '1/16W'  | 'IO'       | 'RES CHIP 25.5K 1/16W +-1%(0402)DAL_AEC'           | 'CHIPR0402'    | ''          | ''            | '20160802'
 '41.2K'      | '1%'      | '1/16W'  | '0402LF'  | 'CHIP'   | 'CS34122FB02'(!)        = ''              | ''                 | 'CS34122FB02'           |'R0402'| '(R0402-0201)'                 | '41.2K'   | '1%'    | '1/16W'  | 'DISCRETE' | 'RES CHIP 41.2K 1/16W +-1%(0402)DAL_AEC'           | 'CHIPR0402'    | ''          | ''            | '20160802'
 '41.2K'      | '1%'      | '1/16W'  | '0402LF'  | 'EMPTY'  | 'CS34122FB02'(!)        = ''              | ''                 | 'CS34122FB02'           |'R0402'| '(R0402-0201)'                 | '41.2K'   | '1%'    | '1/16W'  | 'IO'       | 'RES CHIP 41.2K 1/16W +-1%(0402)DAL_AEC'           | 'CHIPR0402'    | ''          | ''            | '20160802'
 '37.4K'      | '1%'      | '1/16W'  | '0402LF'  | 'CHIP'   | 'CS33742FB07'(!)        = ''              | ''                 | 'CS33742FB07'           |'R0402'| '(R0402-0201)'                 | '37.4K'   | '1%'    | '1/16W'  | 'DISCRETE' | 'RES CHIP 37.4K 1/16W +-1% (0402)DAL_AEC'          | 'CHIPR0402'    | ''          | ''            | '20160802'
 '37.4K'      | '1%'      | '1/16W'  | '0402LF'  | 'EMPTY'  | 'CS33742FB07'(!)        = ''              | ''                 | 'CS33742FB07'           |'R0402'| '(R0402-0201)'                 | '37.4K'   | '1%'    | '1/16W'  | 'IO'       | 'RES CHIP 37.4K 1/16W +-1% (0402)DAL_AEC'          | 'CHIPR0402'    | ''          | ''            | '20160802'
 '34K'        | '1%'      | '1/16W'  | '0402LF'  | 'CHIP'   | 'CS33402FB04'(!)        = ''              | ''                 | 'CS33402FB04'           |'R0402'| '(R0402-0201)'                 | '34K'     | '1%'    | '1/16W'  | 'DISCRETE' | 'RES CHIP 34K 1/16W +-1%(0402)DAL_AEC'             | 'CHIPR0402'    | ''          | ''            | '20160802'
 '34K'        | '1%'      | '1/16W'  | '0402LF'  | 'EMPTY'  | 'CS33402FB04'(!)        = ''              | ''                 | 'CS33402FB04'           |'R0402'| '(R0402-0201)'                 | '34K'     | '1%'    | '1/16W'  | 'IO'       | 'RES CHIP 34K 1/16W +-1%(0402)DAL_AEC'             | 'CHIPR0402'    | ''          | ''            | '20160802'
 '34.8K'      | '1%'      | '1/16W'  | '0402LF'  | 'CHIP'   | 'CS33482FB02'(!)        = ''              | ''                 | 'CS33482FB02'           |'R0402'| '(R0402-0201)'                 | '34.8K'   | '1%'    | '1/16W'  | 'DISCRETE' | 'RES CHIP 34.8K 1/16W +-1% (0402)DAL_AEC'          | 'CHIPR0402'    | ''          | ''            | '20160803'
 '34.8K'      | '1%'      | '1/16W'  | '0402LF'  | 'EMPTY'  | 'CS33482FB02'(!)        = ''              | ''                 | 'CS33482FB02'           |'R0402'| '(R0402-0201)'                 | '34.8K'   | '1%'    | '1/16W'  | 'IO'       | 'RES CHIP 34.8K 1/16W +-1% (0402)DAL_AEC'          | 'CHIPR0402'    | ''          | ''            | '20160803'
 '47K'        | '1%'      | '1/16W'  | '0402LF'  | 'CHIP'   | 'CS34702FB04'(!)        = ''              | ''                 | 'CS34702FB04'           |'R0402'| '(R0402-0201)'                 | '47K'     | '1%'    | '1/16W'  | 'DISCRETE' | 'RES CHIP 47K 1/16W +-1%(0402)DAL_AEC'             | 'CHIPR0402'    | ''          | ''            | '20160803'
 '47K'        | '1%'      | '1/16W'  | '0402LF'  | 'EMPTY'  | 'CS34702FB04'(!)        = ''              | ''                 | 'CS34702FB04'           |'R0402'| '(R0402-0201)'                 | '47K'     | '1%'    | '1/16W'  | 'IO'       | 'RES CHIP 47K 1/16W +-1%(0402)DAL_AEC'             | 'CHIPR0402'    | ''          | ''            | '20160803'
 '45.3K'      | '1%'      | '1/16W'  | '0402LF'  | 'CHIP'   | 'CS34532FB06'(!)        = ''              | ''                 | 'CS34532FB06'           |'R0402'| '(R0402-0201)'                 | '45.3K'   | '1%'    | '1/16W'  | 'DISCRETE' | 'RES CHIP 45.3K 1/16W +-1% (0402)DAL_AEC'          | 'CHIPR0402'    | ''          | ''            | '20160803'
 '45.3K'      | '1%'      | '1/16W'  | '0402LF'  | 'EMPTY'  | 'CS34532FB06'(!)        = ''              | ''                 | 'CS34532FB06'           |'R0402'| '(R0402-0201)'                 | '45.3K'   | '1%'    | '1/16W'  | 'IO'       | 'RES CHIP 45.3K 1/16W +-1% (0402)DAL_AEC'          | 'CHIPR0402'    | ''          | ''            | '20160803'
 '64.9K'      | '1%'      | '1/16W'  | '0402LF'  | 'CHIP'   | 'CS36492FB04'(!)        = ''              | ''                 | 'CS36492FB04'           |'R0402'| '(R0402-0201)'                 | '64.9K'   | '1%'    | '1/16W'  | 'DISCRETE' | 'RES CHIP 64.9K 1/16W +1%(0402)DAL_AEC'            | 'CHIPR0402'    | ''          | ''            | '20160803'
 '64.9K'      | '1%'      | '1/16W'  | '0402LF'  | 'EMPTY'  | 'CS36492FB04'(!)        = ''              | ''                 | 'CS36492FB04'           |'R0402'| '(R0402-0201)'                 | '64.9K'   | '1%'    | '1/16W'  | 'IO'       | 'RES CHIP 64.9K 1/16W +1%(0402)DAL_AEC'            | 'CHIPR0402'    | ''          | ''            | '20160803'
 '60.4K'      | '1%'      | '1/16W'  | '0402LF'  | 'CHIP'   | 'CS36042FB05'(!)        = ''              | ''                 | 'CS36042FB05'           |'R0402'| '(R0402-0201)'                 | '60.4K'   | '1%'    | '1/16W'  | 'DISCRETE' | 'RES CHIP 60.4K 1/16W +-1%(0402)DAL_AEC'           | 'CHIPR0402'    | ''          | ''            | '20160803'
 '60.4K'      | '1%'      | '1/16W'  | '0402LF'  | 'EMPTY'  | 'CS36042FB05'(!)        = ''              | ''                 | 'CS36042FB05'           |'R0402'| '(R0402-0201)'                 | '60.4K'   | '1%'    | '1/16W'  | 'IO'       | 'RES CHIP 60.4K 1/16W +-1%(0402)DAL_AEC'           | 'CHIPR0402'    | ''          | ''            | '20160803'
 '53.6K'      | '1%'      | '1/16W'  | '0402LF'  | 'CHIP'   | 'CS35362FB04'(!)        = ''              | ''                 | 'CS35362FB04'           |'R0402'| '(R0402-0201)'                 | '53.6K'   | '1%'    | '1/16W'  | 'DISCRETE' | 'RES CHIP 53.6K 1/16W +1%(0402)DAL_AEC'            | 'CHIPR0402'    | ''          | ''            | '20160803'
 '53.6K'      | '1%'      | '1/16W'  | '0402LF'  | 'EMPTY'  | 'CS35362FB04'(!)        = ''              | ''                 | 'CS35362FB04'           |'R0402'| '(R0402-0201)'                 | '53.6K'   | '1%'    | '1/16W'  | 'IO'       | 'RES CHIP 53.6K 1/16W +1%(0402)DAL_AEC'            | 'CHIPR0402'    | ''          | ''            | '20160803'
 '56.2K'      | '1%'      | '1/16W'  | '0402LF'  | 'CHIP'   | 'CS35622FB04'(!)        = ''              | ''                 | 'CS35622FB04'           |'R0402'| '(R0402-0201)'                 | '56.2K'   | '1%'    | '1/16W'  | 'DISCRETE' | 'RES CHIP 56.2K 1/16W +-1% (0402)DAL_AEC'          | 'CHIPR0402'    | ''          | ''            | '20160803'
 '56.2K'      | '1%'      | '1/16W'  | '0402LF'  | 'EMPTY'  | 'CS35622FB04'(!)        = ''              | ''                 | 'CS35622FB04'           |'R0402'| '(R0402-0201)'                 | '56.2K'   | '1%'    | '1/16W'  | 'IO'       | 'RES CHIP 56.2K 1/16W +-1% (0402)DAL_AEC'          | 'CHIPR0402'    | ''          | ''            | '20160803'
 '49.9K'      | '1%'      | '1/16W'  | '0402LF'  | 'CHIP'   | 'CS34992FB07'(!)        = ''              | ''                 | 'CS34992FB07'           |'R0402'| '(R0402-0201)'                 | '49.9K'   | '1%'    | '1/16W'  | 'DISCRETE' | 'RES CHIP 49.9K 1/16W +-1%(0402)DAL_AEC'           | 'CHIPR0402'    | ''          | ''            | '20160803'
 '49.9K'      | '1%'      | '1/16W'  | '0402LF'  | 'EMPTY'  | 'CS34992FB07'(!)        = ''              | ''                 | 'CS34992FB07'           |'R0402'| '(R0402-0201)'                 | '49.9K'   | '1%'    | '1/16W'  | 'IO'       | 'RES CHIP 49.9K 1/16W +-1%(0402)DAL_AEC'           | 'CHIPR0402'    | ''          | ''            | '20160803'
 '68K'        | '1%'      | '1/16W'  | '0402LF'  | 'CHIP'   | 'CS36802FB03'(!)        = ''              | ''                 | 'CS36802FB03'           |'R0402'| '(R0402-0201)'                 | '68K'     | '1%'    | '1/16W'  | 'DISCRETE' | 'RES CHIP 68K 1/16W +1%(0402)DAL_AEC'              | 'CHIPR0402'    | ''          | ''            | '20160803'
 '68K'        | '1%'      | '1/16W'  | '0402LF'  | 'EMPTY'  | 'CS36802FB03'(!)        = ''              | ''                 | 'CS36802FB03'           |'R0402'| '(R0402-0201)'                 | '68K'     | '1%'    | '1/16W'  | 'IO'       | 'RES CHIP 68K 1/16W +1%(0402)DAL_AEC'              | 'CHIPR0402'    | ''          | ''            | '20160803'
 '66.5K'      | '1%'      | '1/16W'  | '0402LF'  | 'CHIP'   | 'CS36652FB02'(!)        = ''              | ''                 | 'CS36652FB02'           |'R0402'| '(R0402-0201)'                 | '66.5K'   | '1%'    | '1/16W'  | 'DISCRETE' | 'RES CHIP 66.5K 1/16W +-1%(0402)DAL_AEC'           | 'CHIPR0402'    | ''          | ''            | '20160803'
 '66.5K'      | '1%'      | '1/16W'  | '0402LF'  | 'EMPTY'  | 'CS36652FB02'(!)        = ''              | ''                 | 'CS36652FB02'           |'R0402'| '(R0402-0201)'                 | '66.5K'   | '1%'    | '1/16W'  | 'IO'       | 'RES CHIP 66.5K 1/16W +-1%(0402)DAL_AEC'           | 'CHIPR0402'    | ''          | ''            | '20160803'
 '82K'        | '1%'      | '1/16W'  | '0402LF'  | 'CHIP'   | 'CS38202FB00'(!)        = ''              | ''                 | 'CS38202FB00'           |'R0402'| '(R0402-0201)'                 | '82K'     | '1%'    | '1/16W'  | 'DISCRETE' | 'RES CHIP 82K 1/16W +1%(0402)DAL_AEC'              | 'CHIPR0402'    | ''          | ''            | '20160803'
 '82K'        | '1%'      | '1/16W'  | '0402LF'  | 'EMPTY'  | 'CS38202FB00'(!)        = ''              | ''                 | 'CS38202FB00'           |'R0402'| '(R0402-0201)'                 | '82K'     | '1%'    | '1/16W'  | 'IO'       | 'RES CHIP 82K 1/16W +1%(0402)DAL_AEC'              | 'CHIPR0402'    | ''          | ''            | '20160803'
 '86.6K'      | '1%'      | '1/16W'  | '0402LF'  | 'CHIP'   | 'CS38662FB03'(!)        = ''              | ''                 | 'CS38662FB03'           |'R0402'| '(R0402-0201)'                 | '86.6K'   | '1%'    | '1/16W'  | 'DISCRETE' | 'RES CHIP 86.6K 1/16W +-1%(0402)DAL_AEC'           | 'CHIPR0402'    | ''          | ''            | '20160803'
 '86.6K'      | '1%'      | '1/16W'  | '0402LF'  | 'EMPTY'  | 'CS38662FB03'(!)        = ''              | ''                 | 'CS38662FB03'           |'R0402'| '(R0402-0201)'                 | '86.6K'   | '1%'    | '1/16W'  | 'IO'       | 'RES CHIP 86.6K 1/16W +-1%(0402)DAL_AEC'           | 'CHIPR0402'    | ''          | ''            | '20160803'
 '75K'        | '1%'      | '1/16W'  | '0402LF'  | 'CHIP'   | 'CS37502FB06'(!)        = ''              | ''                 | 'CS37502FB06'           |'R0402'| '(R0402-0201)'                 | '75K'     | '1%'    | '1/16W'  | 'DISCRETE' | 'RES CHIP 75K 1/16W +-1%(0402)DAL_AEC'             | 'CHIPR0402'    | ''          | ''            | '20160803'
 '75K'        | '1%'      | '1/16W'  | '0402LF'  | 'EMPTY'  | 'CS37502FB06'(!)        = ''              | ''                 | 'CS37502FB06'           |'R0402'| '(R0402-0201)'                 | '75K'     | '1%'    | '1/16W'  | 'IO'       | 'RES CHIP 75K 1/16W +-1%(0402)DAL_AEC'             | 'CHIPR0402'    | ''          | ''            | '20160803'
 '80.6K'      | '1%'      | '1/16W'  | '0402LF'  | 'CHIP'   | 'CS38062FB07'(!)        = ''              | ''                 | 'CS38062FB07'           |'R0402'| '(R0402-0201)'                 | '80.6K'   | '1%'    | '1/16W'  | 'DISCRETE' | 'RES CHIP 80.6K 1/16W +-1% (0402)DAL_AEC'          | 'CHIPR0402'    | ''          | ''            | '20160803'
 '80.6K'      | '1%'      | '1/16W'  | '0402LF'  | 'EMPTY'  | 'CS38062FB07'(!)        = ''              | ''                 | 'CS38062FB07'           |'R0402'| '(R0402-0201)'                 | '80.6K'   | '1%'    | '1/16W'  | 'IO'       | 'RES CHIP 80.6K 1/16W +-1% (0402)DAL_AEC'          | 'CHIPR0402'    | ''          | ''            | '20160803'
 '69.8K'      | '1%'      | '1/16W'  | '0402LF'  | 'CHIP'   | 'CS36982FB05'(!)        = ''              | ''                 | 'CS36982FB05'           |'R0402'| '(R0402-0201)'                 | '69.8K'   | '1%'    | '1/16W'  | 'DISCRETE' | 'RES CHIP 69.8K 1/16W +-1% (0402)DAL_AEC'          | 'CHIPR0402'    | ''          | ''            | '20160803'
 '69.8K'      | '1%'      | '1/16W'  | '0402LF'  | 'EMPTY'  | 'CS36982FB05'(!)        = ''              | ''                 | 'CS36982FB05'           |'R0402'| '(R0402-0201)'                 | '69.8K'   | '1%'    | '1/16W'  | 'IO'       | 'RES CHIP 69.8K 1/16W +-1% (0402)DAL_AEC'          | 'CHIPR0402'    | ''          | ''            | '20160803'
 '100K'       | '1%'      | '1/16W'  | '0402LF'  | 'CHIP'   | 'CS41002FB17'(!)        = ''              | ''                 | 'CS41002FB17'           |'R0402'| '(R0402-0201)'                 | '100K'    | '1%'    | '1/16W'  | 'DISCRETE' | 'RES CHIP 100K 1/16W +-1%(0402) DAL_AEC'           | 'CHIPR0402'    | ''          | ''            | '20160803'
 '100K'       | '1%'      | '1/16W'  | '0402LF'  | 'EMPTY'  | 'CS41002FB17'(!)        = ''              | ''                 | 'CS41002FB17'           |'R0402'| '(R0402-0201)'                 | '100K'    | '1%'    | '1/16W'  | 'IO'       | 'RES CHIP 100K 1/16W +-1%(0402) DAL_AEC'           | 'CHIPR0402'    | ''          | ''            | '20160803'
 '107K'       | '1%'      | '1/16W'  | '0402LF'  | 'CHIP'   | 'CS41072FB01'(!)        = ''              | ''                 | 'CS41072FB01'           |'R0402'| '(R0402-0201)'                 | '107K'    | '1%'    | '1/16W'  | 'DISCRETE' | 'RES CHIP 107K 1/16W +1%(0402)DAL_AEC'             | 'CHIPR0402'    | ''          | ''            | '20160805'
 '107K'       | '1%'      | '1/16W'  | '0402LF'  | 'EMPTY'  | 'CS41072FB01'(!)        = ''              | ''                 | 'CS41072FB01'           |'R0402'| '(R0402-0201)'                 | '107K'    | '1%'    | '1/16W'  | 'IO'       | 'RES CHIP 107K 1/16W +1%(0402)DAL_AEC'             | 'CHIPR0402'    | ''          | ''            | '20160805'
 '150K'       | '1%'      | '1/16W'  | '0402LF'  | 'CHIP'   | 'CS41502FB06'(!)        = ''              | ''                 | 'CS41502FB06'           |'R0402'| '(R0402-0201)'                 | '150K'    | '1%'    | '1/16W'  | 'DISCRETE' | 'RES CHIP 150K 1/16W +-1%(0402)DAL_AEC'            | 'CHIPR0402'    | ''          | ''            | '20160805'
 '150K'       | '1%'      | '1/16W'  | '0402LF'  | 'EMPTY'  | 'CS41502FB06'(!)        = ''              | ''                 | 'CS41502FB06'           |'R0402'| '(R0402-0201)'                 | '150K'    | '1%'    | '1/16W'  | 'IO'       | 'RES CHIP 150K 1/16W +-1%(0402)DAL_AEC'            | 'CHIPR0402'    | ''          | ''            | '20160805'
 '147K'       | '1%'      | '1/16W'  | '0402LF'  | 'CHIP'   | 'CS41472FB05'(!)        = ''              | ''                 | 'CS41472FB05'           |'R0402'| '(R0402-0201)'                 | '147K'    | '1%'    | '1/16W'  | 'DISCRETE' | 'RES CHIP 147K 1/16W +-1%(0402)DAL_AEC'            | 'CHIPR0402'    | ''          | ''            | '20160805'
 '147K'       | '1%'      | '1/16W'  | '0402LF'  | 'EMPTY'  | 'CS41472FB05'(!)        = ''              | ''                 | 'CS41472FB05'           |'R0402'| '(R0402-0201)'                 | '147K'    | '1%'    | '1/16W'  | 'IO'       | 'RES CHIP 147K 1/16W +-1%(0402)DAL_AEC'            | 'CHIPR0402'    | ''          | ''            | '20160805'
 '143K'       | '1%'      | '1/16W'  | '0402LF'  | 'CHIP'   | 'CS41432FB03'(!)        = ''              | ''                 | 'CS41432FB03'           |'R0402'| '(R0402-0201)'                 | '143K'    | '1%'    | '1/16W'  | 'DISCRETE' | 'RES CHIP 143K 1/16W +-1%(0402)DAL_AEC'            | 'CHIPR0402'    | ''          | ''            | '20160805'
 '143K'       | '1%'      | '1/16W'  | '0402LF'  | 'EMPTY'  | 'CS41432FB03'(!)        = ''              | ''                 | 'CS41432FB03'           |'R0402'| '(R0402-0201)'                 | '143K'    | '1%'    | '1/16W'  | 'IO'       | 'RES CHIP 143K 1/16W +-1%(0402)DAL_AEC'            | 'CHIPR0402'    | ''          | ''            | '20160805'
 '115K'       | '1%'      | '1/16W'  | '0402LF'  | 'CHIP'   | 'CS41152FB02'(!)        = ''              | ''                 | 'CS41152FB02'           |'R0402'| '(R0402-0201)'                 | '115K'    | '1%'    | '1/16W'  | 'DISCRETE' | 'RES CHIP 115K 1/16W +-1%(0402)DAL_AEC'            | 'CHIPR0402'    | ''          | ''            | '20160805'
 '115K'       | '1%'      | '1/16W'  | '0402LF'  | 'EMPTY'  | 'CS41152FB02'(!)        = ''              | ''                 | 'CS41152FB02'           |'R0402'| '(R0402-0201)'                 | '115K'    | '1%'    | '1/16W'  | 'IO'       | 'RES CHIP 115K 1/16W +-1%(0402)DAL_AEC'            | 'CHIPR0402'    | ''          | ''            | '20160805'
 '118K'       | '1%'      | '1/16W'  | '0402LF'  | 'CHIP'   | 'CS41182FB03'(!)        = ''              | ''                 | 'CS41182FB03'           |'R0402'| '(R0402-0201)'                 | '118K'    | '1%'    | '1/16W'  | 'DISCRETE' | 'RES CHIP 118K 1/16W +-1%(0402)DAL_AEC'            | 'CHIPR0402'    | ''          | ''            | '20160805'
 '118K'       | '1%'      | '1/16W'  | '0402LF'  | 'EMPTY'  | 'CS41182FB03'(!)        = ''              | ''                 | 'CS41182FB03'           |'R0402'| '(R0402-0201)'                 | '118K'    | '1%'    | '1/16W'  | 'IO'       | 'RES CHIP 118K 1/16W +-1%(0402)DAL_AEC'            | 'CHIPR0402'    | ''          | ''            | '20160805'
 '120K'       | '1%'      | '1/16W'  | '0402LF'  | 'CHIP'   | 'CS41202FB02'(!)        = ''              | ''                 | 'CS41202FB02'           |'R0402'| '(R0402-0201)'                 | '120K'    | '1%'    | '1/16W'  | 'DISCRETE' | 'RES CHIP 120K 1/16W +-1%( 0402)DAL_AEC'           | 'CHIPR0402'    | ''          | ''            | '20160805'
 '120K'       | '1%'      | '1/16W'  | '0402LF'  | 'EMPTY'  | 'CS41202FB02'(!)        = ''              | ''                 | 'CS41202FB02'           |'R0402'| '(R0402-0201)'                 | '120K'    | '1%'    | '1/16W'  | 'IO'       | 'RES CHIP 120K 1/16W +-1%( 0402)DAL_AEC'           | 'CHIPR0402'    | ''          | ''            | '20160805'
 '133K'       | '1%'      | '1/16W'  | '0402LF'  | 'CHIP'   | 'CS41332FB03'(!)        = ''              | ''                 | 'CS41332FB03'           |'R0402'| '(R0402-0201)'                 | '133K'    | '1%'    | '1/16W'  | 'DISCRETE' | 'RES CHIP 133K 1/16W +-1%(0402)DAL_AEC'            | 'CHIPR0402'    | ''          | ''            | '20160805'
 '133K'       | '1%'      | '1/16W'  | '0402LF'  | 'EMPTY'  | 'CS41332FB03'(!)        = ''              | ''                 | 'CS41332FB03'           |'R0402'| '(R0402-0201)'                 | '133K'    | '1%'    | '1/16W'  | 'IO'       | 'RES CHIP 133K 1/16W +-1%(0402)DAL_AEC'            | 'CHIPR0402'    | ''          | ''            | '20160805'
 '154K'       | '1%'      | '1/16W'  | '0402LF'  | 'CHIP'   | 'CS41542FB07'(!)        = ''              | ''                 | 'CS41542FB07'           |'R0402'| '(R0402-0201)'                 | '154K'    | '1%'    | '1/16W'  | 'DISCRETE' | 'RES CHIP 154K 1/16W +-1%(0402)DAL_AEC'            | 'CHIPR0402'    | ''          | ''            | '20160805'
 '154K'       | '1%'      | '1/16W'  | '0402LF'  | 'EMPTY'  | 'CS41542FB07'(!)        = ''              | ''                 | 'CS41542FB07'           |'R0402'| '(R0402-0201)'                 | '154K'    | '1%'    | '1/16W'  | 'IO'       | 'RES CHIP 154K 1/16W +-1%(0402)DAL_AEC'            | 'CHIPR0402'    | ''          | ''            | '20160805'
 '162K'       | '1%'      | '1/16W'  | '0402LF'  | 'CHIP'   | 'CS41622FB04'(!)        = ''              | ''                 | 'CS41622FB04'           |'R0402'| '(R0402-0201)'                 | '162K'    | '1%'    | '1/16W'  | 'DISCRETE' | 'RES CHIP 162K 1/16W +-1% (0402)DAL_AEC'           | 'CHIPR0402'    | ''          | ''            | '20160805'
 '162K'       | '1%'      | '1/16W'  | '0402LF'  | 'EMPTY'  | 'CS41622FB04'(!)        = ''              | ''                 | 'CS41622FB04'           |'R0402'| '(R0402-0201)'                 | '162K'    | '1%'    | '1/16W'  | 'IO'       | 'RES CHIP 162K 1/16W +-1% (0402)DAL_AEC'           | 'CHIPR0402'    | ''          | ''            | '20160805'
 '200K'       | '1%'      | '1/16W'  | '0402LF'  | 'CHIP'   | 'CS42002FB11'(!)        = ''              | ''                 | 'CS42002FB11'           |'R0402'| '(R0402-0201)'                 | '200K'    | '1%'    | '1/16W'  | 'DISCRETE' | 'RES CHIP 200K 1/16W +-1%(0402)DAL_AEC'            | 'CHIPR0402'    | ''          | ''            | '20160805'
 '200K'       | '1%'      | '1/16W'  | '0402LF'  | 'EMPTY'  | 'CS42002FB11'(!)        = ''              | ''                 | 'CS42002FB11'           |'R0402'| '(R0402-0201)'                 | '200K'    | '1%'    | '1/16W'  | 'IO'       | 'RES CHIP 200K 1/16W +-1%(0402)DAL_AEC'            | 'CHIPR0402'    | ''          | ''            | '20160805'
 '255K'       | '1%'      | '1/16W'  | '0402LF'  | 'CHIP'   | 'CS42552FB04'(!)        = ''              | ''                 | 'CS42552FB04'           |'R0402'| '(R0402-0201)'                 | '255K'    | '1%'    | '1/16W'  | 'DISCRETE' | 'RES CHIP 255K 1/16W +-1%(0402)DAL_AEC'            | 'CHIPR0402'    | ''          | ''            | '20160805'
 '255K'       | '1%'      | '1/16W'  | '0402LF'  | 'EMPTY'  | 'CS42552FB04'(!)        = ''              | ''                 | 'CS42552FB04'           |'R0402'| '(R0402-0201)'                 | '255K'    | '1%'    | '1/16W'  | 'IO'       | 'RES CHIP 255K 1/16W +-1%(0402)DAL_AEC'            | 'CHIPR0402'    | ''          | ''            | '20160805'
 '20M'        | '5%'      | '1/16W'  | '0402LF'  | 'CHIP'   | 'CS62002JB18'(!)        = ''              | ''                 | 'CS62002JB18'           |'R0402'| '(R0402-0201)'                 | '20M'     | '5%'    | '1/16W'  | 'DISCRETE' | 'RES CHIP 20M 1/16W +-5%(0402)'                    | 'CHIPR0402'    | ''          | ''            | '20160808'
 '20M'        | '5%'      | '1/16W'  | '0402LF'  | 'EMPTY'  | 'CS62002JB18'(!)        = ''              | ''                 | 'CS62002JB18'           |'R0402'| '(R0402-0201)'                 | '20M'     | '5%'    | '1/16W'  | 'IO'       | 'RES CHIP 20M 1/16W +-5%(0402)'                    | 'CHIPR0402'    | ''          | ''            | '20160808'
 '24'         | '1%'      | '1/16W'  | '0402LF'  | 'CHIP'   | 'CS02402FB00'(!)        = 'End of Design' | 'Comp-Approve'     | 'CS02402FB00'           |'R0402'| '(R0402-0201)'                 | '24'      | '1%'    | '1/16W'  | 'DISCRETE' | 'RES CHIP 24 1/16W +-1%(0402)DAL_AEC'              | 'CHIPR0402'    | ''          | ''            | '20160808'
 '24'         | '1%'      | '1/16W'  | '0402LF'  | 'EMPTY'  | 'CS02402FB00'(!)        = 'End of Design' | 'Comp-Approve'     | 'CS02402FB00'           |'R0402'| '(R0402-0201)'                 | '24'      | '1%'    | '1/16W'  | 'IO'       | 'RES CHIP 24 1/16W +-1%(0402)DAL_AEC'              | 'CHIPR0402'    | ''          | ''            | '20160808'
 '280K'       | '1%'      | '1/16W'  | '0402LF'  | 'CHIP'   | 'CS42802FB04'(!)        = ''              | ''                 | 'CS42802FB04'           |'R0402'| '(R0402-0201)'                 | '280K'    | '1%'    | '1/16W'  | 'DISCRETE' | 'RES CHIP 280K 1/16W +-1%(0402)DAL_AEC'            | 'CHIPR0402'    | ''          | ''            | '20160809'
 '280K'       | '1%'      | '1/16W'  | '0402LF'  | 'EMPTY'  | 'CS42802FB04'(!)        = ''              | ''                 | 'CS42802FB04'           |'R0402'| '(R0402-0201)'                 | '280K'    | '1%'    | '1/16W'  | 'IO'       | 'RES CHIP 280K 1/16W +-1%(0402)DAL_AEC'            | 'CHIPR0402'    | ''          | ''            | '20160809'
 '348K'       | '1%'      | '1/16W'  | '0402LF'  | 'CHIP'   | 'CS43482FB03'(!)        = ''              | ''                 | 'CS43482FB03'           |'R0402'| '(R0402-0201)'                 | '348K'    | '1%'    | '1/16W'  | 'DISCRETE' | 'RES CHIP 348K 1/16W +-1%( 0402)DAL_AEC'           | 'CHIPR0402'    | ''          | ''            | '20160809'
 '348K'       | '1%'      | '1/16W'  | '0402LF'  | 'EMPTY'  | 'CS43482FB03'(!)        = ''              | ''                 | 'CS43482FB03'           |'R0402'| '(R0402-0201)'                 | '348K'    | '1%'    | '1/16W'  | 'IO'       | 'RES CHIP 348K 1/16W +-1%( 0402)DAL_AEC'           | 'CHIPR0402'    | ''          | ''            | '20160809'
 '475K'       | '1%'      | '1/16W'  | '0402LF'  | 'CHIP'   | 'CS44752FB04'(!)        = ''              | ''                 | 'CS44752FB04'           |'R0402'| '(R0402-0201)'                 | '475K'    | '1%'    | '1/16W'  | 'DISCRETE' | 'RES CHIP 475K 1/16W +-1%(0402)DAL_AEC'            | 'CHIPR0402'    | ''          | ''            | '20160809'
 '475K'       | '1%'      | '1/16W'  | '0402LF'  | 'EMPTY'  | 'CS44752FB04'(!)        = ''              | ''                 | 'CS44752FB04'           |'R0402'| '(R0402-0201)'                 | '475K'    | '1%'    | '1/16W'  | 'IO'       | 'RES CHIP 475K 1/16W +-1%(0402)DAL_AEC'            | 'CHIPR0402'    | ''          | ''            | '20160809'
 '499K'       | '1%'      | '1/16W'  | '0402LF'  | 'CHIP'   | 'CS44992FB02'(!)        = ''              | ''                 | 'CS44992FB02'           |'R0402'| '(R0402-0201)'                 | '499K'    | '1%'    | '1/16W'  | 'DISCRETE' | 'RES CHIP 499K 1/16W +1% (0402)DAL_AEC'            | 'CHIPR0402'    | ''          | ''            | '20160809'
 '499K'       | '1%'      | '1/16W'  | '0402LF'  | 'EMPTY'  | 'CS44992FB02'(!)        = ''              | ''                 | 'CS44992FB02'           |'R0402'| '(R0402-0201)'                 | '499K'    | '1%'    | '1/16W'  | 'IO'       | 'RES CHIP 499K 1/16W +1% (0402)DAL_AEC'            | 'CHIPR0402'    | ''          | ''            | '20160809'
 '681K'       | '1%'      | '1/16W'  | '0402LF'  | 'CHIP'   | 'CS46812FB04'(!)        = ''              | ''                 | 'CS46812FB04'           |'R0402'| '(R0402-0201)'                 | '681K'    | '1%'    | '1/16W'  | 'DISCRETE' | 'RES CHIP 681K 1/16W +-1%(0402)DAL_AEC'            | 'CHIPR0402'    | ''          | ''            | '20160809'
 '681K'       | '1%'      | '1/16W'  | '0402LF'  | 'EMPTY'  | 'CS46812FB04'(!)        = ''              | ''                 | 'CS46812FB04'           |'R0402'| '(R0402-0201)'                 | '681K'    | '1%'    | '1/16W'  | 'IO'       | 'RES CHIP 681K 1/16W +-1%(0402)DAL_AEC'            | 'CHIPR0402'    | ''          | ''            | '20160809'
 '1M'         | '1%'      | '1/16W'  | '0402LF'  | 'CHIP'   | 'CS51002FB07'(!)        = ''              | ''                 | 'CS51002FB07'           |'R0402'| '(R0402-0201)'                 | '1M'      | '1%'    | '1/16W'  | 'DISCRETE' | 'RES CHIP 1M 1/16W +-1%(0402)DAL_AEC'              | 'CHIPR0402'    | ''          | ''            | '20160809'
 '1M'         | '1%'      | '1/16W'  | '0402LF'  | 'EMPTY'  | 'CS51002FB07'(!)        = ''              | ''                 | 'CS51002FB07'           |'R0402'| '(R0402-0201)'                 | '1M'      | '1%'    | '1/16W'  | 'IO'       | 'RES CHIP 1M 1/16W +-1%(0402)DAL_AEC'              | 'CHIPR0402'    | ''          | ''            | '20160809'
 '1.69M'      | '1%'      | '1/16W'  | '0402LF'  | 'CHIP'   | 'CS51692FB02'(!)        = ''              | ''                 | 'CS51692FB02'           |'R0402'| '(R0402-0201)'                 | '1.69M'   | '1%'    | '1/16W'  | 'DISCRETE' | 'RES CHIP 1.69M,1/16W +-1%(0402)DAL_AEC'           | 'CHIPR0402'    | ''          | ''            | '20160809'
 '1.69M'      | '1%'      | '1/16W'  | '0402LF'  | 'EMPTY'  | 'CS51692FB02'(!)        = ''              | ''                 | 'CS51692FB02'           |'R0402'| '(R0402-0201)'                 | '1.69M'   | '1%'    | '1/16W'  | 'IO'       | 'RES CHIP 1.69M,1/16W +-1%(0402)DAL_AEC'           | 'CHIPR0402'    | ''          | ''            | '20160809'
 '10M'        | '1%'      | '1/16W'  | '0402LF'  | 'CHIP'   | 'CS61002FB01'(!)        = ''              | ''                 | 'CS61002FB01'           |'R0402'| '(R0402-0201)'                 | '10M'     | '1%'    | '1/16W'  | 'DISCRETE' | 'RES CHIP 10M 1/16W +-1%(0402)DAL_AEC'             | 'CHIPR0402'    | ''          | ''            | '20160809'
 '10M'        | '1%'      | '1/16W'  | '0402LF'  | 'EMPTY'  | 'CS61002FB01'(!)        = ''              | ''                 | 'CS61002FB01'           |'R0402'| '(R0402-0201)'                 | '10M'     | '1%'    | '1/16W'  | 'IO'       | 'RES CHIP 10M 1/16W +-1%(0402)DAL_AEC'             | 'CHIPR0402'    | ''          | ''            | '20160809'
 '100K'       | '0.1%'    | '1/8W'   | '0805LF'  | 'CHIP'   | 'CS41004BA00'(!)        = ''              | ''                 | 'CS41004BA00'           |'R0805'| '(SMR0805AW)'                  | '100K'    | '0.1%'  | '1/8W'   | 'DISCRETE' | 'RES CHIP 100K 1/8W +-0.1%(0805)AEC'               | 'CHIPR0805'    | ''          | ''            | '20160818'
 '100K'       | '0.1%'    | '1/8W'   | '0805LF'  | 'EMPTY'  | 'CS41004BA00'(!)        = ''              | ''                 | 'CS41004BA00'           |'R0805'| '(SMR0805AW)'                  | '100K'    | '0.1%'  | '1/8W'   | 'IO'       | 'RES CHIP 100K 1/8W +-0.1%(0805)AEC'               | 'CHIPR0805'    | ''          | ''            | '20160818'
 '165K'       | '1%'      | '1/16W'  | '0402LF'  | 'CHIP'   | 'CS41652FB14'(!)        = 'End of Design' | 'Comp-Approve'     | 'CS41652FB14'           |'R0402'| '(R0402-0201)'                 | '165K'    | '1%'    | '1/16W'  | 'DISCRETE' | 'RES CHIP 165K 1/16W +-1%(0402)'                   | 'CHIPR0402'    | ''          | ''            | '20140618'
 '165K'       | '1%'      | '1/16W'  | '0402LF'  | 'EMPTY'  | 'CS41652FB14'(!)        = 'End of Design' | 'Comp-Approve'     | 'CS41652FB14'           |'R0402'| '(R0402-0201)'                 | '165K'    | '1%'    | '1/16W'  | 'IO'       | 'RES CHIP 165K 1/16W +-1%(0402)'                   | 'CHIPR0402'    | ''          | ''            | '20140618'
 '0.0005'     | '1%'      | '1W'     | '2512LF'  | 'CHIP'   | 'CS00008FR04'(!)        = ''              | ''                 | 'CS00008FR04'           |'R2512A'| '(SMR2512AW)'                  | '0.0005'  | '1%'    | '1W'     | 'DISCRETE' | 'RES CHIP 0.0005 1W +-1%(2512)DAL_AEC'             | 'CHIPR2512'    | ''          | ''            | '20160822'
 '0.0005'     | '1%'      | '1W'     | '2512LF'  | 'EMPTY'  | 'CS00008FR04'(!)        = ''              | ''                 | 'CS00008FR04'           |'R2512A'| '(SMR2512AW)'                  | '0.0005'  | '1%'    | '1W'     | 'IO'       | 'RES CHIP 0.0005 1W +-1%(2512)DAL_AEC'             | 'CHIPR2512'    | ''          | ''            | '20160822'
 '0.001'      | '1%'      | '1W'     | '2512LF'  | 'CHIP'   | 'CS+0018FR06'(!)        = ''              | ''                 | 'CS+0018FR06'           |'R2512A'| '(SMR2512AW)'                  | '0.001'   | '1%'    | '1W'     | 'DISCRETE' | 'RES CHIP 0.001 1W +-1%(2512)DAL_AEC'              | 'CHIPR2512'    | ''          | ''            | '20160822'
 '0.001'      | '1%'      | '1W'     | '2512LF'  | 'EMPTY'  | 'CS+0018FR06'(!)        = ''              | ''                 | 'CS+0018FR06'           |'R2512A'| '(SMR2512AW)'                  | '0.001'   | '1%'    | '1W'     | 'IO'       | 'RES CHIP 0.001 1W +-1%(2512)DAL_AEC'              | 'CHIPR2512'    | ''          | ''            | '20160822'
 '0.001'      | '1%'      | '3W'     | '2512LF'  | 'CHIP'   | 'CS+001DFR04'(!)        = ''              | ''                 | 'CS+001DFR04'           |'R2512A'| '(SMR2512AW)'                  | '0.001'   | '1%'    | '3W'     | 'DISCRETE' | 'RES CHIP 0.001 3W +-1%(2512)DAL_AEC'              | 'CHIPR2512'    | ''          | ''            | '20160822'
 '0.001'      | '1%'      | '3W'     | '2512LF'  | 'EMPTY'  | 'CS+001DFR04'(!)        = ''              | ''                 | 'CS+001DFR04'           |'R2512A'| '(SMR2512AW)'                  | '0.001'   | '1%'    | '3W'     | 'IO'       | 'RES CHIP 0.001 3W +-1%(2512)DAL_AEC'              | 'CHIPR2512'    | ''          | ''            | '20160822'
 '1'          | '1%'      | '1W'     | '2512LF'  | 'CHIP'   | 'CS-1008FR01'(!)        = ''              | ''                 | 'CS-1008FR01'           |'R2512XN'| '(SMR2512AW)'                  | '1'       | '1%'    | '1W'     | 'DISCRETE' | 'RES CHIP 1 1W +-1%(2512) DAL_AEC'                 | 'CHIPR2512'    | ''          | ''            | '20160822'
 '1'          | '1%'      | '1W'     | '2512LF'  | 'EMPTY'  | 'CS-1008FR01'(!)        = ''              | ''                 | 'CS-1008FR01'           |'R2512XN'| '(SMR2512AW)'                  | '1'       | '1%'    | '1W'     | 'IO'       | 'RES CHIP 1 1W +-1%(2512) DAL_AEC'                 | 'CHIPR2512'    | ''          | ''            | '20160822'
 '1K'         | '1%'      | '1/16W'  | '0402LF'  | 'CHIP'   | 'SP_CS21002FB24_1'(!)   = 'End of Design' | 'Comp-Approve'     | 'CS21002FB24'           |'R0402_SMDC25_SM30'| '(R0402-0201)'                 | '1K'      | '1%'    | '1/16W'  | 'DISCRETE' | 'RES CHIP 1K 1/16W +-1% (0402)_FOR AMD CIRCLE PAD' | 'CHIPR0402'    | ''          | ''            | '20160824'
 '1K'         | '1%'      | '1/16W'  | '0402LF'  | 'EMPTY'  | 'SP_CS21002FB24_1'(!)   = 'End of Design' | 'Comp-Approve'     | 'CS21002FB24'           |'R0402_SMDC25_SM30'| '(R0402-0201)'                 | '1K'      | '1%'    | '1/16W'  | 'IO'       | 'RES CHIP 1K 1/16W +-1% (0402)_FOR AMD CIRCLE PAD' | 'CHIPR0402'    | ''          | ''            | '20160824'
 '59K'        | '1%'      | '1/16W'  | '0402LF'  | 'CHIP'   | 'CS35902FB11'(!)        = 'End of Design' | 'Comp-Approve'     | 'CS35902FB11'           |'R0402'| '(R0402-0201)'                 | '59K'     | '1%'    | '1/16W'  | 'DISCRETE' | 'RESISTOR CHIP 59K 1/16W +-1%(0402)EP'             | 'CHIPR0402'    | ''          | ''            | '20120710'
 '59K'        | '1%'      | '1/16W'  | '0402LF'  | 'EMPTY'  | 'CS35902FB11'(!)        = 'End of Design' | 'Comp-Approve'     | 'CS35902FB11'           |'R0402'| '(R0402-0201)'                 | '59K'     | '1%'    | '1/16W'  | 'IO'       | 'RESISTOR CHIP 59K 1/16W +-1%(0402)EP'             | 'CHIPR0402'    | ''          | ''            | '20120710'
 '2.2'        | '1%'      | '1/4W'   | '1206LF'  | 'CHIP'   | 'CS-2206F202'(!)        = ''              | ''                 | 'CS-2206F202'           |'R1206XC'| '(SMR1206AW)'                  | '2.2'     | '1%'    | '1/4W'   | 'DISCRETE' | 'RES CHIP 2.2 1/4W +-1%(1206)DAL_AEC'              | 'CHIPR1206'    | ''          | ''            | '20160920'
 '2.2'        | '1%'      | '1/4W'   | '1206LF'  | 'EMPTY'  | 'CS-2206F202'(!)        = ''              | ''                 | 'CS-2206F202'           |'R1206XC'| '(SMR1206AW)'                  | '2.2'     | '1%'    | '1/4W'   | 'IO'       | 'RES CHIP 2.2 1/4W +-1%(1206)DAL_AEC'              | 'CHIPR1206'    | ''          | ''            | '20160920'
 '221'        | '1%'      | '1/16W'  | '0402LF'  | 'CHIP'   | 'CS12212FB05'(!)        = ''              | ''                 | 'CS12212FB05'           |'R0402'| '(R0402-0201)'                 | '221'     | '1%'    | '1/16W'  | 'DISCRETE' | 'RES CHIP 221 1/16W +-1%(0402)DAL_AEC'             | 'CHIPR0402'    | ''          | ''            | '20160929'
 '221'        | '1%'      | '1/16W'  | '0402LF'  | 'EMPTY'  | 'CS12212FB05'(!)        = ''              | ''                 | 'CS12212FB05'           |'R0402'| '(R0402-0201)'                 | '221'     | '1%'    | '1/16W'  | 'IO'       | 'RES CHIP 221 1/16W +-1%(0402)DAL_AEC'             | 'CHIPR0402'    | ''          | ''            | '20160929'
 '0.001'      | '1%'      | '2W'     | '2512LF'  | 'CHIP'   | 'CS+001AFR03'(!)        = ''              | ''                 | 'CS+001AFR03'           |'R2512XG'| '(SMR2512AW)'                  | '0.001'   | '1%'    | '2W'     | 'DISCRETE' | 'RES CHIP 0.001 2W +-1%(2512)'                     | 'CHIPR2512'    | ''          | ''            | '20161007'
 '0.001'      | '1%'      | '2W'     | '2512LF'  | 'EMPTY'  | 'CS+001AFR03'(!)        = ''              | ''                 | 'CS+001AFR03'           |'R2512XG'| '(SMR2512AW)'                  | '0.001'   | '1%'    | '2W'     | 'IO'       | 'RES CHIP 0.001 2W +-1%(2512)'                     | 'CHIPR2512'    | ''          | ''            | '20161007'
 '309K'       | '1%'      | '1/8W'   | '0805LF'  | 'CHIP'   | 'CS43094FA00'(!)        = ''              | ''                 | 'CS43094FA00'           |'R0805'| '(SMR0805AW)'                  | '309K'    | '1%'    | '1/8W'   | 'DISCRETE' | 'RES CHIP 309K 1/8W +-1%(0805)'                    | 'CHIPR0805'    | ''          | ''            | '20161013'
 '309K'       | '1%'      | '1/8W'   | '0805LF'  | 'EMPTY'  | 'CS43094FA00'(!)        = ''              | ''                 | 'CS43094FA00'           |'R0805'| '(SMR0805AW)'                  | '309K'    | '1%'    | '1/8W'   | 'IO'       | 'RES CHIP 309K 1/8W +-1%(0805)'                    | 'CHIPR0805'    | ''          | ''            | '20161013'
 '374K'       | '1%'      | '1/8W'   | '0805LF'  | 'CHIP'   | 'CS43744FA00'(!)        = ''              | ''                 | 'CS43744FA00'           |'R0805'| '(SMR0805AW)'                  | '374K'    | '1%'    | '1/8W'   | 'DISCRETE' | 'RES CHIP 374K 1/8W +-1%(0805)'                    | 'CHIPR0805'    | ''          | ''            | '20161013'
 '374K'       | '1%'      | '1/8W'   | '0805LF'  | 'EMPTY'  | 'CS43744FA00'(!)        = ''              | ''                 | 'CS43744FA00'           |'R0805'| '(SMR0805AW)'                  | '374K'    | '1%'    | '1/8W'   | 'IO'       | 'RES CHIP 374K 1/8W +-1%(0805)'                    | 'CHIPR0805'    | ''          | ''            | '20161013'
 '1.5M'       | '1%'      | '1/16W'  | '0402LF'  | 'CHIP'   | 'CS51502FB02'(!)        = ''              | ''                 | 'CS51502FB02'           |'R0402'| '(R0402-0201)'                 | '1.5M'    | '1%'    | '1/16W'  | 'DISCRETE' | 'RES CHIP 1.5M 1/16W +-1%(0402)DAL_AEC'            | 'CHIPR0402'    | ''          | ''            | '20161017'
 '1.5M'       | '1%'      | '1/16W'  | '0402LF'  | 'EMPTY'  | 'CS51502FB02'(!)        = ''              | ''                 | 'CS51502FB02'           |'R0402'| '(R0402-0201)'                 | '1.5M'    | '1%'    | '1/16W'  | 'IO'       | 'RES CHIP 1.5M 1/16W +-1%(0402)DAL_AEC'            | 'CHIPR0402'    | ''          | ''            | '20161017'
 '562K'       | '1%'      | '1/16W'  | '0402LF'  | 'CHIP'   | 'CS45622FB02'(!)        = ''              | ''                 | 'CS45622FB02'           |'R0402'| '(R0402-0201)'                 | '562K'    | '1%'    | '1/16W'  | 'DISCRETE' | 'RES CHIP 562K 1/16W +-1%(0402)DAL_AEC'            | 'CHIPR0402'    | ''          | ''            | '20161017'
 '562K'       | '1%'      | '1/16W'  | '0402LF'  | 'EMPTY'  | 'CS45622FB02'(!)        = ''              | ''                 | 'CS45622FB02'           |'R0402'| '(R0402-0201)'                 | '562K'    | '1%'    | '1/16W'  | 'IO'       | 'RES CHIP 562K 1/16W +-1%(0402)DAL_AEC'            | 'CHIPR0402'    | ''          | ''            | '20161017'
 '267K'       | '1%'      | '1/16W'  | '0402LF'  | 'CHIP'   | 'CS42672FB02'(!)        = ''              | ''                 | 'CS42672FB02'           |'R0402'| '(R0402-0201)'                 | '267K'    | '1%'    | '1/16W'  | 'DISCRETE' | 'RES CHIP 267K 1/16W +-1%(0402)DAL_AEC'            | 'CHIPR0402'    | ''          | ''            | '20161017'
 '267K'       | '1%'      | '1/16W'  | '0402LF'  | 'EMPTY'  | 'CS42672FB02'(!)        = ''              | ''                 | 'CS42672FB02'           |'R0402'| '(R0402-0201)'                 | '267K'    | '1%'    | '1/16W'  | 'IO'       | 'RES CHIP 267K 1/16W +-1%(0402)DAL_AEC'            | 'CHIPR0402'    | ''          | ''            | '20161017'
 '29.4K'      | '1%'      | '1/16W'  | '0402LF'  | 'CHIP'   | 'CS32942FB04'(!)        = ''              | ''                 | 'CS32942FB04'           |'R0402'| '(R0402-0201)'                 | '29.4K'   | '1%'    | '1/16W'  | 'DISCRETE' | 'RES CHIP 29.4K 1/16W +-1%(0402)DAL_AEC'           | 'CHIPR0402'    | ''          | ''            | '20161017'
 '29.4K'      | '1%'      | '1/16W'  | '0402LF'  | 'EMPTY'  | 'CS32942FB04'(!)        = ''              | ''                 | 'CS32942FB04'           |'R0402'| '(R0402-0201)'                 | '29.4K'   | '1%'    | '1/16W'  | 'IO'       | 'RES CHIP 29.4K 1/16W +-1%(0402)DAL_AEC'           | 'CHIPR0402'    | ''          | ''            | '20161017'
 '3K'         | '1%'      | '1/16W'  | '0402LF'  | 'CHIP'   | 'CS23002FB04'(!)        = ''              | ''                 | 'CS23002FB04'           |'R0402'| '(R0402-0201)'                 | '3K'      | '1%'    | '1/16W'  | 'DISCRETE' | 'RES CHIP 3K 1/16W +-1%(0402)DAL_AEC'              | 'CHIPR0402'    | ''          | ''            | '20161017'
 '3K'         | '1%'      | '1/16W'  | '0402LF'  | 'EMPTY'  | 'CS23002FB04'(!)        = ''              | ''                 | 'CS23002FB04'           |'R0402'| '(R0402-0201)'                 | '3K'      | '1%'    | '1/16W'  | 'IO'       | 'RES CHIP 3K 1/16W +-1%(0402)DAL_AEC'              | 'CHIPR0402'    | ''          | ''            | '20161017'
 '442K'       | '1%'      | '1/16W'  | '0402LF'  | 'CHIP'   | 'CS44422FB00'(!)        = 'End of Design' | 'Comp-Approve'     | 'CS44422FB00'           |'R0402'| '(R0402-0201)'                 | '442K'    | '1%'    | '1/16W'  | 'DISCRETE' | 'RES CHIP 442K 1/16W +-1%(0402)'                   | 'CHIPR0402'    | ''          | ''            | '20161104'
 '442K'       | '1%'      | '1/16W'  | '0402LF'  | 'EMPTY'  | 'CS44422FB00'(!)        = 'End of Design' | 'Comp-Approve'     | 'CS44422FB00'           |'R0402'| '(R0402-0201)'                 | '442K'    | '1%'    | '1/16W'  | 'IO'       | 'RES CHIP 442K 1/16W +-1%(0402)'                   | 'CHIPR0402'    | ''          | ''            | '20161104'
 '182'        | '1%'      | '1/16W'  | '0402LF'  | 'CHIP'   | 'CS11822FB21'(!)        = 'End of Design' | 'Comp-Approve'     | 'CS11822FB21'           |'R0402'| '(R0402-0201)'                 | '182'     | '1%'    | '1/16W'  | 'DISCRETE' | 'RES CHIP 182 1/16W +-1%(0402)'                    | 'CHIPR0402'    | ''          | ''            | '20161110'
 '182'        | '1%'      | '1/16W'  | '0402LF'  | 'EMPTY'  | 'CS11822FB21'(!)        = 'End of Design' | 'Comp-Approve'     | 'CS11822FB21'           |'R0402'| '(R0402-0201)'                 | '182'     | '1%'    | '1/16W'  | 'IO'       | 'RES CHIP 182 1/16W +-1%(0402)'                    | 'CHIPR0402'    | ''          | ''            | '20161110'
 '332'        | '1%'      | '1/16W'  | '0402LF'  | 'CHIP'   | 'CS13322FB01'(!)        = ''              | ''                 | 'CS13322FB01'           |'R0402'| '(R0402-0201)'                 | '332'     | '1%'    | '1/16W'  | 'DISCRETE' | 'RES CHIP 332 1/16W +-1%(0402)'                    | 'CHIPR0402'    | ''          | ''            | '20161114'
 '332'        | '1%'      | '1/16W'  | '0402LF'  | 'EMPTY'  | 'CS13322FB01'(!)        = ''              | ''                 | 'CS13322FB01'           |'R0402'| '(R0402-0201)'                 | '332'     | '1%'    | '1/16W'  | 'IO'       | 'RES CHIP 332 1/16W +-1%(0402)'                    | 'CHIPR0402'    | ''          | ''            | '20161114'
 '0.001'      | '1%'      | '1W'     | '1206LF'  | 'CHIP'   | 'CS+0018F200'(!)        = ''              | ''                 | 'CS+0018F200'           |'R1206XA'| '(SMR1206AW)'                  | '0.001'   | '1%'    | '1W'     | 'DISCRETE' | 'RES CHIP 0.001 1W +-1%(1206)'                     | 'CHIPR1206'    | ''          | ''            | '20161118'
 '0.001'      | '1%'      | '1W'     | '1206LF'  | 'EMPTY'  | 'CS+0018F200'(!)        = ''              | ''                 | 'CS+0018F200'           |'R1206XA'| '(SMR1206AW)'                  | '0.001'   | '1%'    | '1W'     | 'IO'       | 'RES CHIP 0.001 1W +-1%(1206)'                     | 'CHIPR1206'    | ''          | ''            | '20161118'
 '75'         | '1%'      | '1/8W'   | '0402LF'  | 'CHIP'   | 'CS07504FB00'(!)        = ''              | ''                 | 'CS07504FB00'           |'R0402'| '(R0402-0201)'                 | '75'      | '1%'    | '1/8W'   | 'DISCRETE' | 'RES CHIP 75 1/8W +-1%(0402)'                      | 'CHIPR0402'    | ''          | ''            | '20161128'
 '75'         | '1%'      | '1/8W'   | '0402LF'  | 'EMPTY'  | 'CS07504FB00'(!)        = ''              | ''                 | 'CS07504FB00'           |'R0402'| '(R0402-0201)'                 | '75'      | '1%'    | '1/8W'   | 'IO'       | 'RES CHIP 75 1/8W +-1%(0402)'                      | 'CHIPR0402'    | ''          | ''            | '20161128'
 '56.2K'      | '0.1%'    | '1/16W'  | '0402LF'  | 'CHIP'   | 'CS35622BB00'(!)        = ''              | ''                 | 'CS35622BB00'           |'R0402'| '(R0402-0201)'                 | '56.2K'   | '0.1%'  | '1/16W'  | 'DISCRETE' | 'RES CHIP 56.2K 1/16W +-0.1%(0402)'                | 'CHIPR0402'    | ''          | ''            | '20161128'
 '56.2K'      | '0.1%'    | '1/16W'  | '0402LF'  | 'EMPTY'  | 'CS35622BB00'(!)        = ''              | ''                 | 'CS35622BB00'           |'R0402'| '(R0402-0201)'                 | '56.2K'   | '0.1%'  | '1/16W'  | 'IO'       | 'RES CHIP 56.2K 1/16W +-0.1%(0402)'                | 'CHIPR0402'    | ''          | ''            | '20161128'
 '1M'         | '1%'      | '1/4W'   | '1206LF'  | 'CHIP'   | 'CS51006F200'(!)        = ''              | ''                 | 'CS51006F200'           |'R1206XF'| '(SMR1206AW)'                  | '1M'      | '1%'    | '1/4W'   | 'DISCRETE' | 'RES CHIP 1M 1/4W +-1%(1206)'                      | 'CHIPR1206'    | ''          | ''            | '20170207'
 '1M'         | '1%'      | '1/4W'   | '1206LF'  | 'EMPTY'  | 'CS51006F200'(!)        = ''              | ''                 | 'CS51006F200'           |'R1206XF'| '(SMR1206AW)'                  | '1M'      | '1%'    | '1/4W'   | 'IO'       | 'RES CHIP 1M 1/4W +-1%(1206)'                      | 'CHIPR1206'    | ''          | ''            | '20170207'
 '0.01'       | '1%'      | '1/2W'   | '1206LF'  | 'CHIP'   | 'CS+0107F211'(!)        = ''              | ''                 | 'CS+0107F211'           |'R1206XG'| '(SMR1206AW)'                  | '0.01'    | '1%'    | '1/2W'   | 'DISCRETE' | 'RES CHIP 0.01 1/2W +-1%(1206)'                    | 'CHIPR1206'    | ''          | ''            | '20170213'
 '0.01'       | '1%'      | '1/2W'   | '1206LF'  | 'EMPTY'  | 'CS+0107F211'(!)        = ''              | ''                 | 'CS+0107F211'           |'R1206XG'| '(SMR1206AW)'                  | '0.01'    | '1%'    | '1/2W'   | 'IO'       | 'RES CHIP 0.01 1/2W +-1%(1206)'                    | 'CHIPR1206'    | ''          | ''            | '20170213'
 '0.01'       | '1%'      | '1W'     | '3720LF'  | 'CHIP'   | 'CS+0108FL09'(!)        = ''              | ''                 | 'CS+0108FL09'           |'R3720XA'| '(SMR3720AW)'                  | '0.01'    | '1%'    | '1W'     | 'DISCRETE' | 'RESISTOR CHIP 0.01 1W +-1%(3720)'                 | 'CHIP3720'     | ''          | ''            | '20170216'
 '0.01'       | '1%'      | '1W'     | '3720LF'  | 'EMPTY'  | 'CS+0108FL09'(!)        = ''              | ''                 | 'CS+0108FL09'           |'R3720XA'| '(SMR3720AW)'                  | '0.01'    | '1%'    | '1W'     | 'IO'       | 'RESISTOR CHIP 0.01 1W +-1%(3720)'                 | 'CHIP3720'     | ''          | ''            | '20170216'
 '160'        | '5%'      | '1/16W'  | '0402LF'  | 'CHIP'   | 'CS11602JB02'(!)        = 'End of Design' | 'Comp-Approve'     | 'CS11602JB02'           |'R0402'| '(R0402-0201)'                 | '160'     | '5%'    | '1/16W'  | 'DISCRETE' | 'RES CHIP 160 1/16W +-5%(0402)'                    | 'CHIPR0402'    | ''          | ''            | '20170216'
 '160'        | '5%'      | '1/16W'  | '0402LF'  | 'EMPTY'  | 'CS11602JB02'(!)        = 'End of Design' | 'Comp-Approve'     | 'CS11602JB02'           |'R0402'| '(R0402-0201)'                 | '160'     | '5%'    | '1/16W'  | 'IO'       | 'RES CHIP 160 1/16W +-5%(0402)'                    | 'CHIPR0402'    | ''          | ''            | '20170216'
 '16.5'       | '1%'      | '1/16W'  | '0402LF'  | 'CHIP'   | 'CS01652FB00'(!)        = 'End of Design' | 'Comp-Approve'     | 'CS01652FB00'           |'R0402'| '(R0402-0201)'                 | '16.5'    | '1%'    | '1/16W'  | 'DISCRETE' | 'RES CHIP 16.5 1/16W +-1%(0402)'                   | 'CHIPR0402'    | ''          | ''            | '20170412'
 '16.5'       | '1%'      | '1/16W'  | '0402LF'  | 'EMPTY'  | 'CS01652FB00'(!)        = 'End of Design' | 'Comp-Approve'     | 'CS01652FB00'           |'R0402'| '(R0402-0201)'                 | '16.5'    | '1%'    | '1/16W'  | 'IO'       | 'RES CHIP 16.5 1/16W +-1%(0402)'                   | 'CHIPR0402'    | ''          | ''            | '20170412'
 '10'         | '5%'      | '1/16W'  | '0402LF'  | 'CHIP'   | 'CS01002JB06'(!)        = ''              | ''                 | 'CS01002JB06'           |'R0402'| '(R0402-0201)'                 | '10'      | '5%'    | '1/16W'  | 'DISCRETE' | 'RES CHIP 10 1/16W +-5%(0402)'                     | 'CHIPR0402'    | ''          | ''            | '20170504'
 '10'         | '5%'      | '1/16W'  | '0402LF'  | 'EMPTY'  | 'CS01002JB06'(!)        = ''              | ''                 | 'CS01002JB06'           |'R0402'| '(R0402-0201)'                 | '10'      | '5%'    | '1/16W'  | 'IO'       | 'RES CHIP 10 1/16W +-5%(0402)'                     | 'CHIPR0402'    | ''          | ''            | '20170504'
 '6.34K'      | '1%'      | '1/16W'  | '0402LF'  | 'CHIP'   | 'CS26342FB04'(!)        = ''              | ''                 | 'CS26342FB04'           |'R0402'| '(R0402-0201)'                 | '6.34K'   | '1%'    | '1/16W'  | 'DISCRETE' | 'RES CHIP 6.34K 1/16W +-1%(0402)DAL_AEC'           | 'CHIPR0402'    | ''          | ''            | '20170524'
 '6.34K'      | '1%'      | '1/16W'  | '0402LF'  | 'EMPTY'  | 'CS26342FB04'(!)        = ''              | ''                 | 'CS26342FB04'           |'R0402'| '(R0402-0201)'                 | '6.34K'   | '1%'    | '1/16W'  | 'IO'       | 'RES CHIP 6.34K 1/16W +-1%(0402)DAL_AEC'           | 'CHIPR0402'    | ''          | ''            | '20170524'
 '49.9'       | '1%'      | '1/16W'  | '0402LF'  | 'CHIP'   | 'CS04992FB11'(!)        = ''              | ''                 | 'CS04992FB11'           |'R0402'| '(R0402-0201)'                 | '49.9'    | '1%'    | '1/16W'  | 'DISCRETE' | 'RES CHIP 49.9 1/16W +-1% (0402)DAL_AEC'           | 'CHIPR0402'    | ''          | ''            | '20170524'
 '49.9'       | '1%'      | '1/16W'  | '0402LF'  | 'EMPTY'  | 'CS04992FB11'(!)        = ''              | ''                 | 'CS04992FB11'           |'R0402'| '(R0402-0201)'                 | '49.9'    | '1%'    | '1/16W'  | 'IO'       | 'RES CHIP 49.9 1/16W +-1% (0402)DAL_AEC'           | 'CHIPR0402'    | ''          | ''            | '20170524'
 '0.020'      | '1%'      | '3W'     | '2512LF'  | 'CHIP'   | 'CS+020DFR00'(!)        = ''              | ''                 | 'CS+020DFR00'           |'R2512XL'| '(SMR2512AW)'                  | '0.020'   | '1%'    | '3W'     | 'DISCRETE' | 'RES CHIP 0.020 3W +-1%(2512)'                     | 'CHIPR2512'    | ''          | ''            | '20170524'
 '0.020'      | '1%'      | '3W'     | '2512LF'  | 'EMPTY'  | 'CS+020DFR00'(!)        = ''              | ''                 | 'CS+020DFR00'           |'R2512XL'| '(SMR2512AW)'                  | '0.020'   | '1%'    | '3W'     | 'IO'       | 'RES CHIP 0.020 3W +-1%(2512)'                     | 'CHIPR2512'    | ''          | ''            | '20170524'
 '15'         | '5%'      | '1W'     | '2512LF'  | 'CHIP'   | 'CS01508JR00'(!)        = ''              | ''                 | 'CS01508JR00'           |'R2512XK'| '(SMR2512AW)'                  | '15'      | '5%'    | '1W'     | 'DISCRETE' | 'RES CHIP 15,5%,1W(2512)'                          | 'CHIPR2512'    | ''          | ''            | '20170524'
 '15'         | '5%'      | '1W'     | '2512LF'  | 'EMPTY'  | 'CS01508JR00'(!)        = ''              | ''                 | 'CS01508JR00'           |'R2512XK'| '(SMR2512AW)'                  | '15'      | '5%'    | '1W'     | 'IO'       | 'RES CHIP 15,5%,1W(2512)'                          | 'CHIPR2512'    | ''          | ''            | '20170524'
 '1.3M'       | '1%'      | '1/10W'  | '0603LF'  | 'CHIP'   | 'CS51303F901'(!)        = ''              | ''                 | 'CS51303F901'           |'R0603'| '(SMR0603AW)'                  | '1.3M'    | '1%'    | '1/10W'  | 'DISCRETE' | 'RES CHIP 1.3M 1/10W +-1%(0603)'                   | 'CHIPR0603'    | ''          | ''            | '20170602'
 '1.3M'       | '1%'      | '1/10W'  | '0603LF'  | 'EMPTY'  | 'CS51303F901'(!)        = ''              | ''                 | 'CS51303F901'           |'R0603'| '(SMR0603AW)'                  | '1.3M'    | '1%'    | '1/10W'  | 'IO'       | 'RES CHIP 1.3M 1/10W +-1%(0603)'                   | 'CHIPR0603'    | ''          | ''            | '20170602'
 '0'          | ''        | '1/8W'   | '0805LF'  | 'CHIP'   | 'CS00004TA03'(!)        = ''              | ''                 | 'CS00004TA03'           |'R0805'| '(SMR0805AW)'                  | '0'       | ''      | '1/8W'   | 'DISCRETE' | 'RES CHIP 0 1/8W (0805) DAL_AEC'                   | 'CHIPR0805'    | ''          | ''            | '20170606'
 '0'          | ''        | '1/8W'   | '0805LF'  | 'EMPTY'  | 'CS00004TA03'(!)        = ''              | ''                 | 'CS00004TA03'           |'R0805'| '(SMR0805AW)'                  | '0'       | ''      | '1/8W'   | 'IO'       | 'RES CHIP 0 1/8W (0805) DAL_AEC'                   | 'CHIPR0805'    | ''          | ''            | '20170606'
 '1'          | '1%'      | '1/4W'   | '1206LF'  | 'CHIP'   | 'CS-1006F201'(!)        = ''              | ''                 | 'CS-1006F201'           |'R1206XC'| '(SMRR1206AW)'                 | '1'       | '1%'    | '1/4W'   | 'DISCRETE' | 'RES CHIP 1 1/4W +-1%(1206)DAL_AEC'                | 'CHIPR1206'    | ''          | ''            | '20170606'
 '1'          | '1%'      | '1/4W'   | '1206LF'  | 'EMPTY'  | 'CS-1006F201'(!)        = ''              | ''                 | 'CS-1006F201'           |'R1206XC'| '(SMRR1206AW)'                 | '1'       | '1%'    | '1/4W'   | 'IO'       | 'RES CHIP 1 1/4W +-1%(1206)DAL_AEC'                | 'CHIPR1206'    | ''          | ''            | '20170606'
 '1K'         | '1%'      | '1/8W'   | '0805LF'  | 'CHIP'   | 'CS21004FA03'(!)        = ''              | ''                 | 'CS21004FA03'           |'R0805'| '(SMR0805AW)'                  | '1K'      | '1%'    | '1/8W'   | 'DISCRETE' | 'RES CHIP 1K 1/8W +-1%(0805)DAL_AEC'               | 'CHIPR0805'    | ''          | ''            | '20170606'
 '1K'         | '1%'      | '1/8W'   | '0805LF'  | 'EMPTY'  | 'CS21004FA03'(!)        = ''              | ''                 | 'CS21004FA03'           |'R0805'| '(SMR0805AW)'                  | '1K'      | '1%'    | '1/8W'   | 'IO'       | 'RES CHIP 1K 1/8W +-1%(0805)DAL_AEC'               | 'CHIPR0805'    | ''          | ''            | '20170606'
 '2.2'        | '1%'      | '1/8W'   | '0805LF'  | 'CHIP'   | 'CS-2204FA04'(!)        = ''              | ''                 | 'CS-2204FA04'           |'R0805'| '(SMR0805AW)'                  | '2.2'     | '1%'    | '1/8W'   | 'DISCRETE' | 'RES CHIP 2.2 1/8W +-1%(0805)DAL_AEC'              | 'CHIPR0805'    | ''          | ''            | '20170606'
 '2.2'        | '1%'      | '1/8W'   | '0805LF'  | 'EMPTY'  | 'CS-2204FA04'(!)        = ''              | ''                 | 'CS-2204FA04'           |'R0805'| '(SMR0805AW)'                  | '2.2'     | '1%'    | '1/8W'   | 'IO'       | 'RES CHIP 2.2 1/8W +-1%(0805)DAL_AEC'              | 'CHIPR0805'    | ''          | ''            | '20170606'
 '0.0005'     | '1%'      | '3W'     | '2512LF'  | 'CHIP'   | 'CS0000DFR05'(!)        = ''              | ''                 | 'CS0000DFR05'           |'R2512XO'| '(SMR2512AW)'                  | '0.0005'  | '1%'    | '3W'     | 'DISCRETE' | 'RES CHIP 0.0005 3W +-1%(2512)CYN'                 | 'CHIPR2512'    | ''          | ''            | '20170607'
 '0.0005'     | '1%'      | '3W'     | '2512LF'  | 'EMPTY'  | 'CS0000DFR05'(!)        = ''              | ''                 | 'CS0000DFR05'           |'R2512XO'| '(SMR2512AW)'                  | '0.0005'  | '1%'    | '3W'     | 'IO'       | 'RES CHIP 0.0005 3W +-1%(2512)CYN'                 | 'CHIPR2512'    | ''          | ''            | '20170607'
 '7.5K'       | '1%'      | '1/8W'   | '0805LF'  | 'CHIP'   | 'CS27504FA00'(!)        = ''              | ''                 | 'CS27504FA00'           |'R0805'| '(SMR0805AW)'                  | '7.5K'    | '1%'    | '1/8W'   | 'DISCRETE' | 'RES CHIP 7.5K 1/8W +-1% (0805)'                   | 'CHIPR0805'    | ''          | ''            | '20170706'
 '7.5K'       | '1%'      | '1/8W'   | '0805LF'  | 'EMPTY'  | 'CS27504FA00'(!)        = ''              | ''                 | 'CS27504FA00'           |'R0805'| '(SMR0805AW)'                  | '7.5K'    | '1%'    | '1/8W'   | 'IO'       | 'RES CHIP 7.5K 1/8W +-1% (0805)'                   | 'CHIPR0805'    | ''          | ''            | '20170706'
 '1'          | '5%'      | '1/8W'   | '0805LF'  | 'CHIP'   | 'CS-1004JA37'(!)        = ''              | ''                 | 'CS-1004JA37'           |'R0805'| '(SMR0805AW)'                  | '1'       | '5%'    | '1/8W'   | 'DISCRETE' | 'RES CHIP 1 1/8W+-5%(0805)'                        | 'CHIPR0805'    | ''          | ''            | '20170711'
 '1'          | '5%'      | '1/8W'   | '0805LF'  | 'EMPTY'  | 'CS-1004JA37'(!)        = ''              | ''                 | 'CS-1004JA37'           |'R0805'| '(SMR0805AW)'                  | '1'       | '5%'    | '1/8W'   | 'IO'       | 'RES CHIP 1 1/8W+-5%(0805)'                        | 'CHIPR0805'    | ''          | ''            | '20170711'
 '3.9'        | '5%'      | '1/4W'   | '1206LF'  | 'CHIP'   | 'CS-3906J209'(!)        = ''              | ''                 | 'CS-3906J209'           |'R1206XI'| '(SMRR1206AW)'                 | '3.9'     | '5%'    | '1/4W'   | 'DISCRETE' | 'RES CHIP 3.9 1/4W +-5%(1206)'                     | 'CHIPR1206'    | ''          | ''            | '20170711'
 '3.9'        | '5%'      | '1/4W'   | '1206LF'  | 'EMPTY'  | 'CS-3906J209'(!)        = ''              | ''                 | 'CS-3906J209'           |'R1206XI'| '(SMRR1206AW)'                 | '3.9'     | '5%'    | '1/4W'   | 'IO'       | 'RES CHIP 3.9 1/4W +-5%(1206)'                     | 'CHIPR1206'    | ''          | ''            | '20170711'
 '665'        | '1%'      | '1/8W'   | '0805LF'  | 'CHIP'   | 'CS16654FA08'(!)        = ''              | ''                 | 'CS16654FA08'           |'R0805'| '(SMR0805AW)'                  | '665'     | '1%'    | '1/8W'   | 'DISCRETE' | 'RES CHIP 665 1/8W +-1%(0805)'                     | 'CHIPR0805'    | ''          | ''            | '20170711'
 '665'        | '1%'      | '1/8W'   | '0805LF'  | 'EMPTY'  | 'CS16654FA08'(!)        = ''              | ''                 | 'CS16654FA08'           |'R0805'| '(SMR0805AW)'                  | '665'     | '1%'    | '1/8W'   | 'IO'       | 'RES CHIP 665 1/8W +-1%(0805)'                     | 'CHIPR0805'    | ''          | ''            | '20170711'
 '1'          | '1%'      | '1/16W'  | '0402LF'  | 'CHIP'   | 'CS-1002FB11'(!)        = ''              | ''                 | 'CS-1002FB11'           |'R0402'| '(R0402-0201)'                 | '1'       | '1%'    | '1/16W'  | 'DISCRETE' | 'RES CHIP 1 1/16W +-1%(0402)DAL_AEC'               | 'CHIPR0402'    | ''          | ''            | '20170711'
 '1'          | '1%'      | '1/16W'  | '0402LF'  | 'EMPTY'  | 'CS-1002FB11'(!)        = ''              | ''                 | 'CS-1002FB11'           |'R0402'| '(R0402-0201)'                 | '1'       | '1%'    | '1/16W'  | 'IO'       | 'RES CHIP 1 1/16W +-1%(0402)DAL_AEC'               | 'CHIPR0402'    | ''          | ''            | '20170711'
 '1K'         | '0.1%'    | '1/16W'  | '0402LF'  | 'CHIP'   | 'CS21002BB07'(!)        = ''              | ''                 | 'CS21002BB07'           |'R0402'| '(R0402-0201)'                 | '1K'      | '0.1%'  | '1/16W'  | 'DISCRETE' | 'RES CHIP 1K 1/16W +-0.1%(0402)DAL_AEC'            | 'CHIPR0402'    | ''          | ''            | '20170711'
 '1K'         | '0.1%'    | '1/16W'  | '0402LF'  | 'EMPTY'  | 'CS21002BB07'(!)        = ''              | ''                 | 'CS21002BB07'           |'R0402'| '(R0402-0201)'                 | '1K'      | '0.1%'  | '1/16W'  | 'IO'       | 'RES CHIP 1K 1/16W +-0.1%(0402)DAL_AEC'            | 'CHIPR0402'    | ''          | ''            | '20170711'
 '4.7K'       | '1%'      | '1/16W'  | '0402LF'  | 'CHIP'   | 'CS24702FB07'(!)        = ''              | ''                 | 'CS24702FB07'           |'R0402'| '(R0402-0201)'                 | '4.7K'    | '1%'    | '1/16W'  | 'DISCRETE' | 'RES CHIP 4.7K 1/16W +-1%(0402)DAL_AEC'            | 'CHIPR0402'    | ''          | ''            | '20170712'
 '4.7K'       | '1%'      | '1/16W'  | '0402LF'  | 'EMPTY'  | 'CS24702FB07'(!)        = ''              | ''                 | 'CS24702FB07'           |'R0402'| '(R0402-0201)'                 | '4.7K'    | '1%'    | '1/16W'  | 'IO'       | 'RES CHIP 4.7K 1/16W +-1%(0402)DAL_AEC'            | 'CHIPR0402'    | ''          | ''            | '20170712'
 '20K'        | '0.1%'    | '1/16W'  | '0402LF'  | 'CHIP'   | 'CS32002BB04'(!)        = ''              | ''                 | 'CS32002BB04'           |'R0402'| '(R0402-0201)'                 | '20K'     | '0.1%'  | '1/16W'  | 'DISCRETE' | 'RES CHIP 20K 1/16W +-0.1%(0402)DAL_AEC'           | 'CHIPR0402'    | ''          | ''            | '20170712'
 '20K'        | '0.1%'    | '1/16W'  | '0402LF'  | 'EMPTY'  | 'CS32002BB04'(!)        = ''              | ''                 | 'CS32002BB04'           |'R0402'| '(R0402-0201)'                 | '20K'     | '0.1%'  | '1/16W'  | 'IO'       | 'RES CHIP 20K 1/16W +-0.1%(0402)DAL_AEC'           | 'CHIPR0402'    | ''          | ''            | '20170712'
 '26.7K'      | '0.1%'    | '1/16W'  | '0402LF'  | 'CHIP'   | 'CS32672BB02'(!)        = ''              | ''                 | 'CS32672BB02'           |'R0402'| '(R0402-0201)'                 | '26.7K'   | '0.1%'  | '1/16W'  | 'DISCRETE' | 'RES CHIP 26.7K 1/16W +-0.1%(0402)DAL_AEC'         | 'CHIPR0402'    | ''          | ''            | '20170712'
 '26.7K'      | '0.1%'    | '1/16W'  | '0402LF'  | 'EMPTY'  | 'CS32672BB02'(!)        = ''              | ''                 | 'CS32672BB02'           |'R0402'| '(R0402-0201)'                 | '26.7K'   | '0.1%'  | '1/16W'  | 'IO'       | 'RES CHIP 26.7K 1/16W +-0.1%(0402)DAL_AEC'         | 'CHIPR0402'    | ''          | ''            | '20170712'
 '118K'       | '0.1%'    | '1/16W'  | '0402LF'  | 'CHIP'   | 'CS41182BB01'(!)        = ''              | ''                 | 'CS41182BB01'           |'R0402'| '(R0402-0201)'                 | '118K'    | '0.1%'  | '1/16W'  | 'DISCRETE' | 'RES CHIP 118K 1/16W +-0.1% (0402)DAL_AEC'         | 'CHIPR0402'    | ''          | ''            | '20170712'
 '118K'       | '0.1%'    | '1/16W'  | '0402LF'  | 'EMPTY'  | 'CS41182BB01'(!)        = ''              | ''                 | 'CS41182BB01'           |'R0402'| '(R0402-0201)'                 | '118K'    | '0.1%'  | '1/16W'  | 'IO'       | 'RES CHIP 118K 1/16W +-0.1% (0402)DAL_AEC'         | 'CHIPR0402'    | ''          | ''            | '20170712'
 '133K'       | '0.1%'    | '1/16W'  | '0402LF'  | 'CHIP'   | 'CS41332BB01'(!)        = ''              | ''                 | 'CS41332BB01'           |'R0402'| '(R0402-0201)'                 | '133K'    | '0.1%'  | '1/16W'  | 'DISCRETE' | 'RES CHIP 133K 1/16W +-0.1%(0402)DAL_AEC'          | 'CHIPR0402'    | ''          | ''            | '20170712'
 '133K'       | '0.1%'    | '1/16W'  | '0402LF'  | 'EMPTY'  | 'CS41332BB01'(!)        = ''              | ''                 | 'CS41332BB01'           |'R0402'| '(R0402-0201)'                 | '133K'    | '0.1%'  | '1/16W'  | 'IO'       | 'RES CHIP 133K 1/16W +-0.1%(0402)DAL_AEC'          | 'CHIPR0402'    | ''          | ''            | '20170712'
 '147K'       | '0.1%'    | '1/16W'  | '0402LF'  | 'CHIP'   | 'CS41472BB01'(!)        = 'End of Design' | 'Comp-Release Qty' | 'CS41472BB01'           |'R0402'| '(R0402-0201)'                 | '147K'    | '0.1%'  | '1/16W'  | 'DISCRETE' | 'RES CHIP 147K 1/16W +-0.1% (0402)DAL_AEC'         | 'CHIPR0402'    | ''          | ''            | '20170712'
 '147K'       | '0.1%'    | '1/16W'  | '0402LF'  | 'EMPTY'  | 'CS41472BB01'(!)        = 'End of Design' | 'Comp-Release Qty' | 'CS41472BB01'           |'R0402'| '(R0402-0201)'                 | '147K'    | '0.1%'  | '1/16W'  | 'IO'       | 'RES CHIP 147K 1/16W +-0.1% (0402)DAL_AEC'         | 'CHIPR0402'    | ''          | ''            | '20170712'
 '511K'       | '1%'      | '1/16W'  | '0402LF'  | 'CHIP'   | 'CS45112FB04'(!)        = ''              | ''                 | 'CS45112FB04'           |'R0402'| '(R0402-0201)'                 | '511K'    | '1%'    | '1/16W'  | 'DISCRETE' | 'RES CHIP 511K 1/16W +-1%(0402)DAL_AEC'            | 'CHIPR0402'    | ''          | ''            | '20170712'
 '511K'       | '1%'      | '1/16W'  | '0402LF'  | 'EMPTY'  | 'CS45112FB04'(!)        = ''              | ''                 | 'CS45112FB04'           |'R0402'| '(R0402-0201)'                 | '511K'    | '1%'    | '1/16W'  | 'IO'       | 'RES CHIP 511K 1/16W +-1%(0402)DAL_AEC'            | 'CHIPR0402'    | ''          | ''            | '20170712'
 '26.1K'      | '1%'      | '1/16W'  | '0402LF'  | 'CHIP'   | 'CS32612FB03'(!)        = ''              | ''                 | 'CS32612FB03'           |'R0402'| '(R0402-0201)'                 | '26.1K'   | '1%'    | '1/16W'  | 'DISCRETE' | 'RES CHIP 26.1K 1/16W +-1%(0402)DAL_AEC'           | 'CHIPR0402'    | ''          | ''            | '20170713'
 '26.1K'      | '1%'      | '1/16W'  | '0402LF'  | 'EMPTY'  | 'CS32612FB03'(!)        = ''              | ''                 | 'CS32612FB03'           |'R0402'| '(R0402-0201)'                 | '26.1K'   | '1%'    | '1/16W'  | 'IO'       | 'RES CHIP 26.1K 1/16W +-1%(0402)DAL_AEC'           | 'CHIPR0402'    | ''          | ''            | '20170713'
 '3.74K'      | '1%'      | '1/16W'  | '0402LF'  | 'CHIP'   | 'CS23742FB04'(!)        = ''              | ''                 | 'CS23742FB04'           |'R0402'| '(R0402-0201)'                 | '3.74K'   | '1%'    | '1/16W'  | 'DISCRETE' | 'RES CHIP 3.74K 1/16W +-1%(0402)DAL_AEC'           | 'CHIPR0402'    | ''          | ''            | '20170713'
 '3.74K'      | '1%'      | '1/16W'  | '0402LF'  | 'EMPTY'  | 'CS23742FB04'(!)        = ''              | ''                 | 'CS23742FB04'           |'R0402'| '(R0402-0201)'                 | '3.74K'   | '1%'    | '1/16W'  | 'IO'       | 'RES CHIP 3.74K 1/16W +-1%(0402)DAL_AEC'           | 'CHIPR0402'    | ''          | ''            | '20170713'
 '0'          | ''        | '1/10W'  | '0603LF'  | 'CHIP'   | 'CS00003T901'(!)        = ''              | ''                 | 'CS00003T901'           |'R0603'| '(SMR0603AW)'                  | '0'       | ''      | '1/10W'  | 'DISCRETE' | 'RES CHIP 0 1/10W (0603)DAL_AEC'                   | 'CHIPR0603'    | ''          | ''            | '20170714'
 '0'          | ''        | '1/10W'  | '0603LF'  | 'EMPTY'  | 'CS00003T901'(!)        = ''              | ''                 | 'CS00003T901'           |'R0603'| '(SMR0603AW)'                  | '0'       | ''      | '1/10W'  | 'IO'       | 'RES CHIP 0 1/10W (0603)DAL_AEC'                   | 'CHIPR0603'    | ''          | ''            | '20170714'
 '1'          | '1%'      | '1/10W'  | '0603LF'  | 'CHIP'   | 'CS-1003F902'(!)        = ''              | ''                 | 'CS-1003F902'           |'R0603'| '(SMR0603AW)'                  | '1'       | '1%'    | '1/10W'  | 'DISCRETE' | 'RES CHIP 1 1/10W +-1%(0603)DAL_AEC'               | 'CHIPR0603'    | ''          | ''            | '20170717'
 '1'          | '1%'      | '1/10W'  | '0603LF'  | 'EMPTY'  | 'CS-1003F902'(!)        = ''              | ''                 | 'CS-1003F902'           |'R0603'| '(SMR0603AW)'                  | '1'       | '1%'    | '1/10W'  | 'IO'       | 'RES CHIP 1 1/10W +-1%(0603)DAL_AEC'               | 'CHIPR0603'    | ''          | ''            | '20170717'
 '330'        | '1%'      | '1/10W'  | '0603LF'  | 'CHIP'   | 'CS13303F901'(!)        = ''              | ''                 | 'CS13303F901'           |'R0603'| '(SMR0603AW)'                  | '330'     | '1%'    | '1/10W'  | 'DISCRETE' | 'RES CHIP 330 1/10W +-1%(0603)DAL_AEC'             | 'CHIPR0603'    | ''          | ''            | '20170717'
 '330'        | '1%'      | '1/10W'  | '0603LF'  | 'EMPTY'  | 'CS13303F901'(!)        = ''              | ''                 | 'CS13303F901'           |'R0603'| '(SMR0603AW)'                  | '330'     | '1%'    | '1/10W'  | 'IO'       | 'RES CHIP 330 1/10W +-1%(0603)DAL_AEC'             | 'CHIPR0603'    | ''          | ''            | '20170717'
 '2.2'        | '1%'      | '1/10W'  | '0603LF'  | 'CHIP'   | 'CS-2203F904'(!)        = ''              | ''                 | 'CS-2203F904'           |'R0603'| '(SMR0603AW)'                  | '2.2'     | '1%'    | '1/10W'  | 'DISCRETE' | 'RES CHIP 2.2 1/10W +-1%(0603)DAL_AEC'             | 'CHIPR0603'    | ''          | ''            | '20170717'
 '2.2'        | '1%'      | '1/10W'  | '0603LF'  | 'EMPTY'  | 'CS-2203F904'(!)        = ''              | ''                 | 'CS-2203F904'           |'R0603'| '(SMR0603AW)'                  | '2.2'     | '1%'    | '1/10W'  | 'IO'       | 'RES CHIP 2.2 1/10W +-1%(0603)DAL_AEC'             | 'CHIPR0603'    | ''          | ''            | '20170717'
 '4.7K'       | '1%'      | '1/10W'  | '0603LF'  | 'CHIP'   | 'CS24703F902'(!)        = ''              | ''                 | 'CS24703F902'           |'R0603'| '(SMR0603AW)'                  | '4.7K'    | '1%'    | '1/10W'  | 'DISCRETE' | 'RES CHIP 4.7K 1/10W +-1%(0603)DAL_AEC'            | 'CHIPR0603'    | ''          | ''            | '20170717'
 '4.7K'       | '1%'      | '1/10W'  | '0603LF'  | 'EMPTY'  | 'CS24703F902'(!)        = ''              | ''                 | 'CS24703F902'           |'R0603'| '(SMR0603AW)'                  | '4.7K'    | '1%'    | '1/10W'  | 'IO'       | 'RES CHIP 4.7K 1/10W +-1%(0603)DAL_AEC'            | 'CHIPR0603'    | ''          | ''            | '20170717'
 '10K'        | '1%'      | '1/10W'  | '0603LF'  | 'CHIP'   | 'CS31003F907'(!)        = ''              | ''                 | 'CS31003F907'           |'R0603'| '(SMR0603AW)'                  | '10K'     | '1%'    | '1/10W'  | 'DISCRETE' | 'RES CHIP 10K 1/10W+1%(0603)DAL_AEC'               | 'CHIPR0603'    | ''          | ''            | '20170717'
 '10K'        | '1%'      | '1/10W'  | '0603LF'  | 'EMPTY'  | 'CS31003F907'(!)        = ''              | ''                 | 'CS31003F907'           |'R0603'| '(SMR0603AW)'                  | '10K'     | '1%'    | '1/10W'  | 'IO'       | 'RES CHIP 10K 1/10W+1%(0603)DAL_AEC'               | 'CHIPR0603'    | ''          | ''            | '20170717'
 '100K'       | '1%'      | '1/10W'  | '0603LF'  | 'CHIP'   | 'CS41003F905'(!)        = ''              | ''                 | 'CS41003F905'           |'R0603'| '(SMR0603AW)'                  | '100K'    | '1%'    | '1/10W'  | 'DISCRETE' | 'RES CHIP 100K 1/10W +-1%(0603) DAL_AEC'           | 'CHIPR0603'    | ''          | ''            | '20170717'
 '100K'       | '1%'      | '1/10W'  | '0603LF'  | 'EMPTY'  | 'CS41003F905'(!)        = ''              | ''                 | 'CS41003F905'           |'R0603'| '(SMR0603AW)'                  | '100K'    | '1%'    | '1/10W'  | 'IO'       | 'RES CHIP 100K 1/10W +-1%(0603) DAL_AEC'           | 'CHIPR0603'    | ''          | ''            | '20170717'
 '200K'       | '0.1%'    | '1/10W'  | '0603LF'  | 'CHIP'   | 'CS42003B904'(!)        = 'Non-Preferred' | 'End of Life'      | 'CS42003B904'           |'R0603_EOL'| '(SMR0603AW)'                  | '200K'    | '0.1%'  | '1/10W'  | 'DISCRETE' | 'RES CHIP 200K 1/10W +-0.1%(0603)DAL_AEC'          | 'CHIPR0603'    | ''          | ''            | '20170717'
 '200K'       | '0.1%'    | '1/10W'  | '0603LF'  | 'EMPTY'  | 'CS42003B904'(!)        = 'Non-Preferred' | 'End of Life'      | 'CS42003B904'           |'R0603_EOL'| '(SMR0603AW)'                  | '200K'    | '0.1%'  | '1/10W'  | 'IO'       | 'RES CHIP 200K 1/10W +-0.1%(0603)DAL_AEC'          | 'CHIPR0603'    | ''          | ''            | '20170717'
 '10M'        | '1%'      | '1/10W'  | '0603LF'  | 'CHIP'   | 'CS61003F903'(!)        = ''              | ''                 | 'CS61003F903'           |'R0603'| '(SMR0603AW)'                  | '10M'     | '1%'    | '1/10W'  | 'DISCRETE' | 'RES CHIP 10M 1/10W +-1%(0603)DAL_AEC'             | 'CHIPR0603'    | ''          | ''            | '20170717'
 '10M'        | '1%'      | '1/10W'  | '0603LF'  | 'EMPTY'  | 'CS61003F903'(!)        = ''              | ''                 | 'CS61003F903'           |'R0603'| '(SMR0603AW)'                  | '10M'     | '1%'    | '1/10W'  | 'IO'       | 'RES CHIP 10M 1/10W +-1%(0603)DAL_AEC'             | 'CHIPR0603'    | ''          | ''            | '20170717'
 '2K'         | '1%'      | '1/20W'  | '0201LF'  | 'CHIP'   | 'CS22001FE15'(!)        = ''              | ''                 | 'CS22001FE15'           |'R0201'| '(SMR0201AW)'                  | '2K'      | '1%'    | '1/20W'  | 'DISCRETE' | 'RES CHIP 2K(1/20W,+-1%,0201)'                     | 'CHIPR0201'    | ''          | ''            | '20170718'
 '2K'         | '1%'      | '1/20W'  | '0201LF'  | 'EMPTY'  | 'CS22001FE15'(!)        = ''              | ''                 | 'CS22001FE15'           |'R0201'| '(SMR0201AW)'                  | '2K'      | '1%'    | '1/20W'  | 'IO'       | 'RES CHIP 2K(1/20W,+-1%,0201)'                     | 'CHIPR0201'    | ''          | ''            | '20170718'
 '412K'       | '1%'      | '1/16W'  | '0402LF'  | 'CHIP'   | 'CS44122FB00'(!)        = 'End of Design' | 'Comp-Approve'     | 'CS44122FB00'           |'R0402'| '(R0402-0201)'                 | '412K'    | '1%'    | '1/16W'  | 'DISCRETE' | 'RES CHIP 412K 1/16W +-1%(0402)'                   | 'CHIPR0402'    | ''          | ''            | '20170718'
 '412K'       | '1%'      | '1/16W'  | '0402LF'  | 'EMPTY'  | 'CS44122FB00'(!)        = 'End of Design' | 'Comp-Approve'     | 'CS44122FB00'           |'R0402'| '(R0402-0201)'                 | '412K'    | '1%'    | '1/16W'  | 'IO'       | 'RES CHIP 412K 1/16W +-1%(0402)'                   | 'CHIPR0402'    | ''          | ''            | '20170718'
 '1'          | '1%'      | '1/2W'   | '1206LF'  | 'CHIP'   | 'CS-1007F200'(!)        = ''              | ''                 | 'CS-1007F200'           |'R1206XJ'| '(SMRR1206AW)'                 | '1'       | '1%'    | '1/2W'   | 'DISCRETE' | 'RES CHIP 1 1/2W +-1%(1206)'                       | 'CHIPR1206'    | ''          | ''            | '20170725'
 '1'          | '1%'      | '1/2W'   | '1206LF'  | 'EMPTY'  | 'CS-1007F200'(!)        = ''              | ''                 | 'CS-1007F200'           |'R1206XJ'| '(SMRR1206AW)'                 | '1'       | '1%'    | '1/2W'   | 'IO'       | 'RES CHIP 1 1/2W +-1%(1206)'                       | 'CHIPR1206'    | ''          | ''            | '20170725'
 '10K'        | '5%'      | '1W'     | '2512LF'  | 'CHIP'   | 'CS31008JR00'(!)        = ''              | ''                 | 'CS31008JR00'           |'R2512XP'| '(SMR2512AW)'                  | '10K'     | '5%'    | '1W'     | 'DISCRETE' | 'RES CHIP 10K 1W +-5%(2512)'                       | 'CHIPR2512'    | ''          | ''            | '20170804'
 '10K'        | '5%'      | '1W'     | '2512LF'  | 'EMPTY'  | 'CS31008JR00'(!)        = ''              | ''                 | 'CS31008JR00'           |'R2512XP'| '(SMR2512AW)'                  | '10K'     | '5%'    | '1W'     | 'IO'       | 'RES CHIP 10K 1W +-5%(2512)'                       | 'CHIPR2512'    | ''          | ''            | '20170804'
 '2.2K'       | '5%'      | '1/8W'   | '0805LF'  | 'CHIP'   | 'CS22204JA38'(!)        = ''              | ''                 | 'CS22204JA38'           |'R0805'| '(SMR0805AW)'                  | '2.2K'    | '5%'    | '1/8W'   | 'DISCRETE' | 'RES CHIP 2.2K 1/8W +-5%(0805)'                    | 'CHIPR0805'    | ''          | ''            | '20170809'
 '2.2K'       | '5%'      | '1/8W'   | '0805LF'  | 'EMPTY'  | 'CS22204JA38'(!)        = ''              | ''                 | 'CS22204JA38'           |'R0805'| '(SMR0805AW)'                  | '2.2K'    | '5%'    | '1/8W'   | 'IO'       | 'RES CHIP 2.2K 1/8W +-5%(0805)'                    | 'CHIPR0805'    | ''          | ''            | '20170809'
 '13.3K'      | '1%'      | '1/10W'  | '0603LF'  | 'CHIP'   | 'CS31333F919'(!)        = ''              | ''                 | 'CS31333F919'           |'R0603'| '(SMR0603AW)'                  | '13.3K'   | '1%'    | '1/10W'  | 'DISCRETE' | 'RES CHIP 13.3K 1/10W +-1%(0603)'                  | 'CHIPR0603'    | ''          | ''            | '20170809'
 '13.3K'      | '1%'      | '1/10W'  | '0603LF'  | 'EMPTY'  | 'CS31333F919'(!)        = ''              | ''                 | 'CS31333F919'           |'R0603'| '(SMR0603AW)'                  | '13.3K'   | '1%'    | '1/10W'  | 'IO'       | 'RES CHIP 13.3K 1/10W +-1%(0603)'                  | 'CHIPR0603'    | ''          | ''            | '20170809'
 '0.47'       | '1%'      | '1/8W'   | '0603LF ' | 'CHIP'   | 'CS+4704F901'(!)        = ''              | ''                 | 'CS+4704F901'           |'R0603'| '(SMR0603AW)'                  | '0.47'    | '1%'    | '1/8W'   | 'DISCRETE' | 'RESISTOR CHIP 0.47 1/8W+-1%(0603) EP'             | 'CHIPR0603'    | ''          | ''            | '20170811'
 '0.47'       | '1%'      | '1/8W'   | '0603LF ' | 'EMPTY'  | 'CS+4704F901'(!)        = ''              | ''                 | 'CS+4704F901'           |'R0603'| '(SMR0603AW)'                  | '0.47'    | '1%'    | '1/8W'   | 'IO'       | 'RESISTOR CHIP 0.47 1/8W+-1%(0603) EP'             | 'CHIPR0603'    | ''          | ''            | '20170811'
 '127K'       | '1%'      | '1/10W'  | '0603LF ' | 'CHIP'   | 'CS41273F915'(!)        = ''              | ''                 | 'CS41273F915'           |'R0603'| '(SMR0603AW)'                  | '127K'    | '1%'    | '1/10W'  | 'DISCRETE' | 'RES CHIP 127K 1/10W +-1%(0603)'                   | 'CHIPR0603'    | ''          | ''            | '20170817'
 '127K'       | '1%'      | '1/10W'  | '0603LF ' | 'EMPTY'  | 'CS41273F915'(!)        = ''              | ''                 | 'CS41273F915'           |'R0603'| '(SMR0603AW)'                  | '127K'    | '1%'    | '1/10W'  | 'IO'       | 'RES CHIP 127K 1/10W +-1%(0603)'                   | 'CHIPR0603'    | ''          | ''            | '20170817'
 '0.5'        | '1%'      | '1/2W'   | '1206LF'  | 'CHIP'   | 'CS+5007F200'(!)        = 'End of Design' | 'Comp-Approve'     | 'CS+5007F200'           |'R1206XI'| '(SMRR1206AW)'                 | '0.5'     | '1%'    | '1/2W'   | 'DISCRETE' | 'RES CHIP 0.5 1/2W +-1%(1206)'                     | 'CHIPR1206'    | ''          | ''            | '20170818'
 '0.5'        | '1%'      | '1/2W'   | '1206LF'  | 'EMPTY'  | 'CS+5007F200'(!)        = 'End of Design' | 'Comp-Approve'     | 'CS+5007F200'           |'R1206XI'| '(SMRR1206AW)'                 | '0.5'     | '1%'    | '1/2W'   | 'IO'       | 'RES CHIP 0.5 1/2W +-1%(1206)'                     | 'CHIPR1206'    | ''          | ''            | '20170818'
 '52.3K'      | '1%'      | '1/8W'   | '0805LF'  | 'CHIP'   | 'CS35234FA00'(!)        = ''              | ''                 | 'CS35234FA00'           |'R0805'| '(SMR0805AW)'                  | '52.3K'   | '1%'    | '1/8W'   | 'DISCRETE' | 'RES CHIP 52.3K 1/8W +-1%(0805)'                   | 'CHIPR0805'    | ''          | ''            | '20170821'
 '52.3K'      | '1%'      | '1/8W'   | '0805LF'  | 'EMPTY'  | 'CS35234FA00'(!)        = ''              | ''                 | 'CS35234FA00'           |'R0805'| '(SMR0805AW)'                  | '52.3K'   | '1%'    | '1/8W'   | 'IO'       | 'RES CHIP 52.3K 1/8W +-1%(0805)'                   | 'CHIPR0805'    | ''          | ''            | '20170821'
 '0.003'      | '1%'      | '2W'     | '2512LF'  | 'CHIP'   | 'CS+003AFR00'(!)        = ''              | ''                 | 'CS+003AFR00'           |'R2512XM'| '(SMR2512AW)'                  | '0.003'   | '1%'    | '2W'     | 'DISCRETE' | 'RES CHIP 0.003 2W +-1%(2512)'                     | 'CHIPR2512'    | ''          | ''            | '20170822'
 '0.003'      | '1%'      | '2W'     | '2512LF'  | 'EMPTY'  | 'CS+003AFR00'(!)        = ''              | ''                 | 'CS+003AFR00'           |'R2512XM'| '(SMR2512AW)'                  | '0.003'   | '1%'    | '2W'     | 'IO'       | 'RES CHIP 0.003 2W +-1%(2512)'                     | 'CHIPR2512'    | ''          | ''            | '20170822'
 '0.004'      | '1%'      | '2W'     | '2512LF'  | 'CHIP'   | 'CS+004AFR00'(!)        = ''              | ''                 | 'CS+004AFR00'           |'R2512XM'| '(SMR2512AW)'                  | '0.004'   | '1%'    | '2W'     | 'DISCRETE' | 'RES CHIP 0.004 2W +-1%(2512)'                     | 'CHIPR2512'    | ''          | ''            | '20170823'
 '0.004'      | '1%'      | '2W'     | '2512LF'  | 'EMPTY'  | 'CS+004AFR00'(!)        = ''              | ''                 | 'CS+004AFR00'           |'R2512XM'| '(SMR2512AW)'                  | '0.004'   | '1%'    | '2W'     | 'IO'       | 'RES CHIP 0.004 2W +-1%(2512)'                     | 'CHIPR2512'    | ''          | ''            | '20170823'
 '178K'       | '1%'      | '1/16W'  | '0402LF'  | 'CHIP'   | 'CS41782FB11'(!)        = 'End of Design' | 'Comp-Approve'     | 'CS41782FB11'           |'R0402'| '(R0402-0201)'                 | '178K'    | '1%'    | '1/16W'  | 'DISCRETE' | 'RES CHIP 178K 1/16W +-1%(0402)'                   | 'CHIP0402'     | ''          | ''            | '20170824'
 '178K'       | '1%'      | '1/16W'  | '0402LF'  | 'EMPTY'  | 'CS41782FB11'(!)        = 'End of Design' | 'Comp-Approve'     | 'CS41782FB11'           |'R0402'| '(R0402-0201)'                 | '178K'    | '1%'    | '1/16W'  | 'IO'       | 'RES CHIP 178K 1/16W +-1%(0402)'                   | 'CHIP0402'     | ''          | ''            | '20170824'
 '4.99'       | '0.1%'    | '2W'     | '2512LF'  | 'CHIP'   | 'CS-499ABR00'(!)        = 'Non-Preferred' | 'End of Life'      | 'CS-499ABR00'           |'R2512XQ_EOL'| '(SMR2512AW)'                  | '4.99'    | '0.1%'  | '2W'     | 'DISCRETE' | 'RES CHIP 4.99 2W  +-0.1%(2512)'                   | 'CHIPR2512'    | ''          | ''            | '20170830'
 '4.99'       | '0.1%'    | '2W'     | '2512LF'  | 'EMPTY'  | 'CS-499ABR00'(!)        = 'Non-Preferred' | 'End of Life'      | 'CS-499ABR00'           |'R2512XQ_EOL'| '(SMR2512AW)'                  | '4.99'    | '0.1%'  | '2W'     | 'IO'       | 'RES CHIP 4.99 2W  +-0.1%(2512)'                   | 'CHIPR2512'    | ''          | ''            | '20170830'
 '1'          | '1%'      | '2W'     | '2512LF'  | 'CHIP'   | 'CS-100AFR00'(!)        = ''              | ''                 | 'CS-100AFR00'           |'R2512XQ'| '(SMR2512AW)'                  | '1'       | '1%'    | '2W'     | 'DISCRETE' | 'RES CHIP 1  2W +-1%(2512)'                        | 'CHIPR2512'    | ''          | ''            | '20170830'
 '1'          | '1%'      | '2W'     | '2512LF'  | 'EMPTY'  | 'CS-100AFR00'(!)        = ''              | ''                 | 'CS-100AFR00'           |'R2512XQ'| '(SMR2512AW)'                  | '1'       | '1%'    | '2W'     | 'IO'       | 'RES CHIP 1  2W +-1%(2512)'                        | 'CHIPR2512'    | ''          | ''            | '20170830'
 '2.2'        | '5%'      | '2W'     | '2512LF'  | 'CHIP'   | 'CS-220AJR00'(!)        = ''              | ''                 | 'CS-220AJR00'           |'R2512XQ'| '(SMR2512AW)'                  | '2.2'     | '5%'    | '2W'     | 'DISCRETE' | 'RES CHIP 2.2 2W  +-5%(2512)'                      | 'CHIPR2512'    | ''          | ''            | '20170830'
 '2.2'        | '5%'      | '2W'     | '2512LF'  | 'EMPTY'  | 'CS-220AJR00'(!)        = ''              | ''                 | 'CS-220AJR00'           |'R2512XQ'| '(SMR2512AW)'                  | '2.2'     | '5%'    | '2W'     | 'IO'       | 'RES CHIP 2.2 2W  +-5%(2512)'                      | 'CHIPR2512'    | ''          | ''            | '20170830'
 '750K'       | '1%'      | '1/16W'  | '0402LF'  | 'CHIP'   | 'CS47502FB06'(!)        = ''              | ''                 | 'CS47502FB06'           |'R0402'| '(R0402-0201)'                 | '750K'    | '1%'    | '1/16W'  | 'DISCRETE' | 'RES CHIP 750K 1/16W +-1%(0402)'                   | 'CHIPR0402'    | ''          | ''            | '20170904'
 '750K'       | '1%'      | '1/16W'  | '0402LF'  | 'EMPTY'  | 'CS47502FB06'(!)        = ''              | ''                 | 'CS47502FB06'           |'R0402'| '(R0402-0201)'                 | '750K'    | '1%'    | '1/16W'  | 'IO'       | 'RES CHIP 750K 1/16W +-1%(0402)'                   | 'CHIPR0402'    | ''          | ''            | '20170904'
 '523K'       | '1%'      | '1/16W'  | '0402LF'  | 'CHIP'   | 'CS45232FB00'(!)        = 'End of Design' | 'Comp-Approve'     | 'CS45232FB00'           |'R0402'| '(R0402-0201)'                 | '523K'    | '1%'    | '1/16W'  | 'DISCRETE' | 'RES CHIP 523K 1/16W +-1%(0402)'                   | 'CHIPR0402'    | ''          | ''            | '20170907'
 '523K'       | '1%'      | '1/16W'  | '0402LF'  | 'EMPTY'  | 'CS45232FB00'(!)        = 'End of Design' | 'Comp-Approve'     | 'CS45232FB00'           |'R0402'| '(R0402-0201)'                 | '523K'    | '1%'    | '1/16W'  | 'IO'       | 'RES CHIP 523K 1/16W +-1%(0402)'                   | 'CHIPR0402'    | ''          | ''            | '20170907'
 '887K'       | '1%'      | '1/16W'  | '0402LF'  | 'CHIP'   | 'CS48872FB10'(!)        = 'End of Design' | 'Comp-Approve'     | 'CS48872FB10'           |'R0402'| '(R0402-0201)'                 | '887K'    | '1%'    | '1/16W'  | 'DISCRETE' | 'RES CHIP 887K 1/16W +-1%(0402)'                   | 'CHIPR0402'    | ''          | ''            | '20170907'
 '887K'       | '1%'      | '1/16W'  | '0402LF'  | 'EMPTY'  | 'CS48872FB10'(!)        = 'End of Design' | 'Comp-Approve'     | 'CS48872FB10'           |'R0402'| '(R0402-0201)'                 | '887K'    | '1%'    | '1/16W'  | 'IO'       | 'RES CHIP 887K 1/16W +-1%(0402)'                   | 'CHIPR0402'    | ''          | ''            | '20170907'
 '280'        | '1%'      | '1/16W'  | '0402LF'  | 'CHIP'   | 'CS12802FB00'(!)        = 'End of Design' | 'Comp-Approve'     | 'CS12802FB00'           |'R0402'| '(R0402-0201)'                 | '280'     | '1%'    | '1/16W'  | 'DISCRETE' | 'RES CHIP 280 1/16W +-1%(0402)'                    | 'CHIPR0402'    | ''          | ''            | '20170922'
 '280'        | '1%'      | '1/16W'  | '0402LF'  | 'EMPTY'  | 'CS12802FB00'(!)        = 'End of Design' | 'Comp-Approve'     | 'CS12802FB00'           |'R0402'| '(R0402-0201)'                 | '280'     | '1%'    | '1/16W'  | 'IO'       | 'RES CHIP 280 1/16W +-1%(0402)'                    | 'CHIPR0402'    | ''          | ''            | '20170922'
 '280'        | '1%'      | '1/16W'  | '0402LF'  | 'CHIP'   | 'CS12802FB08'(!)        = ''              | ''                 | 'CS12802FB08'           |'R0402'| '(R0402-0201)'                 | '280'     | '1%'    | '1/16W'  | 'DISCRETE' | 'RES CHIP 280 1/16W +-1% (0402)'                   | 'CHIPR0402'    | ''          | ''            | '20170922'
 '280'        | '1%'      | '1/16W'  | '0402LF'  | 'EMPTY'  | 'CS12802FB08'(!)        = ''              | ''                 | 'CS12802FB08'           |'R0402'| '(R0402-0201)'                 | '280'     | '1%'    | '1/16W'  | 'IO'       | 'RES CHIP 280 1/16W +-1% (0402)'                   | 'CHIPR0402'    | ''          | ''            | '20170922'
 '464'        | '1%'      | '1/16W'  | '0402LF'  | 'CHIP'   | 'CS14642FB04'(!)        = ''              | ''                 | 'CS14642FB04'           |'R0402'| '(R0402-0201)'                 | '464'     | '1%'    | '1/16W'  | 'DISCRETE' | 'RES CHIP 464 1/16W +-1%(0402)'                    | 'CHIPR0402'    | ''          | ''            | '20170922'
 '464'        | '1%'      | '1/16W'  | '0402LF'  | 'EMPTY'  | 'CS14642FB04'(!)        = ''              | ''                 | 'CS14642FB04'           |'R0402'| '(R0402-0201)'                 | '464'     | '1%'    | '1/16W'  | 'IO'       | 'RES CHIP 464 1/16W +-1%(0402)'                    | 'CHIPR0402'    | ''          | ''            | '20170922'
 '464'        | '1%'      | '1/16W'  | '0402LF'  | 'CHIP'   | 'CS14642FB12'(!)        = 'End of Design' | 'Comp-Approve'     | 'CS14642FB12'           |'R0402'| '(R0402-0201)'                 | '464'     | '1%'    | '1/16W'  | 'DISCRETE' | 'RES CHIP 464 1/16W +-1%(0402)'                    | 'CHIPR0402'    | ''          | ''            | '20170922'
 '464'        | '1%'      | '1/16W'  | '0402LF'  | 'EMPTY'  | 'CS14642FB12'(!)        = 'End of Design' | 'Comp-Approve'     | 'CS14642FB12'           |'R0402'| '(R0402-0201)'                 | '464'     | '1%'    | '1/16W'  | 'IO'       | 'RES CHIP 464 1/16W +-1%(0402)'                    | 'CHIPR0402'    | ''          | ''            | '20170922'
 '2.05K'      | '1%'      | '1/16W'  | '0402LF'  | 'CHIP'   | 'CS22052FB03'(!)        = ''              | ''                 | 'CS22052FB03'           |'R0402'| '(R0402-0201)'                 | '2.05K'   | '1%'    | '1/16W'  | 'DISCRETE' | 'RES CHIP 2.05K 1/16W +-1%(0402)'                  | 'CHIPR0402'    | ''          | ''            | '20170922'
 '2.05K'      | '1%'      | '1/16W'  | '0402LF'  | 'EMPTY'  | 'CS22052FB03'(!)        = ''              | ''                 | 'CS22052FB03'           |'R0402'| '(R0402-0201)'                 | '2.05K'   | '1%'    | '1/16W'  | 'IO'       | 'RES CHIP 2.05K 1/16W +-1%(0402)'                  | 'CHIPR0402'    | ''          | ''            | '20170922'
 '2.05K'      | '1%'      | '1/16W'  | '0402LF'  | 'CHIP'   | 'CS22052FB11'(!)        = 'End of Design' | 'Comp-Approve'     | 'CS22052FB11'           |'R0402'| '(R0402-0201)'                 | '2.05K'   | '1%'    | '1/16W'  | 'DISCRETE' | 'RES CHIP 2.05K 1/16W +-1%(0402)'                  | 'CHIPR0402'    | ''          | ''            | '20170922'
 '2.05K'      | '1%'      | '1/16W'  | '0402LF'  | 'EMPTY'  | 'CS22052FB11'(!)        = 'End of Design' | 'Comp-Approve'     | 'CS22052FB11'           |'R0402'| '(R0402-0201)'                 | '2.05K'   | '1%'    | '1/16W'  | 'IO'       | 'RES CHIP 2.05K 1/16W +-1%(0402)'                  | 'CHIPR0402'    | ''          | ''            | '20170922'
 '750K'       | '1%'      | '1/16W'  | '0402LF'  | 'CHIP'   | 'CS47502FB14'(!)        = 'End of Design' | 'Comp-Approve'     | 'CS47502FB14'           |'R0402'| '(R0402-0201)'                 | '750K'    | '1%'    | '1/16W'  | 'DISCRETE' | 'RES CHIP 750K 1/16W +-1%(0402)'                   | 'CHIPR0402'    | ''          | ''            | '20170925'
 '750K'       | '1%'      | '1/16W'  | '0402LF'  | 'EMPTY'  | 'CS47502FB14'(!)        = 'End of Design' | 'Comp-Approve'     | 'CS47502FB14'           |'R0402'| '(R0402-0201)'                 | '750K'    | '1%'    | '1/16W'  | 'IO'       | 'RES CHIP 750K 1/16W +-1%(0402)'                   | 'CHIPR0402'    | ''          | ''            | '20170925'
 '0.51'       | '1%'      | '1/3W'   | '0805LF'  | 'CHIP'   | 'CS+510CFA00'(!)        = ''              | ''                 | 'CS+510CFA00'           |'R0805'| '(SMR0805AW)'                  | '0.51'    | '1%'    | '1/3W'   | 'DISCRETE' | 'RES CHIP 0.51 1/3W +-1%(0805) YGO_AEC'            | 'CHIPR0805'    | ''          | ''            | '20171006'
 '0.51'       | '1%'      | '1/3W'   | '0805LF'  | 'EMPTY'  | 'CS+510CFA00'(!)        = ''              | ''                 | 'CS+510CFA00'           |'R0805'| '(SMR0805AW)'                  | '0.51'    | '1%'    | '1/3W'   | 'IO'       | 'RES CHIP 0.51 1/3W +-1%(0805) YGO_AEC'            | 'CHIPR0805'    | ''          | ''            | '20171006'
 '47.5'       | '1%'      | '1/16W'  | '0402LF'  | 'CHIP'   | 'CS04752FB19'(!)        = 'End of Design' | 'Comp-Approve'     | 'CS04752FB19'           |'R0402'| '(R0402-0201)'                 | '47.5'    | '1%'    | '1/16W'  | 'DISCRETE' | 'RES CHIP 47.5 1/16W +-1%(0402)'                   | 'CHIPR0402'    | ''          | ''            | '20171018'
 '47.5'       | '1%'      | '1/16W'  | '0402LF'  | 'EMPTY'  | 'CS04752FB19'(!)        = 'End of Design' | 'Comp-Approve'     | 'CS04752FB19'           |'R0402'| '(R0402-0201)'                 | '47.5'    | '1%'    | '1/16W'  | 'IO'       | 'RES CHIP 47.5 1/16W +-1%(0402)'                   | 'CHIPR0402'    | ''          | ''            | '20171018'
 '162'        | '1%'      | '1/20W'  | '0201LF'  | 'CHIP'   | 'CS11621FE00'(!)        = ''              | ''                 | 'CS11621FE00'           |'R0201'| '(SMR0201AW)'                  | '162'     | '1%'    | '1/20W'  | 'DISCRETE' | 'RES CHIP 162 1/20W +-1%(0201)'                    | 'CHIPR0201'    | ''          | ''            | '20171024'
 '162'        | '1%'      | '1/20W'  | '0201LF'  | 'EMPTY'  | 'CS11621FE00'(!)        = ''              | ''                 | 'CS11621FE00'           |'R0201'| '(SMR0201AW)'                  | '162'     | '1%'    | '1/20W'  | 'IO'       | 'RES CHIP 162 1/20W +-1%(0201)'                    | 'CHIPR0201'    | ''          | ''            | '20171024'
 '80.6'       | '1%'      | '1/20W'  | '0201LF'  | 'CHIP'   | 'CS08061FE00'(!)        = ''              | ''                 | 'CS08061FE00'           |'R0201'| '(SMR0201AW)'                  | '80.6'    | '1%'    | '1/20W'  | 'DISCRETE' | 'RES CHIP 80.6  1/20W +-1%(0201)'                  | 'CHIPR0201'    | ''          | ''            | '20171025'
 '80.6'       | '1%'      | '1/20W'  | '0201LF'  | 'EMPTY'  | 'CS08061FE00'(!)        = ''              | ''                 | 'CS08061FE00'           |'R0201'| '(SMR0201AW)'                  | '80.6'    | '1%'    | '1/20W'  | 'IO'       | 'RES CHIP 80.6  1/20W +-1%(0201)'                  | 'CHIPR0201'    | ''          | ''            | '20171025'
 '845K'       | '1%'      | '1/8W'   | '0805LF'  | 'CHIP'   | 'CS48454FA00'(!)        = ''              | ''                 | 'CS48454FA00'           |'R0805'| '(SMR0805AW)'                  | '845K'    | '1%'    | '1/8W'   | 'DISCRETE' | 'RES CHIP 845K 1/8W +-1%(0805)'                    | 'CHIPR0805'    | ''          | ''            | '20171026'
 '845K'       | '1%'      | '1/8W'   | '0805LF'  | 'EMPTY'  | 'CS48454FA00'(!)        = ''              | ''                 | 'CS48454FA00'           |'R0805'| '(SMR0805AW)'                  | '845K'    | '1%'    | '1/8W'   | 'IO'       | 'RES CHIP 845K 1/8W +-1%(0805)'                    | 'CHIPR0805'    | ''          | ''            | '20171026'
 '10'         | '1%'      | '2W'     | '2512LF'  | 'CHIP'   | 'CS0100AFR00'(!)        = ''              | ''                 | 'CS0100AFR00'           |'R2512XR'| '(SMR2512AW)'                  | '10'      | '1%'    | '2W'     | 'DISCRETE' | 'RES CHIP 10 2W +-1%(2512)'                        | 'CHIP2512'     | ''          | ''            | '20171030'
 '10'         | '1%'      | '2W'     | '2512LF'  | 'EMPTY'  | 'CS0100AFR00'(!)        = ''              | ''                 | 'CS0100AFR00'           |'R2512XR'| '(SMR2512AW)'                  | '10'      | '1%'    | '2W'     | 'IO'       | 'RES CHIP 10 2W +-1%(2512)'                        | 'CHIP2512'     | ''          | ''            | '20171030'
 '73.2'       | '1%'      | '1/2W'   | '1210LF'  | 'CHIP'   | 'CS07327F305'(!)        = ''              | ''                 | 'CS07327F305'           |'R1210XA'| '(SMR1210AW)'                  | '73.2'    | '1%'    | '1/2W'   | 'DISCRETE' | 'RES CHIP 73.2 1/2W +-1%(1210)'                    | 'CHIPR1210'    | ''          | ''            | '20171113'
 '73.2'       | '1%'      | '1/2W'   | '1210LF'  | 'EMPTY'  | 'CS07327F305'(!)        = ''              | ''                 | 'CS07327F305'           |'R1210XA'| '(SMR1210AW)'                  | '73.2'    | '1%'    | '1/2W'   | 'IO'       | 'RES CHIP 73.2 1/2W +-1%(1210)'                    | 'CHIPR1210'    | ''          | ''            | '20171113'
 '3.9'        | '1%'      | '1/16W'  | '0402LF'  | 'CHIP'   | 'CS-3902FB05'(!)        = ''              | ''                 | 'CS-3902FB05'           |'R0402'| '(R0402-0201)'                 | '3.9'     | '1%'    | '1/16W'  | 'DISCRETE' | 'RES CHIP 3.9 1/16W +-1% (0402)'                   | 'CHIPR0402'    | ''          | ''            | '20171127'
 '3.9'        | '1%'      | '1/16W'  | '0402LF'  | 'EMPTY'  | 'CS-3902FB05'(!)        = ''              | ''                 | 'CS-3902FB05'           |'R0402'| '(R0402-0201)'                 | '3.9'     | '1%'    | '1/16W'  | 'IO'       | 'RES CHIP 3.9 1/16W +-1% (0402)'                   | 'CHIPR0402'    | ''          | ''            | '20171127'
 '6.49K'      | '1%'      | '1/10W'  | '0603LF'  | 'CHIP'   | 'CS26493F911'(!)        = ''              | ''                 | 'CS26493F911'           |'R0603'| '(SMR0603AW)'                  | '6.49K'   | '1%'    | '1/10W'  | 'DISCRETE' | 'RES CHIP 6.49K 1/10W +-1%(0603)'                  | 'CHIPR0603'    | ''          | ''            | '20171130'
 '6.49K'      | '1%'      | '1/10W'  | '0603LF'  | 'EMPTY'  | 'CS26493F911'(!)        = ''              | ''                 | 'CS26493F911'           |'R0603'| '(SMR0603AW)'                  | '6.49K'   | '1%'    | '1/10W'  | 'IO'       | 'RES CHIP 6.49K 1/10W +-1%(0603)'                  | 'CHIPR0603'    | ''          | ''            | '20171130'
 '200'        | '1%'      | '1/20W'  | '0201LF'  | 'CHIP'   | 'CS12001FE01'(!)        = ''              | ''                 | 'CS12001FE01'           |'R0201'| '(SMR0201AW)'                  | '200'     | '1%'    | '1/20W'  | 'DISCRETE' | 'RES CHIP 200 1/20W +-1%(0201)'                    | 'CHIP0201'     | ''          | ''            | '20171130'
 '200'        | '1%'      | '1/20W'  | '0201LF'  | 'EMPTY'  | 'CS12001FE01'(!)        = ''              | ''                 | 'CS12001FE01'           |'R0201'| '(SMR0201AW)'                  | '200'     | '1%'    | '1/20W'  | 'IO'       | 'RES CHIP 200 1/20W +-1%(0201)'                    | 'CHIP0201'     | ''          | ''            | '20171130'
 '0.0002'     | '1%'      | '4W'     | '2725LF'  | 'CHIP'   | 'CS0000FFT06'(!)        = 'End of Design' | 'Comp-Approve'     | 'CS0000FFT06'           |'R2725'| '(SMR2725AW)'                  | '0.0002'  | '1%'    | '4W'     | 'DISCRETE' | 'RES CHIP 0.0002 4W +-1%(2725)1.1'                 | 'CHIP2725'     | ''          | ''            | '20171215'
 '0.0002'     | '1%'      | '4W'     | '2725LF'  | 'EMPTY'  | 'CS0000FFT06'(!)        = 'End of Design' | 'Comp-Approve'     | 'CS0000FFT06'           |'R2725'| '(SMR2725AW)'                  | '0.0002'  | '1%'    | '4W'     | 'IO'       | 'RES CHIP 0.0002 4W +-1%(2725)1.1'                 | 'CHIP2725'     | ''          | ''            | '20171215'
 '5.62K'      | '0.1%'    | '1/16W'  | '0402LF'  | 'CHIP'   | 'CS25622BB00'(!)        = ''              | ''                 | 'CS25622BB00'           |'R0402'| '(R0402-0201)'                 | '5.62K'   | '0.1%'  | '1/16W'  | 'DISCRETE' | 'RES CHIP 5.62K 1/16W +-0.1%(0402)'                | 'CHIPR0402'    | ''          | ''            | '20180103'
 '5.62K'      | '0.1%'    | '1/16W'  | '0402LF'  | 'EMPTY'  | 'CS25622BB00'(!)        = ''              | ''                 | 'CS25622BB00'           |'R0402'| '(R0402-0201)'                 | '5.62K'   | '0.1%'  | '1/16W'  | 'IO'       | 'RES CHIP 5.62K 1/16W +-0.1%(0402)'                | 'CHIPR0402'    | ''          | ''            | '20180103'
 '143'        | '1%'      | '1/16W'  | '0402LF'  | 'CHIP'   | 'CS11432FB00'(!)        = 'End of Design' | 'Comp-Approve'     | 'CS11432FB00'           |'R0402'| '(R0402-0201)'                 | '143'     | '1%'    | '1/16W'  | 'DISCRETE' | 'RES CHIP 143 1/16W +-1%(0402)'                    | 'CHIPR0402'    | ''          | ''            | '20100429'
 '143'        | '1%'      | '1/16W'  | '0402LF'  | 'EMPTY'  | 'CS11432FB00'(!)        = 'End of Design' | 'Comp-Approve'     | 'CS11432FB00'           |'R0402'| '(R0402-0201)'                 | '143'     | '1%'    | '1/16W'  | 'IO'       | 'RES CHIP 143 1/16W +-1%(0402)'                    | 'CHIPR0402'    | ''          | ''            | '20100429'
 '86.6'       | '1%'      | '1/16W'  | '0402LF'  | 'CHIP'   | 'CS08662FB00'(!)        = 'End of Design' | 'Comp-Approve'     | 'CS08662FB00'           |'R0402'| '(R0402-0201)'                 | '86.6'    | '1%'    | '1/16W'  | 'DISCRETE' | 'RES CHIP 86.6 1/16W +-1%(0402)'                   | 'CHIP0402'     | ''          | ''            | '20180109'
 '86.6'       | '1%'      | '1/16W'  | '0402LF'  | 'EMPTY'  | 'CS08662FB00'(!)        = 'End of Design' | 'Comp-Approve'     | 'CS08662FB00'           |'R0402'| '(R0402-0201)'                 | '86.6'    | '1%'    | '1/16W'  | 'IO'       | 'RES CHIP 86.6 1/16W +-1%(0402)'                   | 'CHIP0402'     | ''          | ''            | '20180109'
 '120'        | '1%'      | '1/16W'  | '0402LF'  | 'CHIP'   | 'CS11202FB02'(!)        = 'End of Design' | 'Comp-Approve'     | 'CS11202FB02'           |'R0402'| '(R0402-0201)'                 | '120'     | '1%'    | '1/16W'  | 'DISCRETE' | 'RES CHIP 120 1/16W +-1%(0402)EF'                  | 'CHIPR0402'    | ''          | ''            | '20180116'
 '120'        | '1%'      | '1/16W'  | '0402LF'  | 'EMPTY'  | 'CS11202FB02'(!)        = 'End of Design' | 'Comp-Approve'     | 'CS11202FB02'           |'R0402'| '(R0402-0201)'                 | '120'     | '1%'    | '1/16W'  | 'IO'       | 'RES CHIP 120 1/16W +-1%(0402)EF'                  | 'CHIPR0402'    | ''          | ''            | '20180116'
 '57.6K'      | '0.1%'    | '1/16W'  | '0402LF'  | 'CHIP'   | 'CS35762BB00'(!)        = ''              | ''                 | 'CS35762BB00'           |'R0402'| '(R0402-0201)'                 | '57.6K'   | '0.1%'  | '1/16W'  | 'DISCRETE' | 'RES CHIP 57.6K 1/16W +-0.1% (0402)'               | 'CHIPR0402'    | ''          | ''            | '20150414'
 '57.6K'      | '0.1%'    | '1/16W'  | '0402LF'  | 'EMPTY'  | 'CS35762BB00'(!)        = ''              | ''                 | 'CS35762BB00'           |'R0402'| '(R0402-0201)'                 | '57.6K'   | '0.1%'  | '1/16W'  | 'IO'       | 'RES CHIP 57.6K 1/16W +-0.1% (0402)'               | 'CHIPR0402'    | ''          | ''            | '20150414'
 '10.2K'      | '1%'      | '1/16W'  | '0402LF'  | 'CHIP'   | 'CS31022FB04'(!)        = 'End of Design' | 'Comp-Approve'     | 'CS31022FB04'           |'R0402'| '(R0402-0201)'                 | '10.2K'   | '1%'    | '1/16W'  | 'DISCRETE' | 'RES CHIP 10.2K 1/16W +-1%(0402)EF'                | 'CHIPR0402'    | ''          | ''            | '20180116'
 '10.2K'      | '1%'      | '1/16W'  | '0402LF'  | 'EMPTY'  | 'CS31022FB04'(!)        = 'End of Design' | 'Comp-Approve'     | 'CS31022FB04'           |'R0402'| '(R0402-0201)'                 | '10.2K'   | '1%'    | '1/16W'  | 'IO'       | 'RES CHIP 10.2K 1/16W +-1%(0402)EF'                | 'CHIPR0402'    | ''          | ''            | '20180116'
 '4.02K'      | '0.1%'    | '1/16W'  | '0402LF'  | 'CHIP'   | 'CS24022BB00'(!)        = ''              | ''                 | 'CS24022BB00'           |'R0402'| '(R0402-0201)'                 | '4.02K'   | '0.1%'  | '1/16W'  | 'DISCRETE' | 'RES CHIP 4.02K 1/16W  +-0.1%(0402)'               | 'CHIPR0402'    | ''          | ''            | '20170829'
 '4.02K'      | '0.1%'    | '1/16W'  | '0402LF'  | 'EMPTY'  | 'CS24022BB00'(!)        = ''              | ''                 | 'CS24022BB00'           |'R0402'| '(R0402-0201)'                 | '4.02K'   | '0.1%'  | '1/16W'  | 'IO'       | 'RES CHIP 4.02K 1/16W  +-0.1%(0402)'               | 'CHIPR0402'    | ''          | ''            | '20170829'
 '375'        | '1%'      | '1/10W'  | '0603LF'  | 'CHIP'   | 'CS13753F906'(!)        = 'End of Design' | 'Comp-Approve'     | 'CS13753F906'           |'R0603'| '(SMR0603AW)'                  | '375'     | '1%'    | '1/10W'  | 'DISCRETE' | 'RES CHIP 375 1/10W+-1%(0603)'                     | 'CHIP0603'     | ''          | ''            | '20180131'
 '375'        | '1%'      | '1/10W'  | '0603LF'  | 'EMPTY'  | 'CS13753F906'(!)        = 'End of Design' | 'Comp-Approve'     | 'CS13753F906'           |'R0603'| '(SMR0603AW)'                  | '375'     | '1%'    | '1/10W'  | 'IO'       | 'RES CHIP 375 1/10W+-1%(0603)'                     | 'CHIP0603'     | ''          | ''            | '20180131'
 '576K'       | '1%'      | '1/16W'  | '0402LF'  | 'CHIP'   | 'CS45762FB13'(!)        = 'End of Design' | 'Comp-Approve'     | 'CS45762FB13'           |'R0402'| '(R0402-0201)'                 | '576K'    | '1%'    | '1/16W'  | 'DISCRETE' | 'RES CHIP 576K 1/16W +-1%(0402)'                   | 'CHIPR0402'    | ''          | ''            | '20180206'
 '576K'       | '1%'      | '1/16W'  | '0402LF'  | 'EMPTY'  | 'CS45762FB13'(!)        = 'End of Design' | 'Comp-Approve'     | 'CS45762FB13'           |'R0402'| '(R0402-0201)'                 | '576K'    | '1%'    | '1/16W'  | 'IO'       | 'RES CHIP 576K 1/16W +-1%(0402)'                   | 'CHIPR0402'    | ''          | ''            | '20180206'
 '1.1M'       | '1%'      | '1/16W'  | '0402LF'  | 'CHIP'   | 'CS51102FB00'(!)        = ''              | ''                 | 'CS51102FB00'           |'R0402'| '(R0402-0201)'                 | '1.1M'    | '1%'    | '1/16W'  | 'DISCRETE' | 'RES CHIP 1.1M 1/16W +-1%(0402)'                   | 'CHIPR0402'    | ''          | ''            | '20180206'
 '1.1M'       | '1%'      | '1/16W'  | '0402LF'  | 'EMPTY'  | 'CS51102FB00'(!)        = ''              | ''                 | 'CS51102FB00'           |'R0402'| '(R0402-0201)'                 | '1.1M'    | '1%'    | '1/16W'  | 'IO'       | 'RES CHIP 1.1M 1/16W +-1%(0402)'                   | 'CHIPR0402'    | ''          | ''            | '20180206'
 '1.18M'      | '1%'      | '1/16W'  | '0402LF'  | 'CHIP'   | 'CS51182FB01'(!)        = ''              | ''                 | 'CS51182FB01'           |'R0402'| '(R0402-0201)'                 | '1.18M'   | '1%'    | '1/16W'  | 'DISCRETE' | 'RES CHIP 1.18M 1/16W +-1%(0402)'                  | 'CHIPR0402'    | ''          | ''            | '20180207'
 '1.18M'      | '1%'      | '1/16W'  | '0402LF'  | 'EMPTY'  | 'CS51182FB01'(!)        = ''              | ''                 | 'CS51182FB01'           |'R0402'| '(R0402-0201)'                 | '1.18M'   | '1%'    | '1/16W'  | 'IO'       | 'RES CHIP 1.18M 1/16W +-1%(0402)'                  | 'CHIPR0402'    | ''          | ''            | '20180207'
 '1.13M'      | '1%'      | '1/16W'  | '0402LF'  | 'CHIP'   | 'CS51132FB00'(!)        = ''              | ''                 | 'CS51132FB00'           |'R0402'| '(R0402-0201)'                 | '1.13M'   | '1%'    | '1/16W'  | 'DISCRETE' | 'RES CHIP 1.13M 1/16W +-1%(0402)'                  | 'CHIPR0402'    | ''          | ''            | '20180207'
 '1.13M'      | '1%'      | '1/16W'  | '0402LF'  | 'EMPTY'  | 'CS51132FB00'(!)        = ''              | ''                 | 'CS51132FB00'           |'R0402'| '(R0402-0201)'                 | '1.13M'   | '1%'    | '1/16W'  | 'IO'       | 'RES CHIP 1.13M 1/16W +-1%(0402)'                  | 'CHIPR0402'    | ''          | ''            | '20180207'
 '0.51'       | '1%'      | '1/16W'  | '0402LF'  | 'CHIP'   | 'CS+5102FB01'(!)        = ''              | ''                 | 'CS+5102FB01'           |'R0402'| '(R0402-0201)'                 | '0.51'    | '1%'    | '1/16W'  | 'DISCRETE' | 'RES CHIP 0.51 1/16W +-1%(0402)EF'                 | 'CHIP0402'     | ''          | ''            | '20180212'
 '0.51'       | '1%'      | '1/16W'  | '0402LF'  | 'EMPTY'  | 'CS+5102FB01'(!)        = ''              | ''                 | 'CS+5102FB01'           |'R0402'| '(R0402-0201)'                 | '0.51'    | '1%'    | '1/16W'  | 'IO'       | 'RES CHIP 0.51 1/16W +-1%(0402)EF'                 | 'CHIP0402'     | ''          | ''            | '20180212'
 '143'        | '1%'      | '1/16W'  | '0402LF'  | 'CHIP'   | 'CS11432FB02'(!)        = ''              | ''                 | 'CS11432FB02'           |'R0402'| '(R0402-0201)'                 | '143'     | '1%'    | '1/16W'  | 'DISCRETE' | 'RES CHIP 143 1/16W +-1%(0402)EF'                  | 'CHIP0402'     | ''          | ''            | '20180212'
 '143'        | '1%'      | '1/16W'  | '0402LF'  | 'EMPTY'  | 'CS11432FB02'(!)        = ''              | ''                 | 'CS11432FB02'           |'R0402'| '(R0402-0201)'                 | '143'     | '1%'    | '1/16W'  | 'IO'       | 'RES CHIP 143 1/16W +-1%(0402)EF'                  | 'CHIP0402'     | ''          | ''            | '20180212'
 '220'        | '1%'      | '1/16W'  | '0402LF'  | 'CHIP'   | 'CS12202FB04'(!)        = ''              | ''                 | 'CS12202FB04'           |'R0402'| '(R0402-0201)'                 | '220'     | '1%'    | '1/16W'  | 'DISCRETE' | 'RES CHIP 220 1/16W +-1%(0402)EF'                  | 'CHIP0402'     | ''          | ''            | '20180212'
 '220'        | '1%'      | '1/16W'  | '0402LF'  | 'EMPTY'  | 'CS12202FB04'(!)        = ''              | ''                 | 'CS12202FB04'           |'R0402'| '(R0402-0201)'                 | '220'     | '1%'    | '1/16W'  | 'IO'       | 'RES CHIP 220 1/16W +-1%(0402)EF'                  | 'CHIP0402'     | ''          | ''            | '20180212'
 '1K'         | '1%'      | '1/20W'  | '0201LF'  | 'CHIP'   | 'CS21001FE07'(!)        = ''              | ''                 | 'CS21001FE07'           |'R0201'| '(SMR0201AW)'                  | '1K'      | '1%'    | '1/20W'  | 'DISCRETE' | 'RES CHIP 1K 1/20W +-1%(0201)EF'                   | 'CHIP0201'     | ''          | ''            | '20180212'
 '1K'         | '1%'      | '1/20W'  | '0201LF'  | 'EMPTY'  | 'CS21001FE07'(!)        = ''              | ''                 | 'CS21001FE07'           |'R0201'| '(SMR0201AW)'                  | '1K'      | '1%'    | '1/20W'  | 'IO'       | 'RES CHIP 1K 1/20W +-1%(0201)EF'                   | 'CHIP0201'     | ''          | ''            | '20180212'
 '5.62K'      | '0.1%'    | '1/16W'  | '0402LF'  | 'CHIP'   | 'CS25622BB01'(!)        = ''              | ''                 | 'CS25622BB01'           |'R0402'| '(R0402-0201)'                 | '5.62K'   | '0.1%'  | '1/16W'  | 'DISCRETE' | 'RES CHIP 5.62K 1/16W +-0.1%(0402)EF'              | 'CHIP0402'     | ''          | ''            | '20180212'
 '5.62K'      | '0.1%'    | '1/16W'  | '0402LF'  | 'EMPTY'  | 'CS25622BB01'(!)        = ''              | ''                 | 'CS25622BB01'           |'R0402'| '(R0402-0201)'                 | '5.62K'   | '0.1%'  | '1/16W'  | 'IO'       | 'RES CHIP 5.62K 1/16W +-0.1%(0402)EF'              | 'CHIP0402'     | ''          | ''            | '20180212'
 '6.2K'       | '1%'      | '1/16W'  | '0402LF'  | 'CHIP'   | 'CS26202FB02'(!)        = ''              | ''                 | 'CS26202FB02'           |'R0402'| '(R0402-0201)'                 | '6.2K'    | '1%'    | '1/16W'  | 'DISCRETE' | 'RES CHIP 6.2K 1/16W +-1%(0402)EF'                 | 'CHIP0402'     | ''          | ''            | '20180212'
 '6.2K'       | '1%'      | '1/16W'  | '0402LF'  | 'EMPTY'  | 'CS26202FB02'(!)        = ''              | ''                 | 'CS26202FB02'           |'R0402'| '(R0402-0201)'                 | '6.2K'    | '1%'    | '1/16W'  | 'IO'       | 'RES CHIP 6.2K 1/16W +-1%(0402)EF'                 | 'CHIP0402'     | ''          | ''            | '20180212'
 '6.8K'       | '1%'      | '1/16W'  | '0402LF'  | 'CHIP'   | 'CS26802FB02'(!)        = ''              | ''                 | 'CS26802FB02'           |'R0402'| '(R0402-0201)'                 | '6.8K'    | '1%'    | '1/16W'  | 'DISCRETE' | 'RES CHIP 6.8K 1/16W +-1%(0402)EF'                 | 'CHIP0402'     | ''          | ''            | '20180212'
 '6.8K'       | '1%'      | '1/16W'  | '0402LF'  | 'EMPTY'  | 'CS26802FB02'(!)        = ''              | ''                 | 'CS26802FB02'           |'R0402'| '(R0402-0201)'                 | '6.8K'    | '1%'    | '1/16W'  | 'IO'       | 'RES CHIP 6.8K 1/16W +-1%(0402)EF'                 | 'CHIP0402'     | ''          | ''            | '20180212'
 '7.5K'       | '0.1%'    | '1/16W'  | '0402LF'  | 'CHIP'   | 'CS27502BB01'(!)        = ''              | ''                 | 'CS27502BB01'           |'R0402'| '(R0402-0201)'                 | '7.5K'    | '0.1%'  | '1/16W'  | 'DISCRETE' | 'RES CHIP 7.5K 1/16W +-0.1%(0402)EF'               | 'CHIP0402'     | ''          | ''            | '20180212'
 '7.5K'       | '0.1%'    | '1/16W'  | '0402LF'  | 'EMPTY'  | 'CS27502BB01'(!)        = ''              | ''                 | 'CS27502BB01'           |'R0402'| '(R0402-0201)'                 | '7.5K'    | '0.1%'  | '1/16W'  | 'IO'       | 'RES CHIP 7.5K 1/16W +-0.1%(0402)EF'               | 'CHIP0402'     | ''          | ''            | '20180212'
 '8.45K'      | '1%'      | '1/16W'  | '0402LF'  | 'CHIP'   | 'CS28452FB06'(!)        = ''              | ''                 | 'CS28452FB06'           |'R0402'| '(R0402-0201)'                 | '8.45K'   | '1%'    | '1/16W'  | 'DISCRETE' | 'RES CHIP 8.45K 1/16W +-1%( 0402)EF'               | 'CHIP0402'     | ''          | ''            | '20180212'
 '8.45K'      | '1%'      | '1/16W'  | '0402LF'  | 'EMPTY'  | 'CS28452FB06'(!)        = ''              | ''                 | 'CS28452FB06'           |'R0402'| '(R0402-0201)'                 | '8.45K'   | '1%'    | '1/16W'  | 'IO'       | 'RES CHIP 8.45K 1/16W +-1%( 0402)EF'               | 'CHIP0402'     | ''          | ''            | '20180212'
 '12K'        | '0.1%'    | '1/16W'  | '0402LF'  | 'CHIP'   | 'CS31202BB01'(!)        = ''              | ''                 | 'CS31202BB01'           |'R0402'| '(R0402-0201)'                 | '12K'     | '0.1%'  | '1/16W'  | 'DISCRETE' | 'RES CHIP 12K 1/16W +-0.1%(0402)EF'                | 'CHIP0402'     | ''          | ''            | '20180212'
 '12K'        | '0.1%'    | '1/16W'  | '0402LF'  | 'EMPTY'  | 'CS31202BB01'(!)        = ''              | ''                 | 'CS31202BB01'           |'R0402'| '(R0402-0201)'                 | '12K'     | '0.1%'  | '1/16W'  | 'IO'       | 'RES CHIP 12K 1/16W +-0.1%(0402)EF'                | 'CHIP0402'     | ''          | ''            | '20180212'
 '20K'        | '5%'      | '1/16W'  | '0402LF'  | 'CHIP'   | 'CS32002JB06'(!)        = ''              | ''                 | 'CS32002JB06'           |'R0402'| '(R0402-0201)'                 | '20K'     | '5%'    | '1/16W'  | 'DISCRETE' | 'RES CHIP 20K 1/16W +-5%(0402)EF'                  | 'CHIP0402'     | ''          | ''            | '20180212'
 '20K'        | '5%'      | '1/16W'  | '0402LF'  | 'EMPTY'  | 'CS32002JB06'(!)        = ''              | ''                 | 'CS32002JB06'           |'R0402'| '(R0402-0201)'                 | '20K'     | '5%'    | '1/16W'  | 'IO'       | 'RES CHIP 20K 1/16W +-5%(0402)EF'                  | 'CHIP0402'     | ''          | ''            | '20180212'
 '34K'        | '1%'      | '1/16W'  | '0402LF'  | 'CHIP'   | 'CS33402FB06'(!)        = ''              | ''                 | 'CS33402FB06'           |'R0402'| '(R0402-0201)'                 | '34K'     | '1%'    | '1/16W'  | 'DISCRETE' | 'RES CHIP 34K 1/16W +-1%(0402)EF'                  | 'CHIP0402'     | ''          | ''            | '20180212'
 '34K'        | '1%'      | '1/16W'  | '0402LF'  | 'EMPTY'  | 'CS33402FB06'(!)        = ''              | ''                 | 'CS33402FB06'           |'R0402'| '(R0402-0201)'                 | '34K'     | '1%'    | '1/16W'  | 'IO'       | 'RES CHIP 34K 1/16W +-1%(0402)EF'                  | 'CHIP0402'     | ''          | ''            | '20180212'
 '1.87K'      | '0.1%'    | '1/16W'  | '0402LF'  | 'CHIP'   | 'CS21872BB00'(!)        = ''              | ''                 | 'CS21872BB00'           |'R0402'| '(R0402-0201)'                 | '1.87K'   | '0.1%'  | '1/16W'  | 'DISCRETE' | 'RES CHIP 1.87K 1/16W +-0.1%(0402)EF'              | 'CHIP0402'     | ''          | ''            | '20180212'
 '1.87K'      | '0.1%'    | '1/16W'  | '0402LF'  | 'EMPTY'  | 'CS21872BB00'(!)        = ''              | ''                 | 'CS21872BB00'           |'R0402'| '(R0402-0201)'                 | '1.87K'   | '0.1%'  | '1/16W'  | 'IO'       | 'RES CHIP 1.87K 1/16W +-0.1%(0402)EF'              | 'CHIP0402'     | ''          | ''            | '20180212'
 '2.37K'      | '0.1%'    | '1/16W'  | '0402LF'  | 'CHIP'   | 'CS22372BB02'(!)        = ''              | ''                 | 'CS22372BB02'           |'R0402'| '(R0402-0201)'                 | '2.37K'   | '0.1%'  | '1/16W'  | 'DISCRETE' | 'RES CHIP 2.37K 1/16W +-0.1%(0402)EF'              | 'CHIP0402'     | ''          | ''            | '20180212'
 '2.37K'      | '0.1%'    | '1/16W'  | '0402LF'  | 'EMPTY'  | 'CS22372BB02'(!)        = ''              | ''                 | 'CS22372BB02'           |'R0402'| '(R0402-0201)'                 | '2.37K'   | '0.1%'  | '1/16W'  | 'IO'       | 'RES CHIP 2.37K 1/16W +-0.1%(0402)EF'              | 'CHIP0402'     | ''          | ''            | '20180212'
 '4.02K'      | '0.1%'    | '1/16W'  | '0402LF'  | 'CHIP'   | 'CS24022BB01'(!)        = ''              | ''                 | 'CS24022BB01'           |'R0402'| '(R0402-0201)'                 | '4.02K'   | '0.1%'  | '1/16W'  | 'DISCRETE' | 'RES CHIP 4.02K 1/16W +-0.1%(0402)EF'              | 'CHIP0402'     | ''          | ''            | '20180212'
 '4.02K'      | '0.1%'    | '1/16W'  | '0402LF'  | 'EMPTY'  | 'CS24022BB01'(!)        = ''              | ''                 | 'CS24022BB01'           |'R0402'| '(R0402-0201)'                 | '4.02K'   | '0.1%'  | '1/16W'  | 'IO'       | 'RES CHIP 4.02K 1/16W +-0.1%(0402)EF'              | 'CHIP0402'     | ''          | ''            | '20180212'
 '57.6K'      | '0.1%'    | '1/16W'  | '0402LF'  | 'CHIP'   | 'CS35762BB01'(!)        = ''              | ''                 | 'CS35762BB01'           |'R0402'| '(R0402-0201)'                 | '57.6K'   | '0.1%'  | '1/16W'  | 'DISCRETE' | 'RES CHIP 57.6K 1/16W +-0.1%(0402)EF'              | 'CHIP0402'     | ''          | ''            | '20180212'
 '57.6K'      | '0.1%'    | '1/16W'  | '0402LF'  | 'EMPTY'  | 'CS35762BB01'(!)        = ''              | ''                 | 'CS35762BB01'           |'R0402'| '(R0402-0201)'                 | '57.6K'   | '0.1%'  | '1/16W'  | 'IO'       | 'RES CHIP 57.6K 1/16W +-0.1%(0402)EF'              | 'CHIP0402'     | ''          | ''            | '20180212'
 '100K'       | '0.1%'    | '1/16W'  | '0402LF'  | 'CHIP'   | 'CS41002BB08'(!)        = ''              | ''                 | 'CS41002BB08'           |'R0402'| '(R0402-0201)'                 | '100K'    | '0.1%'  | '1/16W'  | 'DISCRETE' | 'RES CHIP 100K 1/16W +-0.1%(0402)EF'               | 'CHIP0402'     | ''          | ''            | '20180212'
 '100K'       | '0.1%'    | '1/16W'  | '0402LF'  | 'EMPTY'  | 'CS41002BB08'(!)        = ''              | ''                 | 'CS41002BB08'           |'R0402'| '(R0402-0201)'                 | '100K'    | '0.1%'  | '1/16W'  | 'IO'       | 'RES CHIP 100K 1/16W +-0.1%(0402)EF'               | 'CHIP0402'     | ''          | ''            | '20180212'
 '2.2'        | '1%'      | '1/16W'  | '0402LF'  | 'CHIP'   | 'CS-2202FB01'(!)        = 'End of Design' | 'Comp-Approve'     | 'CS-2202FB01'           |'R0402'| '(R0402-0201)'                 | '2.2'     | '1%'    | '1/16W'  | 'DISCRETE' | 'RES CHIP 2.2 1/16W +-1%(0402)EF'                  | 'CHIP0402'     | ''          | ''            | '20180212'
 '2.2'        | '1%'      | '1/16W'  | '0402LF'  | 'EMPTY'  | 'CS-2202FB01'(!)        = 'End of Design' | 'Comp-Approve'     | 'CS-2202FB01'           |'R0402'| '(R0402-0201)'                 | '2.2'     | '1%'    | '1/16W'  | 'IO'       | 'RES CHIP 2.2 1/16W +-1%(0402)EF'                  | 'CHIP0402'     | ''          | ''            | '20180212'
 '0'          | '5%'      | '1/20W'  | '0201LF'  | 'CHIP'   | 'CS00001JE10'(!)        = 'End of Design' | 'Comp-Approve'     | 'CS00001JE10'           |'R0201'| '(SMR0201AW)'                  | '0'       | '5%'    | '1/20W'  | 'DISCRETE' | 'RES CHIP 0 1/20W +-5% (0201)EF'                   | 'CHIP0201'     | ''          | ''            | '20180212'
 '0'          | '5%'      | '1/20W'  | '0201LF'  | 'EMPTY'  | 'CS00001JE10'(!)        = 'End of Design' | 'Comp-Approve'     | 'CS00001JE10'           |'R0201'| '(SMR0201AW)'                  | '0'       | '5%'    | '1/20W'  | 'IO'       | 'RES CHIP 0 1/20W +-5% (0201)EF'                   | 'CHIP0201'     | ''          | ''            | '20180212'
 '22'         | '5%'      | '1/16W'  | '0402LF'  | 'CHIP'   | 'CS02202JB09'(!)        = 'End of Design' | 'Comp-Approve'     | 'CS02202JB09'           |'R0402'| '(R0402-0201)'                 | '22'      | '5%'    | '1/16W'  | 'DISCRETE' | 'RES CHIP 22 1/16W +-5%(0402)EF'                   | 'CHIP0402'     | ''          | ''            | '20180212'
 '22'         | '5%'      | '1/16W'  | '0402LF'  | 'EMPTY'  | 'CS02202JB09'(!)        = 'End of Design' | 'Comp-Approve'     | 'CS02202JB09'           |'R0402'| '(R0402-0201)'                 | '22'      | '5%'    | '1/16W'  | 'IO'       | 'RES CHIP 22 1/16W +-5%(0402)EF'                   | 'CHIP0402'     | ''          | ''            | '20180212'
 '51'         | '5%'      | '1/16W'  | '0402LF'  | 'CHIP'   | 'CS05102JB04'(!)        = 'End of Design' | 'Comp-Approve'     | 'CS05102JB04'           |'R0402'| '(R0402-0201)'                 | '51'      | '5%'    | '1/16W'  | 'DISCRETE' | 'RES CHIP 51 1/16W +-5%(0402)EF'                   | 'CHIP0402'     | ''          | ''            | '20180212'
 '51'         | '5%'      | '1/16W'  | '0402LF'  | 'EMPTY'  | 'CS05102JB04'(!)        = 'End of Design' | 'Comp-Approve'     | 'CS05102JB04'           |'R0402'| '(R0402-0201)'                 | '51'      | '5%'    | '1/16W'  | 'IO'       | 'RES CHIP 51 1/16W +-5%(0402)EF'                   | 'CHIP0402'     | ''          | ''            | '20180212'
 '82.5'       | '1%'      | '1/16W'  | '0402LF'  | 'CHIP'   | 'CS08252FB02'(!)        = 'End of Design' | 'Comp-Approve'     | 'CS08252FB02'           |'R0402'| '(R0402-0201)'                 | '82.5'    | '1%'    | '1/16W'  | 'DISCRETE' | 'RES CHIP 82.5 1/16W +-1%(0402)EF'                 | 'CHIP0402'     | ''          | ''            | '20180212'
 '82.5'       | '1%'      | '1/16W'  | '0402LF'  | 'EMPTY'  | 'CS08252FB02'(!)        = 'End of Design' | 'Comp-Approve'     | 'CS08252FB02'           |'R0402'| '(R0402-0201)'                 | '82.5'    | '1%'    | '1/16W'  | 'IO'       | 'RES CHIP 82.5 1/16W +-1%(0402)EF'                 | 'CHIP0402'     | ''          | ''            | '20180212'
 '330'        | '1%'      | '1/16W'  | '0402LF'  | 'CHIP'   | 'CS13302FB00'(!)        = 'End of Design' | 'Comp-Approve'     | 'CS13302FB00'           |'R0402'| '(R0402-0201)'                 | '330'     | '1%'    | '1/16W'  | 'DISCRETE' | 'RES CHIP 330 1/16W +-1%(0402)EF'                  | 'CHIP0402'     | ''          | ''            | '20180212'
 '330'        | '1%'      | '1/16W'  | '0402LF'  | 'EMPTY'  | 'CS13302FB00'(!)        = 'End of Design' | 'Comp-Approve'     | 'CS13302FB00'           |'R0402'| '(R0402-0201)'                 | '330'     | '1%'    | '1/16W'  | 'IO'       | 'RES CHIP 330 1/16W +-1%(0402)EF'                  | 'CHIP0402'     | ''          | ''            | '20180212'
 '2.2K'       | '5%'      | '1/16W'  | '0402LF'  | 'CHIP'   | 'CS22202JB07'(!)        = 'End of Design' | 'Comp-Approve'     | 'CS22202JB07'           |'R0402'| '(R0402-0201)'                 | '2.2K'    | '5%'    | '1/16W'  | 'DISCRETE' | 'RES CHIP 2.2K 1/16W +-5%(0402)EF'                 | 'CHIP0402'     | ''          | ''            | '20180212'
 '2.2K'       | '5%'      | '1/16W'  | '0402LF'  | 'EMPTY'  | 'CS22202JB07'(!)        = 'End of Design' | 'Comp-Approve'     | 'CS22202JB07'           |'R0402'| '(R0402-0201)'                 | '2.2K'    | '5%'    | '1/16W'  | 'IO'       | 'RES CHIP 2.2K 1/16W +-5%(0402)EF'                 | 'CHIP0402'     | ''          | ''            | '20180212'
 '2.7K'       | '5%'      | '1/16W'  | '0402LF'  | 'CHIP'   | 'CS22702JB04'(!)        = 'End of Design' | 'Comp-Approve'     | 'CS22702JB04'           |'R0402'| '(R0402-0201)'                 | '2.7K'    | '5%'    | '1/16W'  | 'DISCRETE' | 'RES CHIP 2.7K 1/16W +-5%(0402)EF'                 | 'CHIP0402'     | ''          | ''            | '20180212'
 '2.7K'       | '5%'      | '1/16W'  | '0402LF'  | 'EMPTY'  | 'CS22702JB04'(!)        = 'End of Design' | 'Comp-Approve'     | 'CS22702JB04'           |'R0402'| '(R0402-0201)'                 | '2.7K'    | '5%'    | '1/16W'  | 'IO'       | 'RES CHIP 2.7K 1/16W +-5%(0402)EF'                 | 'CHIP0402'     | ''          | ''            | '20180212'
 '4.53K'      | '1%'      | '1/16W'  | '0402LF'  | 'CHIP'   | 'CS24532FB03'(!)        = 'End of Design' | 'Comp-Approve'     | 'CS24532FB03'           |'R0402'| '(R0402-0201)'                 | '4.53K'   | '1%'    | '1/16W'  | 'DISCRETE' | 'RES CHIP 4.53K 1/16W +-1%(0402)EF'                | 'CHIP0402'     | ''          | ''            | '20180212'
 '4.53K'      | '1%'      | '1/16W'  | '0402LF'  | 'EMPTY'  | 'CS24532FB03'(!)        = 'End of Design' | 'Comp-Approve'     | 'CS24532FB03'           |'R0402'| '(R0402-0201)'                 | '4.53K'   | '1%'    | '1/16W'  | 'IO'       | 'RES CHIP 4.53K 1/16W +-1%(0402)EF'                | 'CHIP0402'     | ''          | ''            | '20180212'
 '8.2K'       | '5%'      | '1/16W'  | '0402LF'  | 'CHIP'   | 'CS28202JB05'(!)        = 'End of Design' | 'Comp-Approve'     | 'CS28202JB05'           |'R0402'| '(R0402-0201)'                 | '8.2K'    | '5%'    | '1/16W'  | 'DISCRETE' | 'RES CHIP 8.2K 1/16W +-5% (0402) EF'               | 'CHIP0402'     | ''          | ''            | '20180212'
 '8.2K'       | '5%'      | '1/16W'  | '0402LF'  | 'EMPTY'  | 'CS28202JB05'(!)        = 'End of Design' | 'Comp-Approve'     | 'CS28202JB05'           |'R0402'| '(R0402-0201)'                 | '8.2K'    | '5%'    | '1/16W'  | 'IO'       | 'RES CHIP 8.2K 1/16W +-5% (0402) EF'               | 'CHIP0402'     | ''          | ''            | '20180212'
 '9.76K'      | '1%'      | '1/16W'  | '0402LF'  | 'CHIP'   | 'CS29762FB05'(!)        = 'End of Design' | 'Comp-Approve'     | 'CS29762FB05'           |'R0402'| '(R0402-0201)'                 | '9.76K'   | '1%'    | '1/16W'  | 'DISCRETE' | 'RES CHIP 9.76K 1/16W +-1%(0402)EF'                | 'CHIP0402'     | ''          | ''            | '20180212'
 '9.76K'      | '1%'      | '1/16W'  | '0402LF'  | 'EMPTY'  | 'CS29762FB05'(!)        = 'End of Design' | 'Comp-Approve'     | 'CS29762FB05'           |'R0402'| '(R0402-0201)'                 | '9.76K'   | '1%'    | '1/16W'  | 'IO'       | 'RES CHIP 9.76K 1/16W +-1%(0402)EF'                | 'CHIP0402'     | ''          | ''            | '20180212'
 '11.3K'      | '1%'      | '1/16W'  | '0402LF'  | 'CHIP'   | 'CS31132FB01'(!)        = 'End of Design' | 'Comp-Approve'     | 'CS31132FB01'           |'R0402'| '(R0402-0201)'                 | '11.3K'   | '1%'    | '1/16W'  | 'DISCRETE' | 'RES CHIP 11.3K 1/16W +-1%(0402)EF'                | 'CHIP0402'     | ''          | ''            | '20180212'
 '11.3K'      | '1%'      | '1/16W'  | '0402LF'  | 'EMPTY'  | 'CS31132FB01'(!)        = 'End of Design' | 'Comp-Approve'     | 'CS31132FB01'           |'R0402'| '(R0402-0201)'                 | '11.3K'   | '1%'    | '1/16W'  | 'IO'       | 'RES CHIP 11.3K 1/16W +-1%(0402)EF'                | 'CHIP0402'     | ''          | ''            | '20180212'
 '28K'        | '1%'      | '1/16W'  | '0402LF'  | 'CHIP'   | 'CS32802FB05'(!)        = 'End of Design' | 'Comp-Approve'     | 'CS32802FB05'           |'R0402'| '(R0402-0201)'                 | '28K'     | '1%'    | '1/16W'  | 'DISCRETE' | 'RES CHIP 28K 1/16W +-1%(0402)EF'                  | 'CHIP0402'     | ''          | ''            | '20180212'
 '28K'        | '1%'      | '1/16W'  | '0402LF'  | 'EMPTY'  | 'CS32802FB05'(!)        = 'End of Design' | 'Comp-Approve'     | 'CS32802FB05'           |'R0402'| '(R0402-0201)'                 | '28K'     | '1%'    | '1/16W'  | 'IO'       | 'RES CHIP 28K 1/16W +-1%(0402)EF'                  | 'CHIP0402'     | ''          | ''            | '20180212'
 '49.9K'      | '1%'      | '1/16W'  | '0402LF'  | 'CHIP'   | 'CS34992FB05'(!)        = 'End of Design' | 'Comp-Approve'     | 'CS34992FB05'           |'R0402'| '(R0402-0201)'                 | '49.9K'   | '1%'    | '1/16W'  | 'DISCRETE' | 'RES CHIP 49.9K 1/16W +-1%(0402)EF'                | 'CHIP0402'     | ''          | ''            | '20180212'
 '49.9K'      | '1%'      | '1/16W'  | '0402LF'  | 'EMPTY'  | 'CS34992FB05'(!)        = 'End of Design' | 'Comp-Approve'     | 'CS34992FB05'           |'R0402'| '(R0402-0201)'                 | '49.9K'   | '1%'    | '1/16W'  | 'IO'       | 'RES CHIP 49.9K 1/16W +-1%(0402)EF'                | 'CHIP0402'     | ''          | ''            | '20180212'
 '51K'        | '1%'      | '1/16W'  | '0402LF'  | 'CHIP'   | 'CS35102FB00'(!)        = 'End of Design' | 'Comp-Approve'     | 'CS35102FB00'           |'R0402'| '(R0402-0201)'                 | '51K'     | '1%'    | '1/16W'  | 'DISCRETE' | 'RES CHIP 51K 1/16W +-1%(0402)EF'                  | 'CHIP0402'     | ''          | ''            | '20180212'
 '51K'        | '1%'      | '1/16W'  | '0402LF'  | 'EMPTY'  | 'CS35102FB00'(!)        = 'End of Design' | 'Comp-Approve'     | 'CS35102FB00'           |'R0402'| '(R0402-0201)'                 | '51K'     | '1%'    | '1/16W'  | 'IO'       | 'RES CHIP 51K 1/16W +-1%(0402)EF'                  | 'CHIP0402'     | ''          | ''            | '20180212'
 '60.4K'      | '1%'      | '1/16W'  | '0402LF'  | 'CHIP'   | 'CS36042FB04'(!)        = 'End of Design' | 'Comp-Approve'     | 'CS36042FB04'           |'R0402'| '(R0402-0201)'                 | '60.4K'   | '1%'    | '1/16W'  | 'DISCRETE' | 'RES CHIP 60.4K 1/16W +-1%(0402)EF'                | 'CHIP0402'     | ''          | ''            | '20180212'
 '60.4K'      | '1%'      | '1/16W'  | '0402LF'  | 'EMPTY'  | 'CS36042FB04'(!)        = 'End of Design' | 'Comp-Approve'     | 'CS36042FB04'           |'R0402'| '(R0402-0201)'                 | '60.4K'   | '1%'    | '1/16W'  | 'IO'       | 'RES CHIP 60.4K 1/16W +-1%(0402)EF'                | 'CHIP0402'     | ''          | ''            | '20180212'
 '63.4K'      | '1%'      | '1/16W'  | '0402LF'  | 'CHIP'   | 'CS36342FB04'(!)        = 'End of Design' | 'Comp-Approve'     | 'CS36342FB04'           |'R0402'| '(R0402-0201)'                 | '63.4K'   | '1%'    | '1/16W'  | 'DISCRETE' | 'RES CHIP 63.4K 1/16W +-1%(0402)EF'                | 'CHIP0402'     | ''          | ''            | '20180212'
 '63.4K'      | '1%'      | '1/16W'  | '0402LF'  | 'EMPTY'  | 'CS36342FB04'(!)        = 'End of Design' | 'Comp-Approve'     | 'CS36342FB04'           |'R0402'| '(R0402-0201)'                 | '63.4K'   | '1%'    | '1/16W'  | 'IO'       | 'RES CHIP 63.4K 1/16W +-1%(0402)EF'                | 'CHIP0402'     | ''          | ''            | '20180212'
 '80.6K'      | '1%'      | '1/16W'  | '0402LF'  | 'CHIP'   | 'CS38062FB04'(!)        = 'End of Design' | 'Comp-Approve'     | 'CS38062FB04'           |'R0402'| '(R0402-0201)'                 | '80.6K'   | '1%'    | '1/16W'  | 'DISCRETE' | 'RES CHIP 80.6K 1/16W +-1%(0402)EF'                | 'CHIP0402'     | ''          | ''            | '20180212'
 '80.6K'      | '1%'      | '1/16W'  | '0402LF'  | 'EMPTY'  | 'CS38062FB04'(!)        = 'End of Design' | 'Comp-Approve'     | 'CS38062FB04'           |'R0402'| '(R0402-0201)'                 | '80.6K'   | '1%'    | '1/16W'  | 'IO'       | 'RES CHIP 80.6K 1/16W +-1%(0402)EF'                | 'CHIP0402'     | ''          | ''            | '20180212'
 '100K'       | '5%'      | '1/20W'  | '0201LF'  | 'CHIP'   | 'CS41001JE05'(!)        = 'End of Design' | 'Comp-Approve'     | 'CS41001JE05'           |'R0201'| '(SMR0201AW)'                  | '100K'    | '5%'    | '1/20W'  | 'DISCRETE' | 'RES CHIP 100K 1/20W +-5%(0201)EF'                 | 'CHIP0201'     | ''          | ''            | '20180212'
 '100K'       | '5%'      | '1/20W'  | '0201LF'  | 'EMPTY'  | 'CS41001JE05'(!)        = 'End of Design' | 'Comp-Approve'     | 'CS41001JE05'           |'R0201'| '(SMR0201AW)'                  | '100K'    | '5%'    | '1/20W'  | 'IO'       | 'RES CHIP 100K 1/20W +-5%(0201)EF'                 | 'CHIP0201'     | ''          | ''            | '20180212'
 '100K'       | '5%'      | '1/16W'  | '0402LF'  | 'CHIP'   | 'CS41002JB06'(!)        = 'End of Design' | 'Comp-Approve'     | 'CS41002JB06'           |'R0402'| '(R0402-0201)'                 | '100K'    | '5%'    | '1/16W'  | 'DISCRETE' | 'RES CHIP 100K 1/16W +-5%(0402)EF'                 | 'CHIP0402'     | ''          | ''            | '20180212'
 '100K'       | '5%'      | '1/16W'  | '0402LF'  | 'EMPTY'  | 'CS41002JB06'(!)        = 'End of Design' | 'Comp-Approve'     | 'CS41002JB06'           |'R0402'| '(R0402-0201)'                 | '100K'    | '5%'    | '1/16W'  | 'IO'       | 'RES CHIP 100K 1/16W +-5%(0402)EF'                 | 'CHIP0402'     | ''          | ''            | '20180212'
 '180K'       | '1%'      | '1/16W'  | '0402LF'  | 'CHIP'   | 'CS41802FB03'(!)        = 'End of Design' | 'Comp-Approve'     | 'CS41802FB03'           |'R0402'| '(R0402-0201)'                 | '180K'    | '1%'    | '1/16W'  | 'DISCRETE' | 'RES CHIP 180K 1/16W +-1%(0402)EF'                 | 'CHIP0402'     | ''          | ''            | '20180212'
 '180K'       | '1%'      | '1/16W'  | '0402LF'  | 'EMPTY'  | 'CS41802FB03'(!)        = 'End of Design' | 'Comp-Approve'     | 'CS41802FB03'           |'R0402'| '(R0402-0201)'                 | '180K'    | '1%'    | '1/16W'  | 'IO'       | 'RES CHIP 180K 1/16W +-1%(0402)EF'                 | 'CHIP0402'     | ''          | ''            | '20180212'
 '22'         | '1%'      | '1/16W'  | '0402LF'  | 'CHIP'   | 'CS02202FB02'(!)        = 'End of Design' | 'Comp-Approve'     | 'CS02202FB02'           |'R0402'| '(R0402-0201)'                 | '22'      | '1%'    | '1/16W'  | 'DISCRETE' | 'RES CHIP 22 1/16W +-1%(0402)EF'                   | 'CHIP0402'     | ''          | ''            | '20180212'
 '22'         | '1%'      | '1/16W'  | '0402LF'  | 'EMPTY'  | 'CS02202FB02'(!)        = 'End of Design' | 'Comp-Approve'     | 'CS02202FB02'           |'R0402'| '(R0402-0201)'                 | '22'      | '1%'    | '1/16W'  | 'IO'       | 'RES CHIP 22 1/16W +-1%(0402)EF'                   | 'CHIP0402'     | ''          | ''            | '20180212'
 '42.2'       | '1%'      | '1/16W'  | '0402LF'  | 'CHIP'   | 'CS04222FB05'(!)        = 'End of Design' | 'Comp-Approve'     | 'CS04222FB05'           |'R0402'| '(R0402-0201)'                 | '42.2'    | '1%'    | '1/16W'  | 'DISCRETE' | 'RES CHIP 42.2 1/16W +-1%(0402)EF'                 | 'CHIP0402'     | ''          | ''            | '20180212'
 '42.2'       | '1%'      | '1/16W'  | '0402LF'  | 'EMPTY'  | 'CS04222FB05'(!)        = 'End of Design' | 'Comp-Approve'     | 'CS04222FB05'           |'R0402'| '(R0402-0201)'                 | '42.2'    | '1%'    | '1/16W'  | 'IO'       | 'RES CHIP 42.2 1/16W +-1%(0402)EF'                 | 'CHIP0402'     | ''          | ''            | '20180212'
 '10K'        | '0.1%'    | '1/16W'  | '0402LF'  | 'CHIP'   | 'CS31002BB06'(!)        = 'End of Design' | 'Comp-Approve'     | 'CS31002BB06'           |'R0402'| '(R0402-0201)'                 | '10K'     | '0.1%'  | '1/16W'  | 'DISCRETE' | 'RES CHIP 10K 1/16W +-0.1%(0402)EF'                | 'CHIP0402'     | ''          | ''            | '20180212'
 '10K'        | '0.1%'    | '1/16W'  | '0402LF'  | 'EMPTY'  | 'CS31002BB06'(!)        = 'End of Design' | 'Comp-Approve'     | 'CS31002BB06'           |'R0402'| '(R0402-0201)'                 | '10K'     | '0.1%'  | '1/16W'  | 'IO'       | 'RES CHIP 10K 1/16W +-0.1%(0402)EF'                | 'CHIP0402'     | ''          | ''            | '20180212'
 '75K'        | '1%'      | '1/16W'  | '0402LF'  | 'CHIP'   | 'CS37502FB05'(!)        = 'End of Design' | 'Comp-Approve'     | 'CS37502FB05'           |'R0402'| '(R0402-0201)'                 | '75K'     | '1%'    | '1/16W'  | 'DISCRETE' | 'RES CHIP 75K 1/16W +-1%(0402)EF'                  | 'CHIP0402'     | ''          | ''            | '20180212'
 '75K'        | '1%'      | '1/16W'  | '0402LF'  | 'EMPTY'  | 'CS37502FB05'(!)        = 'End of Design' | 'Comp-Approve'     | 'CS37502FB05'           |'R0402'| '(R0402-0201)'                 | '75K'     | '1%'    | '1/16W'  | 'IO'       | 'RES CHIP 75K 1/16W +-1%(0402)EF'                  | 'CHIP0402'     | ''          | ''            | '20180212'
 '390K'       | '5%'      | '1/16W'  | '0402LF'  | 'CHIP'   | 'CS43902JB04'(!)        = 'End of Design' | 'Comp-Approve'     | 'CS43902JB04'           |'R0402'| '(R0402-0201)'                 | '390K'    | '5%'    | '1/16W'  | 'DISCRETE' | 'RES CHIP 390K 1/16W +-5%(0402)EF'                 | 'CHIP0402'     | ''          | ''            | '20180212'
 '390K'       | '5%'      | '1/16W'  | '0402LF'  | 'EMPTY'  | 'CS43902JB04'(!)        = 'End of Design' | 'Comp-Approve'     | 'CS43902JB04'           |'R0402'| '(R0402-0201)'                 | '390K'    | '5%'    | '1/16W'  | 'IO'       | 'RES CHIP 390K 1/16W +-5%(0402)EF'                 | 'CHIP0402'     | ''          | ''            | '20180212'
 '1M'         | '1%'      | '1/10W'  | '0603LF'  | 'CHIP'   | 'CS51003F903'(!)        = 'End of Design' | 'Comp-Approve'     | 'CS51003F903'           |'R0603'| '(SMR0603AW)'                  | '1M'      | '1%'    | '1/10W'  | 'DISCRETE' | 'RES CHIP 1M 1/10W +-1%(0603)EF'                   | 'CHIP0603'     | ''          | ''            | '20180212'
 '1M'         | '1%'      | '1/10W'  | '0603LF'  | 'EMPTY'  | 'CS51003F903'(!)        = 'End of Design' | 'Comp-Approve'     | 'CS51003F903'           |'R0603'| '(SMR0603AW)'                  | '1M'      | '1%'    | '1/10W'  | 'IO'       | 'RES CHIP 1M 1/10W +-1%(0603)EF'                   | 'CHIP0603'     | ''          | ''            | '20180212'
 '0'          | '5%'      | '1/16W'  | '0402LF'  | 'CHIP'   | 'CS00002JB13'(!)        = 'End of Design' | 'Comp-Approve'     | 'CS00002JB13'           |'R0402'| '(R0402-0201)'                 | '0'       | '5%'    | '1/16W'  | 'DISCRETE' | 'RES CHIP 0 1/16W +-5%(0402)EF'                    | 'CHIPR0402'    | ''          | ''            | '20180208'
 '0'          | '5%'      | '1/16W'  | '0402LF'  | 'EMPTY'  | 'CS00002JB13'(!)        = 'End of Design' | 'Comp-Approve'     | 'CS00002JB13'           |'R0402'| '(R0402-0201)'                 | '0'       | '5%'    | '1/16W'  | 'IO'       | 'RES CHIP 0 1/16W +-5%(0402)EF'                    | 'CHIPR0402'    | ''          | ''            | '20180208'
 '10'         | '1%'      | '1/16W'  | '0402LF'  | 'CHIP'   | 'CS01002FB07'(!)        = 'End of Design' | 'Comp-Approve'     | 'CS01002FB07'           |'R0402'| '(R0402-0201)'                 | '10'      | '1%'    | '1/16W'  | 'DISCRETE' | 'RES CHIP 10 1/16W +-1%(0402)EF'                   | 'CHIPR0402'    | ''          | ''            | '20180208'
 '10'         | '1%'      | '1/16W'  | '0402LF'  | 'EMPTY'  | 'CS01002FB07'(!)        = 'End of Design' | 'Comp-Approve'     | 'CS01002FB07'           |'R0402'| '(R0402-0201)'                 | '10'      | '1%'    | '1/16W'  | 'IO'       | 'RES CHIP 10 1/16W +-1%(0402)EF'                   | 'CHIPR0402'    | ''          | ''            | '20180208'
 '33.2'       | '1%'      | '1/16W'  | '0402LF'  | 'CHIP'   | 'CS03322FB03'(!)        = 'End of Design' | 'Comp-Approve'     | 'CS03322FB03'           |'R0402'| '(R0402-0201)'                 | '33.2'    | '1%'    | '1/16W'  | 'DISCRETE' | 'RES CHIP 33.2 1/16W +-1%(0402)EF'                 | 'CHIPR0402'    | ''          | ''            | '20180208'
 '33.2'       | '1%'      | '1/16W'  | '0402LF'  | 'EMPTY'  | 'CS03322FB03'(!)        = 'End of Design' | 'Comp-Approve'     | 'CS03322FB03'           |'R0402'| '(R0402-0201)'                 | '33.2'    | '1%'    | '1/16W'  | 'IO'       | 'RES CHIP 33.2 1/16W +-1%(0402)EF'                 | 'CHIPR0402'    | ''          | ''            | '20180208'
 '49.9'       | '1%'      | '1/16W'  | '0402LF'  | 'CHIP'   | 'CS04992FB07'(!)        = 'End of Design' | 'Comp-Approve'     | 'CS04992FB07'           |'R0402'| '(R0402-0201)'                 | '49.9'    | '1%'    | '1/16W'  | 'DISCRETE' | 'RES CHIP 49.9 1/16W +-1%(0402)EF'                 | 'CHIPR0402'    | ''          | ''            | '20180208'
 '49.9'       | '1%'      | '1/16W'  | '0402LF'  | 'EMPTY'  | 'CS04992FB07'(!)        = 'End of Design' | 'Comp-Approve'     | 'CS04992FB07'           |'R0402'| '(R0402-0201)'                 | '49.9'    | '1%'    | '1/16W'  | 'IO'       | 'RES CHIP 49.9 1/16W +-1%(0402)EF'                 | 'CHIPR0402'    | ''          | ''            | '20180208'
 '100'        | '1%'      | '1/16W'  | '0402LF'  | 'CHIP'   | 'CS11002FB07'(!)        = 'End of Design' | 'Comp-Approve'     | 'CS11002FB07'           |'R0402'| '(R0402-0201)'                 | '100'     | '1%'    | '1/16W'  | 'DISCRETE' | 'RES CHIP 100 1/16W +-1%(0402)EF'                  | 'CHIPR0402'    | ''          | ''            | '20180208'
 '100'        | '1%'      | '1/16W'  | '0402LF'  | 'EMPTY'  | 'CS11002FB07'(!)        = 'End of Design' | 'Comp-Approve'     | 'CS11002FB07'           |'R0402'| '(R0402-0201)'                 | '100'     | '1%'    | '1/16W'  | 'IO'       | 'RES CHIP 100 1/16W +-1%(0402)EF'                  | 'CHIPR0402'    | ''          | ''            | '20180208'
 '150'        | '1%'      | '1/16W'  | '0402LF'  | 'CHIP'   | 'CS11502FB07'(!)        = 'End of Design' | 'Comp-Approve'     | 'CS11502FB07'           |'R0402'| '(R0402-0201)'                 | '150'     | '1%'    | '1/16W'  | 'DISCRETE' | 'RES CHIP 150 1/16W +-1%(0402)EF'                  | 'CHIPR0402'    | ''          | ''            | '20180208'
 '150'        | '1%'      | '1/16W'  | '0402LF'  | 'EMPTY'  | 'CS11502FB07'(!)        = 'End of Design' | 'Comp-Approve'     | 'CS11502FB07'           |'R0402'| '(R0402-0201)'                 | '150'     | '1%'    | '1/16W'  | 'IO'       | 'RES CHIP 150 1/16W +-1%(0402)EF'                  | 'CHIPR0402'    | ''          | ''            | '20180208'
 '200'        | '1%'      | '1/16W'  | '0402LF'  | 'CHIP'   | 'CS12002FB06'(!)        = 'End of Design' | 'Comp-Approve'     | 'CS12002FB06'           |'R0402'| '(R0402-0201)'                 | '200'     | '1%'    | '1/16W'  | 'DISCRETE' | 'RES CHIP 200 1/16W +-1%(0402)EF'                  | 'CHIPR0402'    | ''          | ''            | '20180208'
 '200'        | '1%'      | '1/16W'  | '0402LF'  | 'EMPTY'  | 'CS12002FB06'(!)        = 'End of Design' | 'Comp-Approve'     | 'CS12002FB06'           |'R0402'| '(R0402-0201)'                 | '200'     | '1%'    | '1/16W'  | 'IO'       | 'RES CHIP 200 1/16W +-1%(0402)EF'                  | 'CHIPR0402'    | ''          | ''            | '20180208'
 '412'        | '1%'      | '1/16W'  | '0402LF'  | 'CHIP'   | 'CS14122FB04'(!)        = 'End of Design' | 'Comp-Approve'     | 'CS14122FB04'           |'R0402'| '(R0402-0201)'                 | '412'     | '1%'    | '1/16W'  | 'DISCRETE' | 'RES CHIP 412 1/16W +-1%(0402)EF'                  | 'CHIPR0402'    | ''          | ''            | '20180208'
 '412'        | '1%'      | '1/16W'  | '0402LF'  | 'EMPTY'  | 'CS14122FB04'(!)        = 'End of Design' | 'Comp-Approve'     | 'CS14122FB04'           |'R0402'| '(R0402-0201)'                 | '412'     | '1%'    | '1/16W'  | 'IO'       | 'RES CHIP 412 1/16W +-1%(0402)EF'                  | 'CHIPR0402'    | ''          | ''            | '20180208'
 '1K'         | '1%'      | '1/16W'  | '0402LF'  | 'CHIP'   | 'CS21002FB06'(!)        = 'End of Design' | 'Comp-Approve'     | 'CS21002FB06'           |'R0402'| '(R0402-0201)'                 | '1K'      | '1%'    | '1/16W'  | 'DISCRETE' | 'RES CHIP 1K 1/16W +-1%(0402)EF'                   | 'CHIPR0402'    | ''          | ''            | '20180208'
 '1K'         | '1%'      | '1/16W'  | '0402LF'  | 'EMPTY'  | 'CS21002FB06'(!)        = 'End of Design' | 'Comp-Approve'     | 'CS21002FB06'           |'R0402'| '(R0402-0201)'                 | '1K'      | '1%'    | '1/16W'  | 'IO'       | 'RES CHIP 1K 1/16W +-1%(0402)EF'                   | 'CHIPR0402'    | ''          | ''            | '20180208'
 '1.02K'      | '1%'      | '1/16W'  | '0402LF'  | 'CHIP'   | 'CS21022FB03'(!)        = 'End of Design' | 'Comp-Approve'     | 'CS21022FB03'           |'R0402'| '(R0402-0201)'                 | '1.02K'   | '1%'    | '1/16W'  | 'DISCRETE' | 'RES CHIP 1.02K 1/16W +-1%(0402)EF'                | 'CHIPR0402'    | ''          | ''            | '20180208'
 '1.02K'      | '1%'      | '1/16W'  | '0402LF'  | 'EMPTY'  | 'CS21022FB03'(!)        = 'End of Design' | 'Comp-Approve'     | 'CS21022FB03'           |'R0402'| '(R0402-0201)'                 | '1.02K'   | '1%'    | '1/16W'  | 'IO'       | 'RES CHIP 1.02K 1/16W +-1%(0402)EF'                | 'CHIPR0402'    | ''          | ''            | '20180208'
 '1.5K'       | '1%'      | '1/16W'  | '0402LF'  | 'CHIP'   | 'CS21502FB07'(!)        = 'End of Design' | 'Comp-Approve'     | 'CS21502FB07'           |'R0402'| '(R0402-0201)'                 | '1.5K'    | '1%'    | '1/16W'  | 'DISCRETE' | 'RES CHIP 1.5K 1/16W +-1%(0402)EF'                 | 'CHIPR0402'    | ''          | ''            | '20180208'
 '1.5K'       | '1%'      | '1/16W'  | '0402LF'  | 'EMPTY'  | 'CS21502FB07'(!)        = 'End of Design' | 'Comp-Approve'     | 'CS21502FB07'           |'R0402'| '(R0402-0201)'                 | '1.5K'    | '1%'    | '1/16W'  | 'IO'       | 'RES CHIP 1.5K 1/16W +-1%(0402)EF'                 | 'CHIPR0402'    | ''          | ''            | '20180208'
 '4.7K'       | '1%'      | '1/16W'  | '0402LF'  | 'CHIP'   | 'CS24702FB06'(!)        = 'End of Design' | 'Comp-Approve'     | 'CS24702FB06'           |'R0402'| '(R0402-0201)'                 | '4.7K'    | '1%'    | '1/16W'  | 'DISCRETE' | 'RES CHIP 4.7K 1/16W +-1%(0402)EF'                 | 'CHIPR0402'    | ''          | ''            | '20180208'
 '4.7K'       | '1%'      | '1/16W'  | '0402LF'  | 'EMPTY'  | 'CS24702FB06'(!)        = 'End of Design' | 'Comp-Approve'     | 'CS24702FB06'           |'R0402'| '(R0402-0201)'                 | '4.7K'    | '1%'    | '1/16W'  | 'IO'       | 'RES CHIP 4.7K 1/16W +-1%(0402)EF'                 | 'CHIPR0402'    | ''          | ''            | '20180208'
 '5.9K'       | '1%'      | '1/16W'  | '0402LF'  | 'CHIP'   | 'CS25902FB04'(!)        = 'End of Design' | 'Comp-Approve'     | 'CS25902FB04'           |'R0402'| '(R0402-0201)'                 | '5.9K'    | '1%'    | '1/16W'  | 'DISCRETE' | 'RES CHIP 5.9K 1/16W +-1%(0402)EF'                 | 'CHIPR0402'    | ''          | ''            | '20180208'
 '5.9K'       | '1%'      | '1/16W'  | '0402LF'  | 'EMPTY'  | 'CS25902FB04'(!)        = 'End of Design' | 'Comp-Approve'     | 'CS25902FB04'           |'R0402'| '(R0402-0201)'                 | '5.9K'    | '1%'    | '1/16W'  | 'IO'       | 'RES CHIP 5.9K 1/16W +-1%(0402)EF'                 | 'CHIPR0402'    | ''          | ''            | '20180208'
 '7.5K'       | '1%'      | '1/16W'  | '0402LF'  | 'CHIP'   | 'CS27502FB04'(!)        = 'End of Design' | 'Comp-Approve'     | 'CS27502FB04'           |'R0402'| '(R0402-0201)'                 | '7.5K'    | '1%'    | '1/16W'  | 'DISCRETE' | 'RES CHIP 7.5K 1/16W +-1%(0402)EF'                 | 'CHIPR0402'    | ''          | ''            | '20180208'
 '7.5K'       | '1%'      | '1/16W'  | '0402LF'  | 'EMPTY'  | 'CS27502FB04'(!)        = 'End of Design' | 'Comp-Approve'     | 'CS27502FB04'           |'R0402'| '(R0402-0201)'                 | '7.5K'    | '1%'    | '1/16W'  | 'IO'       | 'RES CHIP 7.5K 1/16W +-1%(0402)EF'                 | 'CHIPR0402'    | ''          | ''            | '20180208'
 '10K'        | '1%'      | '1/16W'  | '0402LF'  | 'CHIP'   | 'CS31002FB08'(!)        = 'End of Design' | 'Comp-Approve'     | 'CS31002FB08'           |'R0402'| '(R0402-0201)'                 | '10K'     | '1%'    | '1/16W'  | 'DISCRETE' | 'RES CHIP 10K 1/16W +-1%(0402)EF'                  | 'CHIPR0402'    | ''          | ''            | '20180208'
 '10K'        | '1%'      | '1/16W'  | '0402LF'  | 'EMPTY'  | 'CS31002FB08'(!)        = 'End of Design' | 'Comp-Approve'     | 'CS31002FB08'           |'R0402'| '(R0402-0201)'                 | '10K'     | '1%'    | '1/16W'  | 'IO'       | 'RES CHIP 10K 1/16W +-1%(0402)EF'                  | 'CHIPR0402'    | ''          | ''            | '20180208'
 '10K'        | '5%'      | '1/16W'  | '0402LF'  | 'CHIP'   | 'CS31002JB08'(!)        = 'End of Design' | 'Comp-Approve'     | 'CS31002JB08'           |'R0402'| '(R0402-0201)'                 | '10K'     | '5%'    | '1/16W'  | 'DISCRETE' | 'RES CHIP 10K 1/16W +-5%(0402)EF'                  | 'CHIPR0402'    | ''          | ''            | '20180208'
 '10K'        | '5%'      | '1/16W'  | '0402LF'  | 'EMPTY'  | 'CS31002JB08'(!)        = 'End of Design' | 'Comp-Approve'     | 'CS31002JB08'           |'R0402'| '(R0402-0201)'                 | '10K'     | '5%'    | '1/16W'  | 'IO'       | 'RES CHIP 10K 1/16W +-5%(0402)EF'                  | 'CHIPR0402'    | ''          | ''            | '20180208'
 '20K'        | '1%'      | '1/16W'  | '0402LF'  | 'CHIP'   | 'CS32002FB06'(!)        = 'End of Design' | 'Comp-Approve'     | 'CS32002FB06'           |'R0402'| '(R0402-0201)'                 | '20K'     | '1%'    | '1/16W'  | 'DISCRETE' | 'RES CHIP 20K 1/16W +-1%(0402)EF'                  | 'CHIPR0402'    | ''          | ''            | '20180208'
 '20K'        | '1%'      | '1/16W'  | '0402LF'  | 'EMPTY'  | 'CS32002FB06'(!)        = 'End of Design' | 'Comp-Approve'     | 'CS32002FB06'           |'R0402'| '(R0402-0201)'                 | '20K'     | '1%'    | '1/16W'  | 'IO'       | 'RES CHIP 20K 1/16W +-1%(0402)EF'                  | 'CHIPR0402'    | ''          | ''            | '20180208'
 '22.1K'      | '1%'      | '1/16W'  | '0402LF'  | 'CHIP'   | 'CS32212FB02'(!)        = 'End of Design' | 'Comp-Approve'     | 'CS32212FB02'           |'R0402'| '(R0402-0201)'                 | '22.1K'   | '1%'    | '1/16W'  | 'DISCRETE' | 'RES CHIP 22.1K 1/16W +-1%(0402)EF'                | 'CHIPR0402'    | ''          | ''            | '20180208'
 '22.1K'      | '1%'      | '1/16W'  | '0402LF'  | 'EMPTY'  | 'CS32212FB02'(!)        = 'End of Design' | 'Comp-Approve'     | 'CS32212FB02'           |'R0402'| '(R0402-0201)'                 | '22.1K'   | '1%'    | '1/16W'  | 'IO'       | 'RES CHIP 22.1K 1/16W +-1%(0402)EF'                | 'CHIPR0402'    | ''          | ''            | '20180208'
 '47K'        | '1%'      | '1/16W'  | '0402LF'  | 'CHIP'   | 'CS34702FB01'(!)        = 'End of Design' | 'Comp-Approve'     | 'CS34702FB01'           |'R0402'| '(R0402-0201)'                 | '47K'     | '1%'    | '1/16W'  | 'DISCRETE' | 'RES CHIP 47K 1/16W +-1%(0402)EF'                  | 'CHIPR0402'    | ''          | ''            | '20180208'
 '47K'        | '1%'      | '1/16W'  | '0402LF'  | 'EMPTY'  | 'CS34702FB01'(!)        = 'End of Design' | 'Comp-Approve'     | 'CS34702FB01'           |'R0402'| '(R0402-0201)'                 | '47K'     | '1%'    | '1/16W'  | 'IO'       | 'RES CHIP 47K 1/16W +-1%(0402)EF'                  | 'CHIPR0402'    | ''          | ''            | '20180208'
 '52.3K'      | '1%'      | '1/16W'  | '0402LF'  | 'CHIP'   | 'CS35232FB02'(!)        = 'End of Design' | 'Comp-Approve'     | 'CS35232FB02'           |'R0402'| '(R0402-0201)'                 | '52.3K'   | '1%'    | '1/16W'  | 'DISCRETE' | 'RES CHIP 52.3K 1/16W +-1%(0402)EF'                | 'CHIPR0402'    | ''          | ''            | '20180208'
 '52.3K'      | '1%'      | '1/16W'  | '0402LF'  | 'EMPTY'  | 'CS35232FB02'(!)        = 'End of Design' | 'Comp-Approve'     | 'CS35232FB02'           |'R0402'| '(R0402-0201)'                 | '52.3K'   | '1%'    | '1/16W'  | 'IO'       | 'RES CHIP 52.3K 1/16W +-1%(0402)EF'                | 'CHIPR0402'    | ''          | ''            | '20180208'
 '97.6K'      | '1%'      | '1/16W'  | '0402LF'  | 'CHIP'   | 'CS39762FB02'(!)        = 'End of Design' | 'Comp-Approve'     | 'CS39762FB02'           |'R0402'| '(R0402-0201)'                 | '97.6K'   | '1%'    | '1/16W'  | 'DISCRETE' | 'RES CHIP 97.6K 1/16W +-1%(0402)EF'                | 'CHIPR0402'    | ''          | ''            | '20180208'
 '97.6K'      | '1%'      | '1/16W'  | '0402LF'  | 'EMPTY'  | 'CS39762FB02'(!)        = 'End of Design' | 'Comp-Approve'     | 'CS39762FB02'           |'R0402'| '(R0402-0201)'                 | '97.6K'   | '1%'    | '1/16W'  | 'IO'       | 'RES CHIP 97.6K 1/16W +-1%(0402)EF'                | 'CHIPR0402'    | ''          | ''            | '20180208'
 '100K'       | '1%'      | '1/16W'  | '0402LF'  | 'CHIP'   | 'CS41002FB09'(!)        = 'End of Design' | 'Comp-Approve'     | 'CS41002FB09'           |'R0402'| '(R0402-0201)'                 | '100K'    | '1%'    | '1/16W'  | 'DISCRETE' | 'RES CHIP 100K 1/16W +-1%(0402)EF'                 | 'CHIPR0402'    | ''          | ''            | '20180208'
 '100K'       | '1%'      | '1/16W'  | '0402LF'  | 'EMPTY'  | 'CS41002FB09'(!)        = 'End of Design' | 'Comp-Approve'     | 'CS41002FB09'           |'R0402'| '(R0402-0201)'                 | '100K'    | '1%'    | '1/16W'  | 'IO'       | 'RES CHIP 100K 1/16W +-1%(0402)EF'                 | 'CHIPR0402'    | ''          | ''            | '20180208'
 '130K'       | '1%'      | '1/16W'  | '0402LF'  | 'CHIP'   | 'CS41302FB05'(!)        = 'End of Design' | 'Comp-Release Qty' | 'CS41302FB05'           |'R0402'| '(R0402-0201)'                 | '130K'    | '1%'    | '1/16W'  | 'DISCRETE' | 'RES CHIP 130K 1/16W +-1%(0402)EF'                 | 'CHIPR0402'    | ''          | ''            | '20180208'
 '130K'       | '1%'      | '1/16W'  | '0402LF'  | 'EMPTY'  | 'CS41302FB05'(!)        = 'End of Design' | 'Comp-Release Qty' | 'CS41302FB05'           |'R0402'| '(R0402-0201)'                 | '130K'    | '1%'    | '1/16W'  | 'IO'       | 'RES CHIP 130K 1/16W +-1%(0402)EF'                 | 'CHIPR0402'    | ''          | ''            | '20180208'
 '147K'       | '1%'      | '1/16W'  | '0402LF'  | 'CHIP'   | 'CS41472FB03'(!)        = 'End of Design' | 'Comp-Approve'     | 'CS41472FB03'           |'R0402'| '(R0402-0201)'                 | '147K'    | '1%'    | '1/16W'  | 'DISCRETE' | 'RES CHIP 147K 1/16W +-1%(0402)EF'                 | 'CHIPR0402'    | ''          | ''            | '20180208'
 '147K'       | '1%'      | '1/16W'  | '0402LF'  | 'EMPTY'  | 'CS41472FB03'(!)        = 'End of Design' | 'Comp-Approve'     | 'CS41472FB03'           |'R0402'| '(R0402-0201)'                 | '147K'    | '1%'    | '1/16W'  | 'IO'       | 'RES CHIP 147K 1/16W +-1%(0402)EF'                 | 'CHIPR0402'    | ''          | ''            | '20180208'
 '154K'       | '1%'      | '1/16W'  | '0402LF'  | 'CHIP'   | 'CS41542FB05'(!)        = 'End of Design' | 'Comp-Approve'     | 'CS41542FB05'           |'R0402'| '(R0402-0201)'                 | '154K'    | '1%'    | '1/16W'  | 'DISCRETE' | 'RES CHIP 154K 1/16W +-1%(0402)EF'                 | 'CHIPR0402'    | ''          | ''            | '20180208'
 '154K'       | '1%'      | '1/16W'  | '0402LF'  | 'EMPTY'  | 'CS41542FB05'(!)        = 'End of Design' | 'Comp-Approve'     | 'CS41542FB05'           |'R0402'| '(R0402-0201)'                 | '154K'    | '1%'    | '1/16W'  | 'IO'       | 'RES CHIP 154K 1/16W +-1%(0402)EF'                 | 'CHIPR0402'    | ''          | ''            | '20180208'
 '200K'       | '1%'      | '1/16W'  | '0402LF'  | 'CHIP'   | 'CS42002FB05'(!)        = 'End of Design' | 'Comp-Approve'     | 'CS42002FB05'           |'R0402'| '(R0402-0201)'                 | '200K'    | '1%'    | '1/16W'  | 'DISCRETE' | 'RES CHIP 200K 1/16W +-1%(0402)EF'                 | 'CHIPR0402'    | ''          | ''            | '20180208'
 '200K'       | '1%'      | '1/16W'  | '0402LF'  | 'EMPTY'  | 'CS42002FB05'(!)        = 'End of Design' | 'Comp-Approve'     | 'CS42002FB05'           |'R0402'| '(R0402-0201)'                 | '200K'    | '1%'    | '1/16W'  | 'IO'       | 'RES CHIP 200K 1/16W +-1%(0402)EF'                 | 'CHIPR0402'    | ''          | ''            | '20180208'
 '267K'       | '1%'      | '1/16W'  | '0402LF'  | 'CHIP'   | 'CS42672FB03'(!)        = 'End of Design' | 'Comp-Approve'     | 'CS42672FB03'           |'R0402'| '(R0402-0201)'                 | '267K'    | '1%'    | '1/16W'  | 'DISCRETE' | 'RES CHIP 267K 1/16W +-1%(0402)EF'                 | 'CHIPR0402'    | ''          | ''            | '20180208'
 '267K'       | '1%'      | '1/16W'  | '0402LF'  | 'EMPTY'  | 'CS42672FB03'(!)        = 'End of Design' | 'Comp-Approve'     | 'CS42672FB03'           |'R0402'| '(R0402-0201)'                 | '267K'    | '1%'    | '1/16W'  | 'IO'       | 'RES CHIP 267K 1/16W +-1%(0402)EF'                 | 'CHIPR0402'    | ''          | ''            | '20180208'
 '0'          | '5%'      | '1/10W'  | '0603LF'  | 'CHIP'   | 'CS00003J910'(!)        = 'End of Design' | 'Comp-Approve'     | 'CS00003J910'           |'R0603'| '(SMR0603AW)'                  | '0'       | '5%'    | '1/16W'  | 'DISCRETE' | 'RES CHIP 0 1/10W +-5% (0603)EF'                   | 'CHIPR0603'    | ''          | ''            | '20180208'
 '0'          | '5%'      | '1/10W'  | '0603LF'  | 'EMPTY'  | 'CS00003J910'(!)        = 'End of Design' | 'Comp-Approve'     | 'CS00003J910'           |'R0603'| '(SMR0603AW)'                  | '0'       | '5%'    | '1/16W'  | 'IO'       | 'RES CHIP 0 1/10W +-5% (0603)EF'                   | 'CHIPR0603'    | ''          | ''            | '20180208'
 '200K'       | '0.1%'    | '1/10W'  | '0603LF'  | 'CHIP'   | 'CS42003B902'(!)        = 'End of Design' | 'Comp-Approve'     | 'CS42003B902'           |'R0603_H24'| '(SMR0603AW)'                  | '200K'    | '0.1%'  | '1/10W'  | 'DISCRETE' | 'RES CHIP 200K 1/10W +-0.1%(0603)EF'               | 'CHIPR0603'    | ''          | ''            | '20180213'
 '200K'       | '0.1%'    | '1/10W'  | '0603LF'  | 'EMPTY'  | 'CS42003B902'(!)        = 'End of Design' | 'Comp-Approve'     | 'CS42003B902'           |'R0603_H24'| '(SMR0603AW)'                  | '200K'    | '0.1%'  | '1/10W'  | 'IO'       | 'RES CHIP 200K 1/10W +-0.1%(0603)EF'               | 'CHIPR0603'    | ''          | ''            | '20180213'
 '1'          | '5'       | '1/8W'   | '0805LF'  | 'CHIP'   | 'CS-1004JA02'(!)        = ''              | ''                 | 'CS-1004JA02'           |'R0805_H26'| '(SMR0805AW)'                  | '1'       | '5%'    | '1/8W'   | 'DISCRETE' | 'RES CHIP 1 1/8W +-5%(0805)EF'                     | 'CHIPR0805'    | ''          | ''            | '20180213'
 '1'          | '5'       | '1/8W'   | '0805LF'  | 'EMPTY'  | 'CS-1004JA02'(!)        = ''              | ''                 | 'CS-1004JA02'           |'R0805_H26'| '(SMR0805AW)'                  | '1'       | '5%'    | '1/8W'   | 'IO'       | 'RES CHIP 1 1/8W +-5%(0805)EF'                     | 'CHIPR0805'    | ''          | ''            | '20180213'
 '0.002'      | '1%'      | '2W'     | '2512LF'  | 'CHIP'   | 'CS+002AFR06'(!)        = 'End of Design' | 'Comp-Approve'     | 'CS+002AFR06'           |'R2512XS'| '(SMR2512AW)'                  | '0.002'   | '1%'    | '2W'     | 'DISCRETE' | 'RES CHIP 0.002 2W +-1%(2512)EF'                   | 'CHIPR2512'    | ''          | ''            | '20180213'
 '0.002'      | '1%'      | '2W'     | '2512LF'  | 'EMPTY'  | 'CS+002AFR06'(!)        = 'End of Design' | 'Comp-Approve'     | 'CS+002AFR06'           |'R2512XS'| '(SMR2512AW)'                  | '0.002'   | '1%'    | '2W'     | 'IO'       | 'RES CHIP 0.002 2W +-1%(2512)EF'                   | 'CHIPR2512'    | ''          | ''            | '20180213'
 '20'         | '1%'      | '1/16W'  | '0402LF'  | 'CHIP'   | 'CS02002FB03'(!)        = 'End of Design' | 'Comp-Approve'     | 'CS02002FB03'           |'R0402'| '(R0402-0201)'                 | '20'      | '1%'    | '1/16W'  | 'DISCRETE' | 'RES CHIP 20 1/16W +-1%(0402)EF'                   | 'CHIPR0402'    | ''          | ''            | '20180221'
 '20'         | '1%'      | '1/16W'  | '0402LF'  | 'EMPTY'  | 'CS02002FB03'(!)        = 'End of Design' | 'Comp-Approve'     | 'CS02002FB03'           |'R0402'| '(R0402-0201)'                 | '20'      | '1%'    | '1/16W'  | 'IO'       | 'RES CHIP 20 1/16W +-1%(0402)EF'                   | 'CHIPR0402'    | ''          | ''            | '20180221'
 '22.1'       | '1%'      | '1/16W'  | '0402LF'  | 'CHIP'   | 'CS02212FB02'(!)        = 'End of Design' | 'Comp-Approve'     | 'CS02212FB02'           |'R0402'| '(R0402-0201)'                 | '22.1'    | '1%'    | '1/16W'  | 'DISCRETE' | 'RES CHIP 22.1 1/16W +-1%(0402)EF'                 | 'CHIPR0402'    | ''          | ''            | '20180221'
 '22.1'       | '1%'      | '1/16W'  | '0402LF'  | 'EMPTY'  | 'CS02212FB02'(!)        = 'End of Design' | 'Comp-Approve'     | 'CS02212FB02'           |'R0402'| '(R0402-0201)'                 | '22.1'    | '1%'    | '1/16W'  | 'IO'       | 'RES CHIP 22.1 1/16W +-1%(0402)EF'                 | 'CHIPR0402'    | ''          | ''            | '20180221'
 '27.4'       | '1%'      | '1/16W'  | '0402LF'  | 'CHIP'   | 'CS02742FB03'(!)        = 'End of Design' | 'Comp-Release Qty' | 'CS02742FB03'           |'R0402'| '(R0402-0201)'                 | '27.4'    | '1%'    | '1/16W'  | 'DISCRETE' | 'RES CHIP 27.4 1/16W +-1%(0402)EF'                 | 'CHIPR0402'    | ''          | ''            | '20180221'
 '27.4'       | '1%'      | '1/16W'  | '0402LF'  | 'EMPTY'  | 'CS02742FB03'(!)        = 'End of Design' | 'Comp-Release Qty' | 'CS02742FB03'           |'R0402'| '(R0402-0201)'                 | '27.4'    | '1%'    | '1/16W'  | 'IO'       | 'RES CHIP 27.4 1/16W +-1%(0402)EF'                 | 'CHIPR0402'    | ''          | ''            | '20180221'
 '47'         | '1%'      | '1/16W'  | '0402LF'  | 'CHIP'   | 'CS04702FB03'(!)        = 'End of Design' | 'Comp-Approve'     | 'CS04702FB03'           |'R0402'| '(R0402-0201)'                 | '47'      | '1%'    | '1/16W'  | 'DISCRETE' | 'RES CHIP 47 1/16W +-1% (0402)EF'                  | 'CHIPR0402'    | ''          | ''            | '20180221'
 '47'         | '1%'      | '1/16W'  | '0402LF'  | 'EMPTY'  | 'CS04702FB03'(!)        = 'End of Design' | 'Comp-Approve'     | 'CS04702FB03'           |'R0402'| '(R0402-0201)'                 | '47'      | '1%'    | '1/16W'  | 'IO'       | 'RES CHIP 47 1/16W +-1% (0402)EF'                  | 'CHIPR0402'    | ''          | ''            | '20180221'
 '60.4'       | '1%'      | '1/16W'  | '0402LF'  | 'CHIP'   | 'CS06042FB03'(!)        = 'End of Design' | 'Comp-Approve'     | 'CS06042FB03'           |'R0402'| '(R0402-0201)'                 | '60.4'    | '1%'    | '1/16W'  | 'DISCRETE' | 'RES CHIP 60.4 1/16W +-1%(0402)EF'                 | 'CHIPR0402'    | ''          | ''            | '20180221'
 '60.4'       | '1%'      | '1/16W'  | '0402LF'  | 'EMPTY'  | 'CS06042FB03'(!)        = 'End of Design' | 'Comp-Approve'     | 'CS06042FB03'           |'R0402'| '(R0402-0201)'                 | '60.4'    | '1%'    | '1/16W'  | 'IO'       | 'RES CHIP 60.4 1/16W +-1%(0402)EF'                 | 'CHIPR0402'    | ''          | ''            | '20180221'
 '75'         | '1%'      | '1/16W'  | '0402LF'  | 'CHIP'   | 'CS07502FB04'(!)        = 'End of Design' | 'Comp-Approve'     | 'CS07502FB04'           |'R0402'| '(R0402-0201)'                 | '75'      | '1%'    | '1/16W'  | 'DISCRETE' | 'RES CHIP 75 1/16W +-1%(0402)EF'                   | 'CHIPR0402'    | ''          | ''            | '20180221'
 '75'         | '1%'      | '1/16W'  | '0402LF'  | 'EMPTY'  | 'CS07502FB04'(!)        = 'End of Design' | 'Comp-Approve'     | 'CS07502FB04'           |'R0402'| '(R0402-0201)'                 | '75'      | '1%'    | '1/16W'  | 'IO'       | 'RES CHIP 75 1/16W +-1%(0402)EF'                   | 'CHIPR0402'    | ''          | ''            | '20180221'
 '113'        | '1%'      | '1/16W'  | '0402LF'  | 'CHIP'   | 'CS11132FB02'(!)        = 'End of Design' | 'Comp-Approve'     | 'CS11132FB02'           |'R0402'| '(R0402-0201)'                 | '113'     | '1%'    | '1/16W'  | 'DISCRETE' | 'RES CHIP 113 1/16W +-1%(0402)EF'                  | 'CHIPR0402'    | ''          | ''            | '20180221'
 '113'        | '1%'      | '1/16W'  | '0402LF'  | 'EMPTY'  | 'CS11132FB02'(!)        = 'End of Design' | 'Comp-Approve'     | 'CS11132FB02'           |'R0402'| '(R0402-0201)'                 | '113'     | '1%'    | '1/16W'  | 'IO'       | 'RES CHIP 113 1/16W +-1%(0402)EF'                  | 'CHIPR0402'    | ''          | ''            | '20180221'
 '130'        | '1%'      | '1/16W'  | '0402LF'  | 'CHIP'   | 'CS11302FB03'(!)        = 'End of Design' | 'Comp-Approve'     | 'CS11302FB03'           |'R0402'| '(R0402-0201)'                 | '130'     | '1%'    | '1/16W'  | 'DISCRETE' | 'RES CHIP 130 1/16W +-1%(0402)EF'                  | 'CHIPR0402'    | ''          | ''            | '20180221'
 '130'        | '1%'      | '1/16W'  | '0402LF'  | 'EMPTY'  | 'CS11302FB03'(!)        = 'End of Design' | 'Comp-Approve'     | 'CS11302FB03'           |'R0402'| '(R0402-0201)'                 | '130'     | '1%'    | '1/16W'  | 'IO'       | 'RES CHIP 130 1/16W +-1%(0402)EF'                  | 'CHIPR0402'    | ''          | ''            | '20180221'
 '169'        | '1%'      | '1/16W'  | '0402LF'  | 'CHIP'   | 'CS11692FB01'(!)        = 'End of Design' | 'Comp-Approve'     | 'CS11692FB01'           |'R0402'| '(R0402-0201)'                 | '169'     | '1%'    | '1/16W'  | 'DISCRETE' | 'RES CHIP 169 1/16W +-1%(0402)EF'                  | 'CHIPR0402'    | ''          | ''            | '20180221'
 '169'        | '1%'      | '1/16W'  | '0402LF'  | 'EMPTY'  | 'CS11692FB01'(!)        = 'End of Design' | 'Comp-Approve'     | 'CS11692FB01'           |'R0402'| '(R0402-0201)'                 | '169'     | '1%'    | '1/16W'  | 'IO'       | 'RES CHIP 169 1/16W +-1%(0402)EF'                  | 'CHIPR0402'    | ''          | ''            | '20180221'
 '220'        | '0.1%'    | '1/16W'  | '0402LF'  | 'CHIP'   | 'CS12202BB00'(!)        = 'End of Design' | 'Comp-Approve'     | 'CS12202BB00'           |'R0402'| '(R0402-0201)'                 | '220'     | '0.1%'  | '1/16W'  | 'DISCRETE' | 'RES CHIP 220 1/16W +-0.1%(0402)EF'                | 'CHIPR0402'    | ''          | ''            | '20180221'
 '220'        | '0.1%'    | '1/16W'  | '0402LF'  | 'EMPTY'  | 'CS12202BB00'(!)        = 'End of Design' | 'Comp-Approve'     | 'CS12202BB00'           |'R0402'| '(R0402-0201)'                 | '220'     | '0.1%'  | '1/16W'  | 'IO'       | 'RES CHIP 220 1/16W +-0.1%(0402)EF'                | 'CHIPR0402'    | ''          | ''            | '20180221'
 '240'        | '1%'      | '1/16W'  | '0402LF'  | 'CHIP'   | 'CS12402FB01'(!)        = 'End of Design' | 'Comp-Approve'     | 'CS12402FB01'           |'R0402'| '(R0402-0201)'                 | '240'     | '1%'    | '1/16W'  | 'DISCRETE' | 'RES CHIP 240 1/16W +-1%(0402)EF'                  | 'CHIPR0402'    | ''          | ''            | '20180221'
 '240'        | '1%'      | '1/16W'  | '0402LF'  | 'EMPTY'  | 'CS12402FB01'(!)        = 'End of Design' | 'Comp-Approve'     | 'CS12402FB01'           |'R0402'| '(R0402-0201)'                 | '240'     | '1%'    | '1/16W'  | 'IO'       | 'RES CHIP 240 1/16W +-1%(0402)EF'                  | 'CHIPR0402'    | ''          | ''            | '20180221'
 '332'        | '1%'      | '1/16W'  | '0402LF'  | 'CHIP'   | 'CS13322FB05'(!)        = 'End of Design' | 'Comp-Approve'     | 'CS13322FB05'           |'R0402'| '(R0402-0201)'                 | '332'     | '1%'    | '1/16W'  | 'DISCRETE' | 'RES CHIP 332 1/16W +-1%(0402)EF'                  | 'CHIPR0402'    | ''          | ''            | '20180221'
 '332'        | '1%'      | '1/16W'  | '0402LF'  | 'EMPTY'  | 'CS13322FB05'(!)        = 'End of Design' | 'Comp-Approve'     | 'CS13322FB05'           |'R0402'| '(R0402-0201)'                 | '332'     | '1%'    | '1/16W'  | 'IO'       | 'RES CHIP 332 1/16W +-1%(0402)EF'                  | 'CHIPR0402'    | ''          | ''            | '20180221'
 '348'        | '1%'      | '1/16W'  | '0402LF'  | 'CHIP'   | 'CS13482FB02'(!)        = 'End of Design' | 'Comp-Approve'     | 'CS13482FB02'           |'R0402'| '(R0402-0201)'                 | '348'     | '1%'    | '1/16W'  | 'DISCRETE' | 'RES CHIP 348 1/16W +-1%(0402)EF'                  | 'CHIPR0402'    | ''          | ''            | '20180221'
 '348'        | '1%'      | '1/16W'  | '0402LF'  | 'EMPTY'  | 'CS13482FB02'(!)        = 'End of Design' | 'Comp-Approve'     | 'CS13482FB02'           |'R0402'| '(R0402-0201)'                 | '348'     | '1%'    | '1/16W'  | 'IO'       | 'RES CHIP 348 1/16W +-1%(0402)EF'                  | 'CHIPR0402'    | ''          | ''            | '20180221'
 '402'        | '1%'      | '1/16W'  | '0402LF'  | 'CHIP'   | 'CS14022FB02'(!)        = 'End of Design' | 'Comp-Approve'     | 'CS14022FB02'           |'R0402'| '(R0402-0201)'                 | '402'     | '1%'    | '1/16W'  | 'DISCRETE' | 'RES CHIP 402 1/16W +-1%(0402)EF'                  | 'CHIPR0402'    | ''          | ''            | '20180221'
 '402'        | '1%'      | '1/16W'  | '0402LF'  | 'EMPTY'  | 'CS14022FB02'(!)        = 'End of Design' | 'Comp-Approve'     | 'CS14022FB02'           |'R0402'| '(R0402-0201)'                 | '402'     | '1%'    | '1/16W'  | 'IO'       | 'RES CHIP 402 1/16W +-1%(0402)EF'                  | 'CHIPR0402'    | ''          | ''            | '20180221'
 '475'        | '1%'      | '1/16W'  | '0402LF'  | 'CHIP'   | 'CS14752FB04'(!)        = 'End of Design' | 'Comp-Approve'     | 'CS14752FB04'           |'R0402'| '(R0402-0201)'                 | '475'     | '1%'    | '1/16W'  | 'DISCRETE' | 'RES CHIP 475 1/16W +-1%(0402)EF'                  | 'CHIPR0402'    | ''          | ''            | '20180221'
 '475'        | '1%'      | '1/16W'  | '0402LF'  | 'EMPTY'  | 'CS14752FB04'(!)        = 'End of Design' | 'Comp-Approve'     | 'CS14752FB04'           |'R0402'| '(R0402-0201)'                 | '475'     | '1%'    | '1/16W'  | 'IO'       | 'RES CHIP 475 1/16W +-1%(0402)EF'                  | 'CHIPR0402'    | ''          | ''            | '20180221'
 '499'        | '1%'      | '1/16W'  | '0402LF'  | 'CHIP'   | 'CS14992FB06'(!)        = 'End of Design' | 'Comp-Approve'     | 'CS14992FB06'           |'R0402'| '(R0402-0201)'                 | '499'     | '1%'    | '1/16W'  | 'DISCRETE' | 'RES CHIP 499 1/16W +-1%(0402)EF'                  | 'CHIPR0402'    | ''          | ''            | '20180221'
 '499'        | '1%'      | '1/16W'  | '0402LF'  | 'EMPTY'  | 'CS14992FB06'(!)        = 'End of Design' | 'Comp-Approve'     | 'CS14992FB06'           |'R0402'| '(R0402-0201)'                 | '499'     | '1%'    | '1/16W'  | 'IO'       | 'RES CHIP 499 1/16W +-1%(0402)EF'                  | 'CHIPR0402'    | ''          | ''            | '20180221'
 '511'        | '1%'      | '1/16W'  | '0402LF'  | 'CHIP'   | 'CS15112FB03'(!)        = 'End of Design' | 'Comp-Approve'     | 'CS15112FB03'           |'R0402'| '(R0402-0201)'                 | '511'     | '1%'    | '1/16W'  | 'DISCRETE' | 'RES CHIP 511 1/16W +-1%(0402)EF'                  | 'CHIPR0402'    | ''          | ''            | '20180221'
 '511'        | '1%'      | '1/16W'  | '0402LF'  | 'EMPTY'  | 'CS15112FB03'(!)        = 'End of Design' | 'Comp-Approve'     | 'CS15112FB03'           |'R0402'| '(R0402-0201)'                 | '511'     | '1%'    | '1/16W'  | 'IO'       | 'RES CHIP 511 1/16W +-1%(0402)EF'                  | 'CHIPR0402'    | ''          | ''            | '20180221'
 '665'        | '1%'      | '1/16W'  | '0402LF'  | 'CHIP'   | 'CS16652FB00'(!)        = 'End of Design' | 'Comp-Approve'     | 'CS16652FB00'           |'R0402'| '(R0402-0201)'                 | '665'     | '1%'    | '1/16W'  | 'DISCRETE' | 'RES CHIP 665 1/16W +-1%(0402)EF'                  | 'CHIPR0402'    | ''          | ''            | '20180221'
 '665'        | '1%'      | '1/16W'  | '0402LF'  | 'EMPTY'  | 'CS16652FB00'(!)        = 'End of Design' | 'Comp-Approve'     | 'CS16652FB00'           |'R0402'| '(R0402-0201)'                 | '665'     | '1%'    | '1/16W'  | 'IO'       | 'RES CHIP 665 1/16W +-1%(0402)EF'                  | 'CHIPR0402'    | ''          | ''            | '20180221'
 '845'        | '1%'      | '1/16W'  | '0402LF'  | 'CHIP'   | 'CS18452FB01'(!)        = 'End of Design' | 'Comp-Approve'     | 'CS18452FB01'           |'R0402'| '(R0402-0201)'                 | '845'     | '1%'    | '1/16W'  | 'DISCRETE' | 'RES CHIP 845 1/16W +-1%(0402)EF'                  | 'CHIPR0402'    | ''          | ''            | '20180221'
 '845'        | '1%'      | '1/16W'  | '0402LF'  | 'EMPTY'  | 'CS18452FB01'(!)        = 'End of Design' | 'Comp-Approve'     | 'CS18452FB01'           |'R0402'| '(R0402-0201)'                 | '845'     | '1%'    | '1/16W'  | 'IO'       | 'RES CHIP 845 1/16W +-1%(0402)EF'                  | 'CHIPR0402'    | ''          | ''            | '20180221'
 '2'          | '1%'      | '1/16W'  | '0402LF'  | 'CHIP'   | 'CS-2002FB02'(!)        = 'End of Design' | 'Comp-Approve'     | 'CS-2002FB02'           |'R0402'| '(R0402-0201)'                 | '2'       | '1%'    | '1/16W'  | 'DISCRETE' | 'RES CHIP 2 1/16W +-1%(0402)EF'                    | 'CHIPR0402'    | ''          | ''            | '20180221'
 '2'          | '1%'      | '1/16W'  | '0402LF'  | 'EMPTY'  | 'CS-2002FB02'(!)        = 'End of Design' | 'Comp-Approve'     | 'CS-2002FB02'           |'R0402'| '(R0402-0201)'                 | '2'       | '1%'    | '1/16W'  | 'IO'       | 'RES CHIP 2 1/16W +-1%(0402)EF'                    | 'CHIPR0402'    | ''          | ''            | '20180221'
 '1K'         | '0.1%'    | '1/16W'  | '0402LF'  | 'CHIP'   | 'CS21002BB05'(!)        = 'End of Design' | 'Comp-Approve'     | 'CS21002BB05'           |'R0402'| '(R0402-0201)'                 | '1K'      | '0.1%'  | '1/16W'  | 'DISCRETE' | 'RES CHIP 1K 1/16W +-0.1%(0402)EF'                 | 'CHIPR0402'    | ''          | ''            | '20180221'
 '1K'         | '0.1%'    | '1/16W'  | '0402LF'  | 'EMPTY'  | 'CS21002BB05'(!)        = 'End of Design' | 'Comp-Approve'     | 'CS21002BB05'           |'R0402'| '(R0402-0201)'                 | '1K'      | '0.1%'  | '1/16W'  | 'IO'       | 'RES CHIP 1K 1/16W +-0.1%(0402)EF'                 | 'CHIPR0402'    | ''          | ''            | '20180221'
 '1.21K'      | '1%'      | '1/16W'  | '0402LF'  | 'CHIP'   | 'CS21212FB05'(!)        = 'End of Design' | 'Comp-Approve'     | 'CS21212FB05'           |'R0402'| '(R0402-0201)'                 | '1.21K'   | '1%'    | '1/16W'  | 'DISCRETE' | 'RES CHIP 1.21K 1/16W +-1%(0402)EF'                | 'CHIPR0402'    | ''          | ''            | '20180221'
 '1.21K'      | '1%'      | '1/16W'  | '0402LF'  | 'EMPTY'  | 'CS21212FB05'(!)        = 'End of Design' | 'Comp-Approve'     | 'CS21212FB05'           |'R0402'| '(R0402-0201)'                 | '1.21K'   | '1%'    | '1/16W'  | 'IO'       | 'RES CHIP 1.21K 1/16W +-1%(0402)EF'                | 'CHIPR0402'    | ''          | ''            | '20180221'
 '1.82K'      | '1%'      | '1/16W'  | '0402LF'  | 'CHIP'   | 'CS21822FB03'(!)        = 'End of Design' | 'Comp-Approve'     | 'CS21822FB03'           |'R0402'| '(R0402-0201)'                 | '1.82K'   | '1%'    | '1/16W'  | 'DISCRETE' | 'RES CHIP 1.82K 1/16W +-1%(0402)EF'                | 'CHIPR0402'    | ''          | ''            | '20180221'
 '1.82K'      | '1%'      | '1/16W'  | '0402LF'  | 'EMPTY'  | 'CS21822FB03'(!)        = 'End of Design' | 'Comp-Approve'     | 'CS21822FB03'           |'R0402'| '(R0402-0201)'                 | '1.82K'   | '1%'    | '1/16W'  | 'IO'       | 'RES CHIP 1.82K 1/16W +-1%(0402)EF'                | 'CHIPR0402'    | ''          | ''            | '20180221'
 '2K'         | '1%'      | '1/16W'  | '0402LF'  | 'CHIP'   | 'CS22002FB07'(!)        = 'End of Design' | 'Comp-Approve'     | 'CS22002FB07'           |'R0402'| '(R0402-0201)'                 | '2K'      | '1%'    | '1/16W'  | 'DISCRETE' | 'RES CHIP 2K 1/16W +-1%(0402)EF'                   | 'CHIPR0402'    | ''          | ''            | '20180221'
 '2K'         | '1%'      | '1/16W'  | '0402LF'  | 'EMPTY'  | 'CS22002FB07'(!)        = 'End of Design' | 'Comp-Approve'     | 'CS22002FB07'           |'R0402'| '(R0402-0201)'                 | '2K'      | '1%'    | '1/16W'  | 'IO'       | 'RES CHIP 2K 1/16W +-1%(0402)EF'                   | 'CHIPR0402'    | ''          | ''            | '20180221'
 '2.21K'      | '1%'      | '1/16W'  | '0402LF'  | 'CHIP'   | 'CS22212FB06'(!)        = 'End of Design' | 'Comp-Approve'     | 'CS22212FB06'           |'R0402'| '(R0402-0201)'                 | '2.21K'   | '1%'    | '1/16W'  | 'DISCRETE' | 'RES CHIP 2.21K 1/16W +-1%(0402)EF'                | 'CHIPR0402'    | ''          | ''            | '20180221'
 '2.21K'      | '1%'      | '1/16W'  | '0402LF'  | 'EMPTY'  | 'CS22212FB06'(!)        = 'End of Design' | 'Comp-Approve'     | 'CS22212FB06'           |'R0402'| '(R0402-0201)'                 | '2.21K'   | '1%'    | '1/16W'  | 'IO'       | 'RES CHIP 2.21K 1/16W +-1%(0402)EF'                | 'CHIPR0402'    | ''          | ''            | '20180221'
 '2.49K'      | '1%'      | '1/16W'  | '0402LF'  | 'CHIP'   | 'CS22492FB05'(!)        = 'End of Design' | 'Comp-Approve'     | 'CS22492FB05'           |'R0402'| '(R0402-0201)'                 | '2.49K'   | '1%'    | '1/16W'  | 'DISCRETE' | 'RES CHIP 2.49K 1/16W +-1%(0402)EF'                | 'CHIPR0402'    | ''          | ''            | '20180221'
 '2.49K'      | '1%'      | '1/16W'  | '0402LF'  | 'EMPTY'  | 'CS22492FB05'(!)        = 'End of Design' | 'Comp-Approve'     | 'CS22492FB05'           |'R0402'| '(R0402-0201)'                 | '2.49K'   | '1%'    | '1/16W'  | 'IO'       | 'RES CHIP 2.49K 1/16W +-1%(0402)EF'                | 'CHIPR0402'    | ''          | ''            | '20180221'
 '2.87K'      | '1%'      | '1/16W'  | '0402LF'  | 'CHIP'   | 'CS22872FB03'(!)        = 'End of Design' | 'Comp-Approve'     | 'CS22872FB03'           |'R0402'| '(R0402-0201)'                 | '2.87K'   | '1%'    | '1/16W'  | 'DISCRETE' | 'RES CHIP 2.87K 1/16W +-1%(0402)EF'                | 'CHIPR0402'    | ''          | ''            | '20180221'
 '2.87K'      | '1%'      | '1/16W'  | '0402LF'  | 'EMPTY'  | 'CS22872FB03'(!)        = 'End of Design' | 'Comp-Approve'     | 'CS22872FB03'           |'R0402'| '(R0402-0201)'                 | '2.87K'   | '1%'    | '1/16W'  | 'IO'       | 'RES CHIP 2.87K 1/16W +-1%(0402)EF'                | 'CHIPR0402'    | ''          | ''            | '20180221'
 '3.16K'      | '1%'      | '1/16W'  | '0402LF'  | 'CHIP'   | 'CS23162FB03'(!)        = 'End of Design' | 'Comp-Approve'     | 'CS23162FB03'           |'R0402'| '(R0402-0201)'                 | '3.16K'   | '1%'    | '1/16W'  | 'DISCRETE' | 'RES CHIP 3.16K 1/16W +-1%(0402)EF'                | 'CHIPR0402'    | ''          | ''            | '20180221'
 '3.16K'      | '1%'      | '1/16W'  | '0402LF'  | 'EMPTY'  | 'CS23162FB03'(!)        = 'End of Design' | 'Comp-Approve'     | 'CS23162FB03'           |'R0402'| '(R0402-0201)'                 | '3.16K'   | '1%'    | '1/16W'  | 'IO'       | 'RES CHIP 3.16K 1/16W +-1%(0402)EF'                | 'CHIPR0402'    | ''          | ''            | '20180221'
 '4.02K'      | '1%'      | '1/16W'  | '0402LF'  | 'CHIP'   | 'CS24022FB04'(!)        = 'End of Design' | 'Comp-Approve'     | 'CS24022FB04'           |'R0402'| '(R0402-0201)'                 | '4.02K'   | '1%'    | '1/16W'  | 'DISCRETE' | 'RES CHIP 4.02K 1/16W +-1%(0402)EF'                | 'CHIPR0402'    | ''          | ''            | '20180221'
 '4.02K'      | '1%'      | '1/16W'  | '0402LF'  | 'EMPTY'  | 'CS24022FB04'(!)        = 'End of Design' | 'Comp-Approve'     | 'CS24022FB04'           |'R0402'| '(R0402-0201)'                 | '4.02K'   | '1%'    | '1/16W'  | 'IO'       | 'RES CHIP 4.02K 1/16W +-1%(0402)EF'                | 'CHIPR0402'    | ''          | ''            | '20180221'
 '4.75K'      | '0.1%'    | '1/16W'  | '0402LF'  | 'CHIP'   | 'CS24752BB02'(!)        = 'End of Design' | 'Comp-Approve'     | 'CS24752BB02'           |'R0402'| '(R0402-0201)'                 | '4.75K'   | '0.1%'  | '1/16W'  | 'DISCRETE' | 'RES CHIP 4.75K 1/16W +-0.1%(0402)EF'              | 'CHIPR0402'    | ''          | ''            | '20180221'
 '4.75K'      | '0.1%'    | '1/16W'  | '0402LF'  | 'EMPTY'  | 'CS24752BB02'(!)        = 'End of Design' | 'Comp-Approve'     | 'CS24752BB02'           |'R0402'| '(R0402-0201)'                 | '4.75K'   | '0.1%'  | '1/16W'  | 'IO'       | 'RES CHIP 4.75K 1/16W +-0.1%(0402)EF'              | 'CHIPR0402'    | ''          | ''            | '20180221'
 '4.87K'      | '1%'      | '1/16W'  | '0402LF'  | 'CHIP'   | 'CS24872FB01'(!)        = 'End of Design' | 'Comp-Approve'     | 'CS24872FB01'           |'R0402'| '(R0402-0201)'                 | '4.87K'   | '1%'    | '1/16W'  | 'DISCRETE' | 'RES CHIP 4.87K 1/16W +-1%(0402)EF'                | 'CHIPR0402'    | ''          | ''            | '20180221'
 '4.87K'      | '1%'      | '1/16W'  | '0402LF'  | 'EMPTY'  | 'CS24872FB01'(!)        = 'End of Design' | 'Comp-Approve'     | 'CS24872FB01'           |'R0402'| '(R0402-0201)'                 | '4.87K'   | '1%'    | '1/16W'  | 'IO'       | 'RES CHIP 4.87K 1/16W +-1%(0402)EF'                | 'CHIPR0402'    | ''          | ''            | '20180221'
 '6.19K'      | '1%'      | '1/16W'  | '0402LF'  | 'CHIP'   | 'CS26192FB03'(!)        = 'End of Design' | 'Comp-Approve'     | 'CS26192FB03'           |'R0402'| '(R0402-0201)'                 | '6.19K'   | '1%'    | '1/16W'  | 'DISCRETE' | 'RES CHIP 6.19K 1/16W +-1%(0402)EF'                | 'CHIPR0402'    | ''          | ''            | '20180221'
 '6.19K'      | '1%'      | '1/16W'  | '0402LF'  | 'EMPTY'  | 'CS26192FB03'(!)        = 'End of Design' | 'Comp-Approve'     | 'CS26192FB03'           |'R0402'| '(R0402-0201)'                 | '6.19K'   | '1%'    | '1/16W'  | 'IO'       | 'RES CHIP 6.19K 1/16W +-1%(0402)EF'                | 'CHIPR0402'    | ''          | ''            | '20180221'
 '6.65K'      | '1%'      | '1/16W'  | '0402LF'  | 'CHIP'   | 'CS26652FB04'(!)        = 'End of Design' | 'Comp-Approve'     | 'CS26652FB04'           |'R0402'| '(R0402-0201)'                 | '6.65K'   | '1%'    | '1/16W'  | 'DISCRETE' | 'RES CHIP 6.65K 1/16W +-1%(0402)EF'                | 'CHIPR0402'    | ''          | ''            | '20180221'
 '6.65K'      | '1%'      | '1/16W'  | '0402LF'  | 'EMPTY'  | 'CS26652FB04'(!)        = 'End of Design' | 'Comp-Approve'     | 'CS26652FB04'           |'R0402'| '(R0402-0201)'                 | '6.65K'   | '1%'    | '1/16W'  | 'IO'       | 'RES CHIP 6.65K 1/16W +-1%(0402)EF'                | 'CHIPR0402'    | ''          | ''            | '20180221'
 '6.81K'      | '1%'      | '1/16W'  | '0402LF'  | 'CHIP'   | 'CS26812FB04'(!)        = ''              | ''                 | 'CS26812FB04'           |'R0402'| '(R0402-0201)'                 | '6.81K'   | '1%'    | '1/16W'  | 'DISCRETE' | 'RES CHIP 6.81K 1/16W +-1%(0402)EF'                | 'CHIPR0402'    | ''          | ''            | '20180221'
 '6.81K'      | '1%'      | '1/16W'  | '0402LF'  | 'EMPTY'  | 'CS26812FB04'(!)        = ''              | ''                 | 'CS26812FB04'           |'R0402'| '(R0402-0201)'                 | '6.81K'   | '1%'    | '1/16W'  | 'IO'       | 'RES CHIP 6.81K 1/16W +-1%(0402)EF'                | 'CHIPR0402'    | ''          | ''            | '20180221'
 '8.25K'      | '1%'      | '1/16W'  | '0402LF'  | 'CHIP'   | 'CS28252FB03'(!)        = 'End of Design' | 'Comp-Approve'     | 'CS28252FB03'           |'R0402'| '(R0402-0201)'                 | '8.25K'   | '1%'    | '1/16W'  | 'DISCRETE' | 'RES CHIP 8.25K 1/16W +-1%(0402)EF'                | 'CHIPR0402'    | ''          | ''            | '20180221'
 '8.25K'      | '1%'      | '1/16W'  | '0402LF'  | 'EMPTY'  | 'CS28252FB03'(!)        = 'End of Design' | 'Comp-Approve'     | 'CS28252FB03'           |'R0402'| '(R0402-0201)'                 | '8.25K'   | '1%'    | '1/16W'  | 'IO'       | 'RES CHIP 8.25K 1/16W +-1%(0402)EF'                | 'CHIPR0402'    | ''          | ''            | '20180221'
 '9.31K'      | '1%'      | '1/16W'  | '0402LF'  | 'CHIP'   | 'CS29312FB02'(!)        = 'End of Design' | 'Comp-Approve'     | 'CS29312FB02'           |'R0402'| '(R0402-0201)'                 | '9.31K'   | '1%'    | '1/16W'  | 'DISCRETE' | 'RES CHIP 9.31K 1/16W +-1%(0402)EF'                | 'CHIPR0402'    | ''          | ''            | '20180221'
 '9.31K'      | '1%'      | '1/16W'  | '0402LF'  | 'EMPTY'  | 'CS29312FB02'(!)        = 'End of Design' | 'Comp-Approve'     | 'CS29312FB02'           |'R0402'| '(R0402-0201)'                 | '9.31K'   | '1%'    | '1/16W'  | 'IO'       | 'RES CHIP 9.31K 1/16W +-1%(0402)EF'                | 'CHIPR0402'    | ''          | ''            | '20180221'
 '11K'        | '1%'      | '1/16W'  | '0402LF'  | 'CHIP'   | 'CS31102FB05'(!)        = 'End of Design' | 'Comp-Approve'     | 'CS31102FB05'           |'R0402'| '(R0402-0201)'                 | '11K'     | '1%'    | '1/16W'  | 'DISCRETE' | 'RES CHIP 11K 1/16W +-1%(0402)EF'                  | 'CHIPR0402'    | ''          | ''            | '20180221'
 '11K'        | '1%'      | '1/16W'  | '0402LF'  | 'EMPTY'  | 'CS31102FB05'(!)        = 'End of Design' | 'Comp-Approve'     | 'CS31102FB05'           |'R0402'| '(R0402-0201)'                 | '11K'     | '1%'    | '1/16W'  | 'IO'       | 'RES CHIP 11K 1/16W +-1%(0402)EF'                  | 'CHIPR0402'    | ''          | ''            | '20180221'
 '11.5K'      | '1%'      | '1/16W'  | '0402LF'  | 'CHIP'   | 'CS31152FB03'(!)        = 'End of Design' | 'Comp-Approve'     | 'CS31152FB03'           |'R0402'| '(R0402-0201)'                 | '11.5K'   | '1%'    | '1/16W'  | 'DISCRETE' | 'RES CHIP 11.5K 1/16W +-1%(0402)EF'                | 'CHIPR0402'    | ''          | ''            | '20180221'
 '11.5K'      | '1%'      | '1/16W'  | '0402LF'  | 'EMPTY'  | 'CS31152FB03'(!)        = 'End of Design' | 'Comp-Approve'     | 'CS31152FB03'           |'R0402'| '(R0402-0201)'                 | '11.5K'   | '1%'    | '1/16W'  | 'IO'       | 'RES CHIP 11.5K 1/16W +-1%(0402)EF'                | 'CHIPR0402'    | ''          | ''            | '20180221'
 '11.8K'      | '1%'      | '1/16W'  | '0402LF'  | 'CHIP'   | 'CS31182FB03'(!)        = 'End of Design' | 'Comp-Approve'     | 'CS31182FB03'           |'R0402'| '(R0402-0201)'                 | '11.8K'   | '1%'    | '1/16W'  | 'DISCRETE' | 'RES CHIP 11.8K 1/16W +-1%(0402)EF'                | 'CHIPR0402'    | ''          | ''            | '20180221'
 '11.8K'      | '1%'      | '1/16W'  | '0402LF'  | 'EMPTY'  | 'CS31182FB03'(!)        = 'End of Design' | 'Comp-Approve'     | 'CS31182FB03'           |'R0402'| '(R0402-0201)'                 | '11.8K'   | '1%'    | '1/16W'  | 'IO'       | 'RES CHIP 11.8K 1/16W +-1%(0402)EF'                | 'CHIPR0402'    | ''          | ''            | '20180221'
 '12K'        | '1%'      | '1/16W'  | '0402LF'  | 'CHIP'   | 'CS31202FB04'(!)        = 'End of Design' | 'Comp-Approve'     | 'CS31202FB04'           |'R0402'| '(R0402-0201)'                 | '12K'     | '1%'    | '1/16W'  | 'DISCRETE' | 'RES CHIP 12K 1/16W +-1%(0402)EF'                  | 'CHIPR0402'    | ''          | ''            | '20180221'
 '12K'        | '1%'      | '1/16W'  | '0402LF'  | 'EMPTY'  | 'CS31202FB04'(!)        = 'End of Design' | 'Comp-Approve'     | 'CS31202FB04'           |'R0402'| '(R0402-0201)'                 | '12K'     | '1%'    | '1/16W'  | 'IO'       | 'RES CHIP 12K 1/16W +-1%(0402)EF'                  | 'CHIPR0402'    | ''          | ''            | '20180221'
 '12.1K'      | '1%'      | '1/16W'  | '0402LF'  | 'CHIP'   | 'CS31212FB05'(!)        = 'End of Design' | 'Comp-Approve'     | 'CS31212FB05'           |'R0402'| '(R0402-0201)'                 | '12.1K'   | '1%'    | '1/16W'  | 'DISCRETE' | 'RES CHIP 12.1K 1/16W +-1%(0402)EF'                | 'CHIPR0402'    | ''          | ''            | '20180221'
 '12.1K'      | '1%'      | '1/16W'  | '0402LF'  | 'EMPTY'  | 'CS31212FB05'(!)        = 'End of Design' | 'Comp-Approve'     | 'CS31212FB05'           |'R0402'| '(R0402-0201)'                 | '12.1K'   | '1%'    | '1/16W'  | 'IO'       | 'RES CHIP 12.1K 1/16W +-1%(0402)EF'                | 'CHIPR0402'    | ''          | ''            | '20180221'
 '12.4K'      | '1%'      | '1/16W'  | '0402LF'  | 'CHIP'   | 'CS31242FB02'(!)        = 'End of Design' | 'Comp-Approve'     | 'CS31242FB02'           |'R0402'| '(R0402-0201)'                 | '12.4K'   | '1%'    | '1/16W'  | 'DISCRETE' | 'RES CHIP 12.4K 1/16W +-1%(0402)EF'                | 'CHIPR0402'    | ''          | ''            | '20180221'
 '12.4K'      | '1%'      | '1/16W'  | '0402LF'  | 'EMPTY'  | 'CS31242FB02'(!)        = 'End of Design' | 'Comp-Approve'     | 'CS31242FB02'           |'R0402'| '(R0402-0201)'                 | '12.4K'   | '1%'    | '1/16W'  | 'IO'       | 'RES CHIP 12.4K 1/16W +-1%(0402)EF'                | 'CHIPR0402'    | ''          | ''            | '20180221'
 '13K'        | '1%'      | '1/16W'  | '0402LF'  | 'CHIP'   | 'CS31302FB04'(!)        = 'End of Design' | 'Comp-Approve'     | 'CS31302FB04'           |'R0402'| '(R0402-0201)'                 | '13K'     | '1%'    | '1/16W'  | 'DISCRETE' | 'RES CHIP 13K 1/16W +-1%(0402)EF'                  | 'CHIPR0402'    | ''          | ''            | '20180221'
 '13K'        | '1%'      | '1/16W'  | '0402LF'  | 'EMPTY'  | 'CS31302FB04'(!)        = 'End of Design' | 'Comp-Approve'     | 'CS31302FB04'           |'R0402'| '(R0402-0201)'                 | '13K'     | '1%'    | '1/16W'  | 'IO'       | 'RES CHIP 13K 1/16W +-1%(0402)EF'                  | 'CHIPR0402'    | ''          | ''            | '20180221'
 '14K'        | '1%'      | '1/16W'  | '0402LF'  | 'CHIP'   | 'CS31402FB03'(!)        = 'End of Design' | 'Comp-Approve'     | 'CS31402FB03'           |'R0402'| '(R0402-0201)'                 | '14K'     | '1%'    | '1/16W'  | 'DISCRETE' | 'RES CHIP 14K 1/16W +-1%(0402)EF'                  | 'CHIPR0402'    | ''          | ''            | '20180221'
 '14K'        | '1%'      | '1/16W'  | '0402LF'  | 'EMPTY'  | 'CS31402FB03'(!)        = 'End of Design' | 'Comp-Approve'     | 'CS31402FB03'           |'R0402'| '(R0402-0201)'                 | '14K'     | '1%'    | '1/16W'  | 'IO'       | 'RES CHIP 14K 1/16W +-1%(0402)EF'                  | 'CHIPR0402'    | ''          | ''            | '20180221'
 '14.3K'      | '1%'      | '1/16W'  | '0402LF'  | 'CHIP'   | 'CS31432FB02'(!)        = 'End of Design' | 'Comp-Approve'     | 'CS31432FB02'           |'R0402'| '(R0402-0201)'                 | '14.3K'   | '1%'    | '1/16W'  | 'DISCRETE' | 'RES CHIP 14.3K 1/16W +-1%(0402)EF'                | 'CHIPR0402'    | ''          | ''            | '20180221'
 '14.3K'      | '1%'      | '1/16W'  | '0402LF'  | 'EMPTY'  | 'CS31432FB02'(!)        = 'End of Design' | 'Comp-Approve'     | 'CS31432FB02'           |'R0402'| '(R0402-0201)'                 | '14.3K'   | '1%'    | '1/16W'  | 'IO'       | 'RES CHIP 14.3K 1/16W +-1%(0402)EF'                | 'CHIPR0402'    | ''          | ''            | '20180221'
 '15K'        | '0.1%'    | '1/16W'  | '0402LF'  | 'CHIP'   | 'CS31502BB03'(!)        = 'End of Design' | 'Comp-Approve'     | 'CS31502BB03'           |'R0402'| '(R0402-0201)'                 | '15K'     | '0.1%'  | '1/16W'  | 'DISCRETE' | 'RES CHIP 15K  1/16W +-0.1%(0402)EF'               | 'CHIPR0402'    | ''          | ''            | '20180221'
 '15K'        | '0.1%'    | '1/16W'  | '0402LF'  | 'EMPTY'  | 'CS31502BB03'(!)        = 'End of Design' | 'Comp-Approve'     | 'CS31502BB03'           |'R0402'| '(R0402-0201)'                 | '15K'     | '0.1%'  | '1/16W'  | 'IO'       | 'RES CHIP 15K  1/16W +-0.1%(0402)EF'               | 'CHIPR0402'    | ''          | ''            | '20180221'
 '15.8K'      | '1%'      | '1/16W'  | '0402LF'  | 'CHIP'   | 'CS31582FB02'(!)        = 'End of Design' | 'Comp-Approve'     | 'CS31582FB02'           |'R0402'| '(R0402-0201)'                 | '15.8K'   | '1%'    | '1/16W'  | 'DISCRETE' | 'RES CHIP 15.8K 1/16W +-1% (0402)EF'               | 'CHIPR0402'    | ''          | ''            | '20180221'
 '15.8K'      | '1%'      | '1/16W'  | '0402LF'  | 'EMPTY'  | 'CS31582FB02'(!)        = 'End of Design' | 'Comp-Approve'     | 'CS31582FB02'           |'R0402'| '(R0402-0201)'                 | '15.8K'   | '1%'    | '1/16W'  | 'IO'       | 'RES CHIP 15.8K 1/16W +-1% (0402)EF'               | 'CHIPR0402'    | ''          | ''            | '20180221'
 '16.5K'      | '1%'      | '1/16W'  | '0402LF'  | 'CHIP'   | 'CS31652FB05'(!)        = 'End of Design' | 'Comp-Approve'     | 'CS31652FB05'           |'R0402'| '(R0402-0201)'                 | '16.5K'   | '1%'    | '1/16W'  | 'DISCRETE' | 'RES CHIP 16.5K 1/16W +-1%(0402)EF'                | 'CHIPR0402'    | ''          | ''            | '20180221'
 '16.5K'      | '1%'      | '1/16W'  | '0402LF'  | 'EMPTY'  | 'CS31652FB05'(!)        = 'End of Design' | 'Comp-Approve'     | 'CS31652FB05'           |'R0402'| '(R0402-0201)'                 | '16.5K'   | '1%'    | '1/16W'  | 'IO'       | 'RES CHIP 16.5K 1/16W +-1%(0402)EF'                | 'CHIPR0402'    | ''          | ''            | '20180221'
 '22K'        | '1%'      | '1/16W'  | '0402LF'  | 'CHIP'   | 'CS32202FB02'(!)        = 'End of Design' | 'Comp-Approve'     | 'CS32202FB02'           |'R0402'| '(R0402-0201)'                 | '22K'     | '1%'    | '1/16W'  | 'DISCRETE' | 'RES CHIP 22K 1/16W +-1%(0402)EF'                  | 'CHIPR0402'    | ''          | ''            | '20180221'
 '22K'        | '1%'      | '1/16W'  | '0402LF'  | 'EMPTY'  | 'CS32202FB02'(!)        = 'End of Design' | 'Comp-Approve'     | 'CS32202FB02'           |'R0402'| '(R0402-0201)'                 | '22K'     | '1%'    | '1/16W'  | 'IO'       | 'RES CHIP 22K 1/16W +-1%(0402)EF'                  | 'CHIPR0402'    | ''          | ''            | '20180221'
 '24.9K'      | '1%'      | '1/16W'  | '0402LF'  | 'CHIP'   | 'CS32492FB04'(!)        = 'End of Design' | 'Comp-Approve'     | 'CS32492FB04'           |'R0402'| '(R0402-0201)'                 | '24.9K'   | '1%'    | '1/16W'  | 'DISCRETE' | 'RES CHIP 24.9K 1/16W +-1%(0402)EF'                | 'CHIPR0402'    | ''          | ''            | '20180221'
 '24.9K'      | '1%'      | '1/16W'  | '0402LF'  | 'EMPTY'  | 'CS32492FB04'(!)        = 'End of Design' | 'Comp-Approve'     | 'CS32492FB04'           |'R0402'| '(R0402-0201)'                 | '24.9K'   | '1%'    | '1/16W'  | 'IO'       | 'RES CHIP 24.9K 1/16W +-1%(0402)EF'                | 'CHIPR0402'    | ''          | ''            | '20180221'
 '25.5K'      | '1%'      | '1/16W'  | '0402LF'  | 'CHIP'   | 'CS32552FB06'(!)        = 'End of Design' | 'Comp-Approve'     | 'CS32552FB06'           |'R0402'| '(R0402-0201)'                 | '25.5K'   | '1%'    | '1/16W'  | 'DISCRETE' | 'RES CHIP 25.5K 1/16W +-1%(0402)EF'                | 'CHIPR0402'    | ''          | ''            | '20180221'
 '25.5K'      | '1%'      | '1/16W'  | '0402LF'  | 'EMPTY'  | 'CS32552FB06'(!)        = 'End of Design' | 'Comp-Approve'     | 'CS32552FB06'           |'R0402'| '(R0402-0201)'                 | '25.5K'   | '1%'    | '1/16W'  | 'IO'       | 'RES CHIP 25.5K 1/16W +-1%(0402)EF'                | 'CHIPR0402'    | ''          | ''            | '20180221'
 '26.1K'      | '1%'      | '1/16W'  | '0402LF'  | 'CHIP'   | 'CS32612FB02'(!)        = 'End of Design' | 'Comp-Approve'     | 'CS32612FB02'           |'R0402'| '(R0402-0201)'                 | '26.1K'   | '1%'    | '1/16W'  | 'DISCRETE' | 'RES CHIP 26.1K 1/16W +-1%(0402)EF'                | 'CHIPR0402'    | ''          | ''            | '20180221'
 '26.1K'      | '1%'      | '1/16W'  | '0402LF'  | 'EMPTY'  | 'CS32612FB02'(!)        = 'End of Design' | 'Comp-Approve'     | 'CS32612FB02'           |'R0402'| '(R0402-0201)'                 | '26.1K'   | '1%'    | '1/16W'  | 'IO'       | 'RES CHIP 26.1K 1/16W +-1%(0402)EF'                | 'CHIPR0402'    | ''          | ''            | '20180221'
 '27.4K'      | '1%'      | '1/16W'  | '0402LF'  | 'CHIP'   | 'CS32742FB04'(!)        = 'End of Design' | 'Comp-Approve'     | 'CS32742FB04'           |'R0402'| '(R0402-0201)'                 | '27.4K'   | '1%'    | '1/16W'  | 'DISCRETE' | 'RES CHIP 27.4K 1/16W +-1%(0402)EF'                | 'CHIPR0402'    | ''          | ''            | '20180221'
 '27.4K'      | '1%'      | '1/16W'  | '0402LF'  | 'EMPTY'  | 'CS32742FB04'(!)        = 'End of Design' | 'Comp-Approve'     | 'CS32742FB04'           |'R0402'| '(R0402-0201)'                 | '27.4K'   | '1%'    | '1/16W'  | 'IO'       | 'RES CHIP 27.4K 1/16W +-1%(0402)EF'                | 'CHIPR0402'    | ''          | ''            | '20180221'
 '33K'        | '1%'      | '1/16W'  | '0402LF'  | 'CHIP'   | 'CS33302FB00'(!)        = ''              | ''                 | 'CS33302FB00'           |'R0402'| '(R0402-0201)'                 | '33K'     | '1%'    | '1/16W'  | 'DISCRETE' | 'RES CHIP 33K 1/16W +-1%(0402)EF'                  | 'CHIPR0402'    | ''          | ''            | '20180221'
 '33K'        | '1%'      | '1/16W'  | '0402LF'  | 'EMPTY'  | 'CS33302FB00'(!)        = ''              | ''                 | 'CS33302FB00'           |'R0402'| '(R0402-0201)'                 | '33K'     | '1%'    | '1/16W'  | 'IO'       | 'RES CHIP 33K 1/16W +-1%(0402)EF'                  | 'CHIPR0402'    | ''          | ''            | '20180221'
 '35.7K'      | '1%'      | '1/16W'  | '0402LF'  | 'CHIP'   | 'CS33572FB01'(!)        = 'End of Design' | 'Comp-Approve'     | 'CS33572FB01'           |'R0402'| '(R0402-0201)'                 | '35.7K'   | '1%'    | '1/16W'  | 'DISCRETE' | 'RES CHIP 35.7K 1/16W +-1%(0402) EF'               | 'CHIPR0402'    | ''          | ''            | '20180221'
 '35.7K'      | '1%'      | '1/16W'  | '0402LF'  | 'EMPTY'  | 'CS33572FB01'(!)        = 'End of Design' | 'Comp-Approve'     | 'CS33572FB01'           |'R0402'| '(R0402-0201)'                 | '35.7K'   | '1%'    | '1/16W'  | 'IO'       | 'RES CHIP 35.7K 1/16W +-1%(0402) EF'               | 'CHIPR0402'    | ''          | ''            | '20180221'
 '39.2K'      | '1%'      | '1/16W'  | '0402LF'  | 'CHIP'   | 'CS33922FB05'(!)        = 'End of Design' | 'Comp-Approve'     | 'CS33922FB05'           |'R0402'| '(R0402-0201)'                 | '39.2K'   | '1%'    | '1/16W'  | 'DISCRETE' | 'RES CHIP 39.2K 1/16W +-1%(0402)EF'                | 'CHIPR0402'    | ''          | ''            | '20180221'
 '39.2K'      | '1%'      | '1/16W'  | '0402LF'  | 'EMPTY'  | 'CS33922FB05'(!)        = 'End of Design' | 'Comp-Approve'     | 'CS33922FB05'           |'R0402'| '(R0402-0201)'                 | '39.2K'   | '1%'    | '1/16W'  | 'IO'       | 'RES CHIP 39.2K 1/16W +-1%(0402)EF'                | 'CHIPR0402'    | ''          | ''            | '20180221'
 '43.2K'      | '1%'      | '1/16W'  | '0402LF'  | 'CHIP'   | 'CS34322FB03'(!)        = 'End of Design' | 'Comp-Approve'     | 'CS34322FB03'           |'R0402'| '(R0402-0201)'                 | '43.2K'   | '1%'    | '1/16W'  | 'DISCRETE' | 'RES CHIP 43.2K 1/16W +-1%(0402)EF'                | 'CHIPR0402'    | ''          | ''            | '20180221'
 '43.2K'      | '1%'      | '1/16W'  | '0402LF'  | 'EMPTY'  | 'CS34322FB03'(!)        = 'End of Design' | 'Comp-Approve'     | 'CS34322FB03'           |'R0402'| '(R0402-0201)'                 | '43.2K'   | '1%'    | '1/16W'  | 'IO'       | 'RES CHIP 43.2K 1/16W +-1%(0402)EF'                | 'CHIPR0402'    | ''          | ''            | '20180221'
 '44.2K'      | '1%'      | '1/16W'  | '0402LF'  | 'CHIP'   | 'CS34422FB04'(!)        = 'End of Design' | 'Comp-Approve'     | 'CS34422FB04'           |'R0402'| '(R0402-0201)'                 | '44.2K'   | '1%'    | '1/16W'  | 'DISCRETE' | 'RES CHIP 44.2K 1/16W +-1%(0402)EF'                | 'CHIPR0402'    | ''          | ''            | '20180221'
 '44.2K'      | '1%'      | '1/16W'  | '0402LF'  | 'EMPTY'  | 'CS34422FB04'(!)        = 'End of Design' | 'Comp-Approve'     | 'CS34422FB04'           |'R0402'| '(R0402-0201)'                 | '44.2K'   | '1%'    | '1/16W'  | 'IO'       | 'RES CHIP 44.2K 1/16W +-1%(0402)EF'                | 'CHIPR0402'    | ''          | ''            | '20180221'
 '47.5K'      | '1%'      | '1/16W'  | '0402LF'  | 'CHIP'   | 'CS34752FB03'(!)        = 'End of Design' | 'Comp-Approve'     | 'CS34752FB03'           |'R0402'| '(R0402-0201)'                 | '47.5K'   | '1%'    | '1/16W'  | 'DISCRETE' | 'RES CHIP 47.5K 1/16W +-1%(0402)EF'                | 'CHIPR0402'    | ''          | ''            | '20180221'
 '47.5K'      | '1%'      | '1/16W'  | '0402LF'  | 'EMPTY'  | 'CS34752FB03'(!)        = 'End of Design' | 'Comp-Approve'     | 'CS34752FB03'           |'R0402'| '(R0402-0201)'                 | '47.5K'   | '1%'    | '1/16W'  | 'IO'       | 'RES CHIP 47.5K 1/16W +-1%(0402)EF'                | 'CHIPR0402'    | ''          | ''            | '20180221'
 '51.1K'      | '1%'      | '1/16W'  | '0402LF'  | 'CHIP'   | 'CS35112FB03'(!)        = 'End of Design' | 'Comp-Approve'     | 'CS35112FB03'           |'R0402'| '(R0402-0201)'                 | '51.1K'   | '1%'    | '1/16W'  | 'DISCRETE' | 'RES CHIP 51.1K 1/16W +-1%(0402)EF'                | 'CHIPR0402'    | ''          | ''            | '20180221'
 '51.1K'      | '1%'      | '1/16W'  | '0402LF'  | 'EMPTY'  | 'CS35112FB03'(!)        = 'End of Design' | 'Comp-Approve'     | 'CS35112FB03'           |'R0402'| '(R0402-0201)'                 | '51.1K'   | '1%'    | '1/16W'  | 'IO'       | 'RES CHIP 51.1K 1/16W +-1%(0402)EF'                | 'CHIPR0402'    | ''          | ''            | '20180221'
 '54.9K'      | '1%'      | '1/16W'  | '0402LF'  | 'CHIP'   | 'CS35492FB03'(!)        = 'End of Design' | 'Comp-Approve'     | 'CS35492FB03'           |'R0402'| '(R0402-0201)'                 | '54.9K'   | '1%'    | '1/16W'  | 'DISCRETE' | 'RES CHIP 54.9K 1/16W  +-1%(0402)EF'               | 'CHIPR0402'    | ''          | ''            | '20180221'
 '54.9K'      | '1%'      | '1/16W'  | '0402LF'  | 'EMPTY'  | 'CS35492FB03'(!)        = 'End of Design' | 'Comp-Approve'     | 'CS35492FB03'           |'R0402'| '(R0402-0201)'                 | '54.9K'   | '1%'    | '1/16W'  | 'IO'       | 'RES CHIP 54.9K 1/16W  +-1%(0402)EF'               | 'CHIPR0402'    | ''          | ''            | '20180221'
 '64.9K'      | '1%'      | '1/16W'  | '0402LF'  | 'CHIP'   | 'CS36492FB02'(!)        = 'End of Design' | 'Comp-Approve'     | 'CS36492FB02'           |'R0402'| '(R0402-0201)'                 | '64.9K'   | '1%'    | '1/16W'  | 'DISCRETE' | 'RES CHIP 64.9K 1/16W +-1%(0402)EF'                | 'CHIPR0402'    | ''          | ''            | '20180221'
 '64.9K'      | '1%'      | '1/16W'  | '0402LF'  | 'EMPTY'  | 'CS36492FB02'(!)        = 'End of Design' | 'Comp-Approve'     | 'CS36492FB02'           |'R0402'| '(R0402-0201)'                 | '64.9K'   | '1%'    | '1/16W'  | 'IO'       | 'RES CHIP 64.9K 1/16W +-1%(0402)EF'                | 'CHIPR0402'    | ''          | ''            | '20180221'
 '66.5K'      | '1%'      | '1/16W'  | '0402LF'  | 'CHIP'   | 'CS36652FB03'(!)        = 'End of Design' | 'Comp-Approve'     | 'CS36652FB03'           |'R0402'| '(R0402-0201)'                 | '66.5K'   | '1%'    | '1/16W'  | 'DISCRETE' | 'RES CHIP 66.5K 1/16W +-1%(0402)EF'                | 'CHIPR0402'    | ''          | ''            | '20180221'
 '66.5K'      | '1%'      | '1/16W'  | '0402LF'  | 'EMPTY'  | 'CS36652FB03'(!)        = 'End of Design' | 'Comp-Approve'     | 'CS36652FB03'           |'R0402'| '(R0402-0201)'                 | '66.5K'   | '1%'    | '1/16W'  | 'IO'       | 'RES CHIP 66.5K 1/16W +-1%(0402)EF'                | 'CHIPR0402'    | ''          | ''            | '20180221'
 '86.6K'      | '1%'      | '1/16W'  | '0402LF'  | 'CHIP'   | 'CS38662FB05'(!)        = 'End of Design' | 'Comp-Approve'     | 'CS38662FB05'           |'R0402'| '(R0402-0201)'                 | '86.6K'   | '1%'    | '1/16W'  | 'DISCRETE' | 'RES CHIP 86.6K 1/16W +-1%(0402)EF'                | 'CHIPR0402'    | ''          | ''            | '20180221'
 '86.6K'      | '1%'      | '1/16W'  | '0402LF'  | 'EMPTY'  | 'CS38662FB05'(!)        = 'End of Design' | 'Comp-Approve'     | 'CS38662FB05'           |'R0402'| '(R0402-0201)'                 | '86.6K'   | '1%'    | '1/16W'  | 'IO'       | 'RES CHIP 86.6K 1/16W +-1%(0402)EF'                | 'CHIPR0402'    | ''          | ''            | '20180221'
 '121K'       | '1%'      | '1/16W'  | '0402LF'  | 'CHIP'   | 'CS41212FB02'(!)        = 'End of Design' | 'Comp-Approve'     | 'CS41212FB02'           |'R0402'| '(R0402-0201)'                 | '121K'    | '1%'    | '1/16W'  | 'DISCRETE' | 'RES CHIP 121K 1/16W +-1%(0402)EF'                 | 'CHIPR0402'    | ''          | ''            | '20180221'
 '121K'       | '1%'      | '1/16W'  | '0402LF'  | 'EMPTY'  | 'CS41212FB02'(!)        = 'End of Design' | 'Comp-Approve'     | 'CS41212FB02'           |'R0402'| '(R0402-0201)'                 | '121K'    | '1%'    | '1/16W'  | 'IO'       | 'RES CHIP 121K 1/16W +-1%(0402)EF'                 | 'CHIPR0402'    | ''          | ''            | '20180221'
 '137K'       | '1%'      | '1/16W'  | '0402LF'  | 'CHIP'   | 'CS41372FB01'(!)        = 'End of Design' | 'Comp-Approve'     | 'CS41372FB01'           |'R0402'| '(R0402-0201)'                 | '137K'    | '1%'    | '1/16W'  | 'DISCRETE' | 'RES CHIP 137K 1/16W +-1%(0402)EF'                 | 'CHIPR0402'    | ''          | ''            | '20180221'
 '137K'       | '1%'      | '1/16W'  | '0402LF'  | 'EMPTY'  | 'CS41372FB01'(!)        = 'End of Design' | 'Comp-Approve'     | 'CS41372FB01'           |'R0402'| '(R0402-0201)'                 | '137K'    | '1%'    | '1/16W'  | 'IO'       | 'RES CHIP 137K 1/16W +-1%(0402)EF'                 | 'CHIPR0402'    | ''          | ''            | '20180221'
 '150K'       | '1%'      | '1/16W'  | '0402LF'  | 'CHIP'   | 'CS41502FB04'(!)        = 'End of Design' | 'Comp-Approve'     | 'CS41502FB04'           |'R0402'| '(R0402-0201)'                 | '150K'    | '1%'    | '1/16W'  | 'DISCRETE' | 'RES CHIP 150K 1/16W +-1%(0402)EF'                 | 'CHIPR0402'    | ''          | ''            | '20180221'
 '150K'       | '1%'      | '1/16W'  | '0402LF'  | 'EMPTY'  | 'CS41502FB04'(!)        = 'End of Design' | 'Comp-Approve'     | 'CS41502FB04'           |'R0402'| '(R0402-0201)'                 | '150K'    | '1%'    | '1/16W'  | 'IO'       | 'RES CHIP 150K 1/16W +-1%(0402)EF'                 | 'CHIPR0402'    | ''          | ''            | '20180221'
 '510K'       | '5%'      | '1/16W'  | '0402LF'  | 'CHIP'   | 'CS45102JB03'(!)        = 'End of Design' | 'Comp-Approve'     | 'CS45102JB03'           |'R0402'| '(R0402-0201)'                 | '510K'    | '5%'    | '1/16W'  | 'DISCRETE' | 'RES CHIP 510K 1/16W +-5%(0402)EF'                 | 'CHIPR0402'    | ''          | ''            | '20180221'
 '510K'       | '5%'      | '1/16W'  | '0402LF'  | 'EMPTY'  | 'CS45102JB03'(!)        = 'End of Design' | 'Comp-Approve'     | 'CS45102JB03'           |'R0402'| '(R0402-0201)'                 | '510K'    | '5%'    | '1/16W'  | 'IO'       | 'RES CHIP 510K 1/16W +-5%(0402)EF'                 | 'CHIPR0402'    | ''          | ''            | '20180221'
 '1M'         | '1%'      | '1/16W'  | '0402LF'  | 'CHIP'   | 'CS51002FB05'(!)        = 'End of Design' | 'Comp-Approve'     | 'CS51002FB05'           |'R0402'| '(R0402-0201)'                 | '1M'      | '1%'    | '1/16W'  | 'DISCRETE' | 'RES CHIP 1M 1/16W +-1%(0402)EF'                   | 'CHIPR0402'    | ''          | ''            | '20180221'
 '1M'         | '1%'      | '1/16W'  | '0402LF'  | 'EMPTY'  | 'CS51002FB05'(!)        = 'End of Design' | 'Comp-Approve'     | 'CS51002FB05'           |'R0402'| '(R0402-0201)'                 | '1M'      | '1%'    | '1/16W'  | 'IO'       | 'RES CHIP 1M 1/16W +-1%(0402)EF'                   | 'CHIPR0402'    | ''          | ''            | '20180221'
 '2.2'        | '1%'      | '1/10W'  | '0603LF'  | 'CHIP'   | 'CS-2203F902'(!)        = 'End of Design' | 'Comp-Approve'     | 'CS-2203F902'           |'R0603'| '(SMR0603AW)'                  | '2.2'     | '1%'    | '1/10W'  | 'DISCRETE' | 'RES CHIP 2.2 1/10W +-1%(0603)EF'                  | 'CHIPR0603'    | ''          | ''            | '20180221'
 '2.2'        | '1%'      | '1/10W'  | '0603LF'  | 'EMPTY'  | 'CS-2203F902'(!)        = 'End of Design' | 'Comp-Approve'     | 'CS-2203F902'           |'R0603'| '(SMR0603AW)'                  | '2.2'     | '1%'    | '1/10W'  | 'IO'       | 'RES CHIP 2.2 1/10W +-1%(0603)EF'                  | 'CHIPR0603'    | ''          | ''            | '20180221'
 '10M'        | '1%'      | '1/10W'  | '0603LF'  | 'CHIP'   | 'CS61003F901'(!)        = 'End of Design' | 'Comp-Approve'     | 'CS61003F901'           |'R0603'| '(SMR0603AW)'                  | '10M'     | '1%'    | '1/10W'  | 'DISCRETE' | 'RES CHIP 10M 1/10W +-1%(0603)EF'                  | 'CHIPR0603'    | ''          | ''            | '20180221'
 '10M'        | '1%'      | '1/10W'  | '0603LF'  | 'EMPTY'  | 'CS61003F901'(!)        = 'End of Design' | 'Comp-Approve'     | 'CS61003F901'           |'R0603'| '(SMR0603AW)'                  | '10M'     | '1%'    | '1/10W'  | 'IO'       | 'RES CHIP 10M 1/10W +-1%(0603)EF'                  | 'CHIPR0603'    | ''          | ''            | '20180221'
 '0'          | ''        | '1/2W'   | '1206LF'  | 'CHIP'   | 'CS00007T200'(!)        = 'End of Design' | 'Comp-Approve'     | 'CS00007T200'           |'R1206XI'| '(SMRR1206AW)'                 | '0'       | ''      | '1/2W'   | 'DISCRETE' | 'RES CHIP 0 1/2W (1206)EF'                         | 'CHIPR1206'    | ''          | ''            | '20180221'
 '0'          | ''        | '1/2W'   | '1206LF'  | 'EMPTY'  | 'CS00007T200'(!)        = 'End of Design' | 'Comp-Approve'     | 'CS00007T200'           |'R1206XI'| '(SMRR1206AW)'                 | '0'       | ''      | '1/2W'   | 'IO'       | 'RES CHIP 0 1/2W (1206)EF'                         | 'CHIPR1206'    | ''          | ''            | '20180221'
 '51.1'       | '1%'      | '1/16W'  | '0402LF'  | 'CHIP'   | 'CS05112FB05'(!)        = 'End of Design' | 'Comp-Approve'     | 'CS05112FB05'           |'R0402'| '(R0402-0201)'                 | '51.1'    | '1%'    | '1/16W'  | 'DISCRETE' | 'RES CHIP 51.1 1/16W +-1%(0402)EF'                 | 'CHIPR0402'    | ''          | ''            | '20180221'
 '51.1'       | '1%'      | '1/16W'  | '0402LF'  | 'EMPTY'  | 'CS05112FB05'(!)        = 'End of Design' | 'Comp-Approve'     | 'CS05112FB05'           |'R0402'| '(R0402-0201)'                 | '51.1'    | '1%'    | '1/16W'  | 'IO'       | 'RES CHIP 51.1 1/16W +-1%(0402)EF'                 | 'CHIPR0402'    | ''          | ''            | '20180221'
 '1'          | '1%'      | '1/16W'  | '0402LF'  | 'CHIP'   | 'CS-1002FB04'(!)        = 'End of Design' | 'Comp-Approve'     | 'CS-1002FB04'           |'R0402'| '(R0402-0201)'                 | '1'       | '1%'    | '1/16W'  | 'DISCRETE' | 'RES CHIP 1 1/16W +-1%(0402)EF'                    | 'CHIPR0402'    | ''          | ''            | '20180221'
 '1'          | '1%'      | '1/16W'  | '0402LF'  | 'EMPTY'  | 'CS-1002FB04'(!)        = 'End of Design' | 'Comp-Approve'     | 'CS-1002FB04'           |'R0402'| '(R0402-0201)'                 | '1'       | '1%'    | '1/16W'  | 'IO'       | 'RES CHIP 1 1/16W +-1%(0402)EF'                    | 'CHIPR0402'    | ''          | ''            | '20180221'
 '4.7'        | '5%'      | '1/16W'  | '0402LF'  | 'CHIP'   | 'CS-4702JB29'(!)        = 'End of Design' | 'Comp-Approve'     | 'CS-4702JB29'           |'R0402'| '(R0402-0201)'                 | '4.7'     | '5%'    | '1/16W'  | 'DISCRETE' | 'RES CHIP 4.7 1/16W +-5% (0402)'                   | 'CHIPR0402'    | ''          | ''            | '20180305'
 '4.7'        | '5%'      | '1/16W'  | '0402LF'  | 'EMPTY'  | 'CS-4702JB29'(!)        = 'End of Design' | 'Comp-Approve'     | 'CS-4702JB29'           |'R0402'| '(R0402-0201)'                 | '4.7'     | '5%'    | '1/16W'  | 'IO'       | 'RES CHIP 4.7 1/16W +-5% (0402)'                   | 'CHIPR0402'    | ''          | ''            | '20180305'
 '8.66K'      | '1%'      | '1/10W'  | '0603LF'  | 'CHIP'   | 'CS28663F911'(!)        = ''              | ''                 | 'CS28663F911'           |'R0603'| '(SMR0603AW)'                  | '8.66K'   | '1%'    | '1/10W'  | 'DISCRETE' | 'RES CHIP 8.66K 1/10W +-1% (0603)'                 | 'CHIP0603'     | ''          | ''            | '20180313'
 '8.66K'      | '1%'      | '1/10W'  | '0603LF'  | 'EMPTY'  | 'CS28663F911'(!)        = ''              | ''                 | 'CS28663F911'           |'R0603'| '(SMR0603AW)'                  | '8.66K'   | '1%'    | '1/10W'  | 'IO'       | 'RES CHIP 8.66K 1/10W +-1% (0603)'                 | 'CHIP0603'     | ''          | ''            | '20180313'
 '11.2K'      | '1%'      | '1/16W'  | '0402LF'  | 'CHIP'   | 'CS31122FB11'(!)        = 'End of Design' | 'Comp-Approve'     | 'CS31122FB11'           |'R0402'| '(R0402-0201)'                 | '11.2K'   | '1%'    | '1/16W'  | 'DISCRETE' | 'RES CHIP 11.2K 1/16W +-1% (0402)'                 | 'CHIP0402'     | ''          | ''            | '20180313'
 '11.2K'      | '1%'      | '1/16W'  | '0402LF'  | 'EMPTY'  | 'CS31122FB11'(!)        = 'End of Design' | 'Comp-Approve'     | 'CS31122FB11'           |'R0402'| '(R0402-0201)'                 | '11.2K'   | '1%'    | '1/16W'  | 'IO'       | 'RES CHIP 11.2K 1/16W +-1% (0402)'                 | 'CHIP0402'     | ''          | ''            | '20180313'
 '40.2K'      | '1%'      | '1/10W'  | '0603LF ' | 'CHIP'   | 'CS34023F911'(!)        = ''              | ''                 | 'CS34023F911'           |'R0603'| '(SMR0603AW)'                  | '40.2K'   | '1%'    | '1/10W'  | 'DISCRETE' | 'RESISTOR CHIP 40.2K 1/10W +-1%(0603)'             | 'CHIPR0603'    | ''          | ''            | '20180319'
 '40.2K'      | '1%'      | '1/10W'  | '0603LF ' | 'EMPTY'  | 'CS34023F911'(!)        = ''              | ''                 | 'CS34023F911'           |'R0603'| '(SMR0603AW)'                  | '40.2K'   | '1%'    | '1/10W'  | 'IO'       | 'RESISTOR CHIP 40.2K 1/10W +-1%(0603)'             | 'CHIPR0603'    | ''          | ''            | '20180319'
 '562'        | '1%'      | '1/16W'  | '0402LF'  | 'CHIP'   | 'CS15622FB16'(!)        = 'End of Design' | 'Comp-Approve'     | 'CS15622FB16'           |'R0402'| '(R0402-0201)'                 | '562'     | '1%'    | '1/16W'  | 'DISCRETE' | 'RES CHIP 562 1/16W +-1% (0402)'                   | 'CHIPR0402'    | ''          | ''            | '20180328'
 '562'        | '1%'      | '1/16W'  | '0402LF'  | 'EMPTY'  | 'CS15622FB16'(!)        = 'End of Design' | 'Comp-Approve'     | 'CS15622FB16'           |'R0402'| '(R0402-0201)'                 | '562'     | '1%'    | '1/16W'  | 'IO'       | 'RES CHIP 562 1/16W +-1% (0402)'                   | 'CHIPR0402'    | ''          | ''            | '20180328'
 '62K'        | '1%'      | '1/16W'  | '0402LF'  | 'CHIP'   | 'CS36202FB19'(!)        = 'End of Design' | 'Comp-Approve'     | 'CS36202FB19'           |'R0402'| '(R0402-0201)'                 | '62K'     | '1%'    | '1/16W'  | 'DISCRETE' | 'RES CHIP 62K 1/16W +-1%(0402)'                    | 'CHIPR0402'    | ''          | ''            | '20180316'
 '62K'        | '1%'      | '1/16W'  | '0402LF'  | 'EMPTY'  | 'CS36202FB19'(!)        = 'End of Design' | 'Comp-Approve'     | 'CS36202FB19'           |'R0402'| '(R0402-0201)'                 | '62K'     | '1%'    | '1/16W'  | 'IO'       | 'RES CHIP 62K 1/16W +-1%(0402)'                    | 'CHIPR0402'    | ''          | ''            | '20180316'
 '78.7K'      | '1%'      | '1/16W'  | '0402LF'  | 'CHIP'   | 'CS37872FB15'(!)        = 'End of Design' | 'Comp-Approve'     | 'CS37872FB15'           |'R0402'| '(R0402-0201)'                 | '78.7K'   | '1%'    | '1/16W'  | 'DISCRETE' | 'RES CHIP 78.7K 1/16W +-1%(0402)'                  | 'CHIPR0402'    | ''          | ''            | '20180402'
 '78.7K'      | '1%'      | '1/16W'  | '0402LF'  | 'EMPTY'  | 'CS37872FB15'(!)        = 'End of Design' | 'Comp-Approve'     | 'CS37872FB15'           |'R0402'| '(R0402-0201)'                 | '78.7K'   | '1%'    | '1/16W'  | 'IO'       | 'RES CHIP 78.7K 1/16W +-1%(0402)'                  | 'CHIPR0402'    | ''          | ''            | '20180402'
 '267K'       | '0.1%'    | '1/16W'  | '0402LF'  | 'CHIP'   | 'CS42672BB00'(!)        = ''              | ''                 | 'CS42672BB00'           |'R0402'| '(R0402-0201)'                 | '267K'    | '0.1%'  | '1/16W'  | 'DISCRETE' | 'RES CHIP 267K 1/16W +-0.1%(0402)'                 | 'CHIPR0402'    | ''          | ''            | '20180418'
 '267K'       | '0.1%'    | '1/16W'  | '0402LF'  | 'EMPTY'  | 'CS42672BB00'(!)        = ''              | ''                 | 'CS42672BB00'           |'R0402'| '(R0402-0201)'                 | '267K'    | '0.1%'  | '1/16W'  | 'IO'       | 'RES CHIP 267K 1/16W +-0.1%(0402)'                 | 'CHIPR0402'    | ''          | ''            | '20180418'
 '549'        | '1%'      | '1/4W'   | '1206LF'  | 'CHIP'   | 'CS15496F200'(!)        = ''              | ''                 | 'CS15496F200'           |'R1206XF'| '(SMR1206AW)'                  | '549'     | '1%'    | '1/4W'   | 'DISCRETE' | 'RES CHIP 549 1/4W 1%(1206)'                       | 'CHIPR1206'    | ''          | ''            | '20180418'
 '549'        | '1%'      | '1/4W'   | '1206LF'  | 'EMPTY'  | 'CS15496F200'(!)        = ''              | ''                 | 'CS15496F200'           |'R1206XF'| '(SMR1206AW)'                  | '549'     | '1%'    | '1/4W'   | 'IO'       | 'RES CHIP 549 1/4W 1%(1206)'                       | 'CHIPR1206'    | ''          | ''            | '20180418'
 '243K'       | '1%'      | '1/16W'  | '0402LF'  | 'CHIP'   | 'CS42432FB02'(!)        = 'End of Design' | 'Comp-Approve'     | 'CS42432FB02'           |'R0402'| '(R0402-0201)'                 | '243K'    | '1%'    | '1/16W'  | 'DISCRETE' | 'RES CHIP 243K 1/16W +-1%(0402)'                   | 'CHIPR0402'    | ''          | ''            | '20180420'
 '243K'       | '1%'      | '1/16W'  | '0402LF'  | 'EMPTY'  | 'CS42432FB02'(!)        = 'End of Design' | 'Comp-Approve'     | 'CS42432FB02'           |'R0402'| '(R0402-0201)'                 | '243K'    | '1%'    | '1/16W'  | 'IO'       | 'RES CHIP 243K 1/16W +-1%(0402)'                   | 'CHIPR0402'    | ''          | ''            | '20180420'
 '147K'       | '1%'      | '1/8W'   | '0805LF'  | 'CHIP'   | 'CS41474FA00'(!)        = ''              | ''                 | 'CS41474FA00'           |'R0805'| '(SMR0805AW)'                  | '147K'    | '1%'    | '1/8W'   | 'DISCRETE' | 'RES CHIP 147K 1/8W +-1%(0805)'                    | 'CHIPR0805'    | ''          | ''            | '20180424'
 '147K'       | '1%'      | '1/8W'   | '0805LF'  | 'EMPTY'  | 'CS41474FA00'(!)        = ''              | ''                 | 'CS41474FA00'           |'R0805'| '(SMR0805AW)'                  | '147K'    | '1%'    | '1/8W'   | 'IO'       | 'RES CHIP 147K 1/8W +-1%(0805)'                    | 'CHIPR0805'    | ''          | ''            | '20180424'
 '1.54K'      | '1%'      | '1/16W'  | '0402LF'  | 'CHIP'   | 'TMP_QCS21542FB00'(!)   = 'End of Design' | 'Comp-Approve'     | 'CS21542FB00'           |'R0402'| '(R0402-0201)'                 | '1.54K'   | '1%'    | '1/16W'  | 'DISCRETE' | 'RES CHIP 1.54K 1/16W +-1%(0402)'                  | 'CHIP0402'     | ''          | ''            | ''        
 '1.54K'      | '1%'      | '1/16W'  | '0402LF'  | 'EMPTY'  | 'TMP_QCS21542FB00'(!)   = 'End of Design' | 'Comp-Approve'     | 'CS21542FB00'           |'R0402'| '(R0402-0201)'                 | '1.54K'   | '1%'    | '1/16W'  | 'IO'       | 'RES CHIP 1.54K 1/16W +-1%(0402)'                  | 'CHIP0402'     | ''          | ''            | ''        
 '6.19K'      | '1%'      | '1/16W'  | '0402LF'  | 'CHIP'   | 'TMP_QCS26192FB14'(!)   = 'End of Design' | 'Comp-Approve'     | 'CS26192FB14'           |'R0402'| '(R0402-0201)'                 | '6.19K'   | '1%'    | '1/16W'  | 'DISCRETE' | 'RES CHIP 6.19K 1/16W +-1%  (0402)'                | 'CHIP0402'     | ''          | ''            | ''        
 '6.19K'      | '1%'      | '1/16W'  | '0402LF'  | 'EMPTY'  | 'TMP_QCS26192FB14'(!)   = 'End of Design' | 'Comp-Approve'     | 'CS26192FB14'           |'R0402'| '(R0402-0201)'                 | '6.19K'   | '1%'    | '1/16W'  | 'IO'       | 'RES CHIP 6.19K 1/16W +-1%  (0402)'                | 'CHIP0402'     | ''          | ''            | ''        
 '47K'        | '1%'      | '1/16W'  | '0402LF'  | 'CHIP'   | 'TMP_QCS34702FB11'(!)   = 'End of Design' | 'Comp-Release Qty' | 'CS34702FB11'           |'R0402'| '(R0402-0201)'                 | '47K'     | '1%'    | '1/16W'  | 'DISCRETE' | 'RES CHIP 47K 1/16W +-1% (0402)'                   | 'CHIP0402'     | ''          | ''            | ''        
 '47K'        | '1%'      | '1/16W'  | '0402LF'  | 'EMPTY'  | 'TMP_QCS34702FB11'(!)   = 'End of Design' | 'Comp-Release Qty' | 'CS34702FB11'           |'R0402'| '(R0402-0201)'                 | '47K'     | '1%'    | '1/16W'  | 'IO'       | 'RES CHIP 47K 1/16W +-1% (0402)'                   | 'CHIP0402'     | ''          | ''            | ''        
 '10K'        | '5%'      | '1/16W'  | '0402LF'  | 'CHIP'   | 'TMP_QCS31002JB28'(!)   = 'End of Design' | 'Comp-Approve'     | 'CS31002JB28'           |'R0402'| '(R0402-0201)'                 | '10K'     | '5%'    | '1/16W'  | 'DISCRETE' | 'RES CHIP 10K 1/16W 5%(0402)'                      | 'CHIP0402'     | ''          | ''            | ''        
 '10K'        | '5%'      | '1/16W'  | '0402LF'  | 'EMPTY'  | 'TMP_QCS31002JB28'(!)   = 'End of Design' | 'Comp-Approve'     | 'CS31002JB28'           |'R0402'| '(R0402-0201)'                 | '10K'     | '5%'    | '1/16W'  | 'IO'       | 'RES CHIP 10K 1/16W 5%(0402)'                      | 'CHIP0402'     | ''          | ''            | ''        
 '1K'         | '1%'      | '1/16W'  | '0402LF'  | 'CHIP'   | 'TMP_QCS21002FB24'(!)   = 'End of Design' | 'Comp-Approve'     | 'CS21002FB24'           |'R0402'| '(R0402-0201)'                 | '1K'      | '1%'    | '1/16W'  | 'DISCRETE' | 'RES CHIP 1K 1/16W +-1% (0402)'                    | 'CHIP0402'     | ''          | ''            | ''        
 '1K'         | '1%'      | '1/16W'  | '0402LF'  | 'EMPTY'  | 'TMP_QCS21002FB24'(!)   = 'End of Design' | 'Comp-Approve'     | 'CS21002FB24'           |'R0402'| '(R0402-0201)'                 | '1K'      | '1%'    | '1/16W'  | 'IO'       | 'RES CHIP 1K 1/16W +-1% (0402)'                    | 'CHIP0402'     | ''          | ''            | ''        
 '0'          | '5%'      | '1/10W'  | '0603'    | 'CHIP'   | 'TMP_QCS00003J951'(!)   = ''              | ''                 | 'CS00003J951'           |'R0603'| '(SMR0603AW)'                  | '0'       | '5%'    | '1/10W'  | 'DISCRETE' | 'RESISTOR CHIP 0 1/10W+-5%(0603)'                  | 'CHIP0603'     | ''          | ''            | ''        
 '0'          | '5%'      | '1/10W'  | '0603'    | 'EMPTY'  | 'TMP_QCS00003J951'(!)   = ''              | ''                 | 'CS00003J951'           |'R0603'| '(SMR0603AW)'                  | '0'       | '5%'    | '1/10W'  | 'IO'       | 'RESISTOR CHIP 0 1/10W+-5%(0603)'                  | 'CHIP0603'     | ''          | ''            | ''        
 '3.4M'       | '1%'      | '1/8W'   | '0805LF'  | 'CHIP'   | 'CS53404FA00'(!)        = ''              | ''                 | 'CS53404FA00'           |'R0805'| '(SMR0805AW)'                  | '3.4M'    | '1%'    | '1/8W'   | 'DISCRETE' | 'RES CHIP 3.4M 1/8W +-1%(0805)'                    | 'CHIPR0805'    | ''          | ''            | '20180502'
 '3.4M'       | '1%'      | '1/8W'   | '0805LF'  | 'EMPTY'  | 'CS53404FA00'(!)        = ''              | ''                 | 'CS53404FA00'           |'R0805'| '(SMR0805AW)'                  | '3.4M'    | '1%'    | '1/8W'   | 'IO'       | 'RES CHIP 3.4M 1/8W +-1%(0805)'                    | 'CHIPR0805'    | ''          | ''            | '20180502'
 '0.006'      | '1%'      | '1W'     | '1206LF'  | 'CHIP'   | 'CS+0068F200'(!)        = ''              | ''                 | 'CS+0068F200'           |'R1206XI_H18'| '(SMR1206AW)'                  | '0.006'   | '1%'    | '1W'     | 'DISCRETE' | 'RES CHIP 0.006 1W +-1%(1206)EF'                   | 'CHIPR1206'    | ''          | ''            | '20180514'
 '0.006'      | '1%'      | '1W'     | '1206LF'  | 'EMPTY'  | 'CS+0068F200'(!)        = ''              | ''                 | 'CS+0068F200'           |'R1206XI_H18'| '(SMR1206AW)'                  | '0.006'   | '1%'    | '1W'     | 'IO'       | 'RES CHIP 0.006 1W +-1%(1206)EF'                   | 'CHIPR1206'    | ''          | ''            | '20180514'
 '1.47M'      | '1%'      | '1/8W'   | '0805LF'  | 'CHIP'   | 'CS51474FA00'(!)        = ''              | ''                 | 'CS51474FA00'           |'R0805'| '(SMR0805AW)'                  | '1.47M'   | '1%'    | '1/8W'   | 'DISCRETE' | 'RES CHIP 1.47M 1/8W +-1%(0805)'                   | 'CHIPR0805'    | ''          | ''            | '20180514'
 '1.47M'      | '1%'      | '1/8W'   | '0805LF'  | 'EMPTY'  | 'CS51474FA00'(!)        = ''              | ''                 | 'CS51474FA00'           |'R0805'| '(SMR0805AW)'                  | '1.47M'   | '1%'    | '1/8W'   | 'IO'       | 'RES CHIP 1.47M 1/8W +-1%(0805)'                   | 'CHIPR0805'    | ''          | ''            | '20180514'
 '2.05M'      | '1%'      | '1/8W'   | '0805LF'  | 'CHIP'   | 'CS52054FA00'(!)        = ''              | ''                 | 'CS52054FA00'           |'R0805'| '(SMR0805AW)'                  | '2.05M'   | '1%'    | '1/8W'   | 'DISCRETE' | 'RES CHIP 2.05M 1/8W +-1%(0805)'                   | 'CHIPR0805'    | ''          | ''            | '20180515'
 '2.05M'      | '1%'      | '1/8W'   | '0805LF'  | 'EMPTY'  | 'CS52054FA00'(!)        = ''              | ''                 | 'CS52054FA00'           |'R0805'| '(SMR0805AW)'                  | '2.05M'   | '1%'    | '1/8W'   | 'IO'       | 'RES CHIP 2.05M 1/8W +-1%(0805)'                   | 'CHIPR0805'    | ''          | ''            | '20180515'
 '30.9K'      | '1%'      | '1/16W'  | '0402LF'  | 'CHIP'   | 'CS33092FB06'(!)        = 'End of Design' | 'Comp-Approve'     | 'CS33092FB06'           |'R0402'| '(R0402-0201)'                 | '30.9K'   | '1%'    | '1/16W'  | 'DISCRETE' | 'RES CHIP 30.9K 1/16W +-1%(0402)'                  | 'CHIPR0402'    | ''          | ''            | '20130510'
 '30.9K'      | '1%'      | '1/16W'  | '0402LF'  | 'EMPTY'  | 'CS33092FB06'(!)        = 'End of Design' | 'Comp-Approve'     | 'CS33092FB06'           |'R0402'| '(R0402-0201)'                 | '30.9K'   | '1%'    | '1/16W'  | 'IO'       | 'RES CHIP 30.9K 1/16W +-1%(0402)'                  | 'CHIPR0402'    | ''          | ''            | '20130510'
 '66.5K'      | '1%'      | '1/16W'  | '0402LF'  | 'CHIP'   | 'TMP_QCS36652FB16'(!)   = 'End of Design' | 'Comp-Approve'     | 'CS36652FB16'           |'R0402'| '(R0402-0201)'                 | '66.5K'   | '1%'    | '1/16W'  | 'DISCRETE' | 'RES CHIP 66.5K 1/16W +-1%(0402)'                  | 'CHIP0402'     | ''          | ''            | ''        
 '66.5K'      | '1%'      | '1/16W'  | '0402LF'  | 'EMPTY'  | 'TMP_QCS36652FB16'(!)   = 'End of Design' | 'Comp-Approve'     | 'CS36652FB16'           |'R0402'| '(R0402-0201)'                 | '66.5K'   | '1%'    | '1/16W'  | 'IO'       | 'RES CHIP 66.5K 1/16W +-1%(0402)'                  | 'CHIP0402'     | ''          | ''            | ''        
 '7.87'       | '1%'      | '1/16W'  | '0402LF'  | 'CHIP'   | 'CS-7872FB00'(!)        = ''              | ''                 | 'CS-7872FB00'           |'R0402'| '(R0402-0201)'                 | '7.87'    | '1%'    | '1/16W'  | 'DISCRETE' | 'RES CHIP 7.87 1/16W +-1%(0402)'                   | 'CHIPR0402'    | ''          | ''            | '20180522'
 '7.87'       | '1%'      | '1/16W'  | '0402LF'  | 'EMPTY'  | 'CS-7872FB00'(!)        = ''              | ''                 | 'CS-7872FB00'           |'R0402'| '(R0402-0201)'                 | '7.87'    | '1%'    | '1/16W'  | 'IO'       | 'RES CHIP 7.87 1/16W +-1%(0402)'                   | 'CHIPR0402'    | ''          | ''            | '20180522'
 '0.5'        | '1%'      | '2W'     | '2512LF'  | 'CHIP'   | 'CS+500AFR00'(!)        = ''              | ''                 | 'CS+500AFR00'           |'R2512XA'| '(SMR2512AW)'                  | '0.5'     | '1%'    | '2W'     | 'DISCRETE' | 'RES CHIP 0.5 2W +-1%(2512)'                       | 'CHIPR2512'    | ''          | ''            | '20180523'
 '0.5'        | '1%'      | '2W'     | '2512LF'  | 'EMPTY'  | 'CS+500AFR00'(!)        = ''              | ''                 | 'CS+500AFR00'           |'R2512XA'| '(SMR2512AW)'                  | '0.5'     | '1%'    | '2W'     | 'IO'       | 'RES CHIP 0.5 2W +-1%(2512)'                       | 'CHIPR2512'    | ''          | ''            | '20180523'
 '1.5'        | '1%'      | '1/8W'   | '0402LF'  | 'CHIP'   | 'CS-1504FB00'(!)        = ''              | ''                 | 'CS-1504FB00'           |'R0402'| '(R0402-0201)'                 | '1.5'     | '1%'    | '1/8W'   | 'DISCRETE' | 'RES CHIP 1.5 1/8W +-1%(0402)'                     | 'CHIPR0402'    | ''          | ''            | '20180523'
 '1.5'        | '1%'      | '1/8W'   | '0402LF'  | 'EMPTY'  | 'CS-1504FB00'(!)        = ''              | ''                 | 'CS-1504FB00'           |'R0402'| '(R0402-0201)'                 | '1.5'     | '1%'    | '1/8W'   | 'IO'       | 'RES CHIP 1.5 1/8W +-1%(0402)'                     | 'CHIPR0402'    | ''          | ''            | '20180523'
 '1'          | '1%'      | '1/8W'   | '0402LF'  | 'CHIP'   | 'CS-1004FB00'(!)        = ''              | ''                 | 'CS-1004FB00'           |'R0402'| '(R0402-0201)'                 | '1'       | '1%'    | '1/8W'   | 'DISCRETE' | 'RES CHIP 1 1/8W +-1%(0402)'                       | 'CHIPR0402'    | ''          | ''            | '20180523'
 '1'          | '1%'      | '1/8W'   | '0402LF'  | 'EMPTY'  | 'CS-1004FB00'(!)        = ''              | ''                 | 'CS-1004FB00'           |'R0402'| '(R0402-0201)'                 | '1'       | '1%'    | '1/8W'   | 'IO'       | 'RES CHIP 1 1/8W +-1%(0402)'                       | 'CHIPR0402'    | ''          | ''            | '20180523'
 '365K'       | '1%'      | '1/16W'  | '0402LF'  | 'CHIP'   | 'CS43652FB10'(!)        = 'End of Design' | 'Comp-Approve'     | 'CS43652FB10'           |'R0402'| '(R0402-0201)'                 | '365K'    | '1%'    | '1/16W'  | 'DISCRETE' | 'RES CHIP 365K 1/16W +-1%(0402)'                   | 'CHIPR0402'    | ''          | ''            | '20180704'
 '365K'       | '1%'      | '1/16W'  | '0402LF'  | 'EMPTY'  | 'CS43652FB10'(!)        = 'End of Design' | 'Comp-Approve'     | 'CS43652FB10'           |'R0402'| '(R0402-0201)'                 | '365K'    | '1%'    | '1/16W'  | 'IO'       | 'RES CHIP 365K 1/16W +-1%(0402)'                   | 'CHIPR0402'    | ''          | ''            | '20180704'
 '100K'       | '0.1%'    | '1/8W'   | '0805LF'  | 'CHIP'   | 'CS41004BA01'(!)        = ''              | ''                 | 'CS41004BA01'           |'R0805'| '(SMR0805AW)'                  | '100K'    | '0.1%'  | '1/8W'   | 'DISCRETE' | 'RES CHIP 100K 1/8W +-0.1%(0805)'                  | 'CHIPR0805'    | ''          | ''            | '20180704'
 '100K'       | '0.1%'    | '1/8W'   | '0805LF'  | 'EMPTY'  | 'CS41004BA01'(!)        = ''              | ''                 | 'CS41004BA01'           |'R0805'| '(SMR0805AW)'                  | '100K'    | '0.1%'  | '1/8W'   | 'IO'       | 'RES CHIP 100K 1/8W +-0.1%(0805)'                  | 'CHIPR0805'    | ''          | ''            | '20180704'
 '100K'       | '1%'      | '1/8W'   | '0805LF'  | 'CHIP'   | 'CS41004FA00'(!)        = 'End of Design' | 'Comp-Approve'     | 'CS41004FA00'           |'R0805'| '(SMR0805AW)'                  | '100K'    | '1%'    | '1/8W'   | 'DISCRETE' | 'RESISTOR CHIP 100K 1/8W+-1%(0805)'                | 'CHIPR0805'    | ''          | ''            | '20170927'
 '100K'       | '1%'      | '1/8W'   | '0805LF'  | 'EMPTY'  | 'CS41004FA00'(!)        = 'End of Design' | 'Comp-Approve'     | 'CS41004FA00'           |'R0805'| '(SMR0805AW)'                  | '100K'    | '1%'    | '1/8W'   | 'IO'       | 'RESISTOR CHIP 100K 1/8W+-1%(0805)'                | 'CHIPR0805'    | ''          | ''            | '20170927'
 '0'          | '1%'      | '1/16W'  | '0402LF'  | 'CHIP'   | 'TMP_QCS00002FB00'(!)   = 'End of Design' | 'Comp-Approve'     | 'CS00002FB00'           |'R0402'| '(R0402-0201)'                 | '0'       | '1%'    | '1/16W'  | 'DISCRETE' | 'RES CHIP 0 1/16W +-1%(0402)'                      | 'CHIP0402'     | ''          | ''            | ''        
 '0'          | '1%'      | '1/16W'  | '0402LF'  | 'EMPTY'  | 'TMP_QCS00002FB00'(!)   = 'End of Design' | 'Comp-Approve'     | 'CS00002FB00'           |'R0402'| '(R0402-0201)'                 | '0'       | '1%'    | '1/16W'  | 'IO'       | 'RES CHIP 0 1/16W +-1%(0402)'                      | 'CHIP0402'     | ''          | ''            | ''        
 '549K'       | '1%'      | '1/16W'  | '0402LF'  | 'CHIP'   | 'CS45492FB08'(!)        = ''              | ''                 | 'CS45492FB08'           |'R0402'| '(R0402-0201)'                 | '549K'    | '1%'    | '1/16W'  | 'DISCRETE' | 'RES CHIP 549K 1/16W +-1%(0402)'                   | 'CHIPR0402'    | ''          | ''            | '20180709'
 '549K'       | '1%'      | '1/16W'  | '0402LF'  | 'EMPTY'  | 'CS45492FB08'(!)        = ''              | ''                 | 'CS45492FB08'           |'R0402'| '(R0402-0201)'                 | '549K'    | '1%'    | '1/16W'  | 'IO'       | 'RES CHIP 549K 1/16W +-1%(0402)'                   | 'CHIPR0402'    | ''          | ''            | '20180709'
 '1.5K'       | '5%'      | '1/8W'   | '0805LF'  | 'CHIP'   | 'CS21504JA02'(!)        = ''              | ''                 | 'CS21504JA02'           |'R0805_H26'| '(SMR0805AW)'                  | '1.5K'    | '5%'    | '1/8W'   | 'DISCRETE' | 'RES CHIP 1.5K 1/8W +-5%(0805)'                    | 'CHIPR0805'    | ''          | ''            | '20180720'
 '1.5K'       | '5%'      | '1/8W'   | '0805LF'  | 'EMPTY'  | 'CS21504JA02'(!)        = ''              | ''                 | 'CS21504JA02'           |'R0805_H26'| '(SMR0805AW)'                  | '1.5K'    | '5%'    | '1/8W'   | 'IO'       | 'RES CHIP 1.5K 1/8W +-5%(0805)'                    | 'CHIPR0805'    | ''          | ''            | '20180720'
 '15'         | '5%'      | '1/16W'  | '0402LF'  | 'CHIP'   | 'CS01502JB12'(!)        = 'End of Design' | 'Comp-Approve'     | 'CS01502JB12'           |'R0402'| '(R0402-0201)'                 | '15'      | '5%'    | '1/16W'  | 'DISCRETE' | 'RES CHIP 15 1/16W +-5%(0402)L-F'                  | 'CHIPR0402'    | ''          | ''            | '20180720'
 '15'         | '5%'      | '1/16W'  | '0402LF'  | 'EMPTY'  | 'CS01502JB12'(!)        = 'End of Design' | 'Comp-Approve'     | 'CS01502JB12'           |'R0402'| '(R0402-0201)'                 | '15'      | '5%'    | '1/16W'  | 'IO'       | 'RES CHIP 15 1/16W +-5%(0402)L-F'                  | 'CHIPR0402'    | ''          | ''            | '20180720'
 '95.3K'      | '1%'      | '1/4W'   | '1206LF'  | 'CHIP'   | 'CS39536F200'(!)        = ''              | ''                 | 'CS39536F200'           |'R1206XJ'| '(SMR1206AW)'                  | '95.3K'   | '1%'    | '1/4W'   | 'DISCRETE' | 'RES CHIP 95.3K 1/4W +-1%(1206)'                   | 'CHIPR1206'    | ''          | ''            | '20180725'
 '95.3K'      | '1%'      | '1/4W'   | '1206LF'  | 'EMPTY'  | 'CS39536F200'(!)        = ''              | ''                 | 'CS39536F200'           |'R1206XJ'| '(SMR1206AW)'                  | '95.3K'   | '1%'    | '1/4W'   | 'IO'       | 'RES CHIP 95.3K 1/4W +-1%(1206)'                   | 'CHIPR1206'    | ''          | ''            | '20180725'
 '100'        | '1%'      | '1/8W'   | '0805LF'  | 'CHIP'   | 'CS11004FA34'(!)        = ''              | ''                 | 'CS11004FA34'           |'R0805_H26'| '(SMR0805AW)'                  | '100'     | '1%'    | '1/8W'   | 'DISCRETE' | 'RES CHIP 100 1/8W +-1%(0805)'                     | 'CHIPR0805'    | ''          | ''            | '20180802'
 '100'        | '1%'      | '1/8W'   | '0805LF'  | 'EMPTY'  | 'CS11004FA34'(!)        = ''              | ''                 | 'CS11004FA34'           |'R0805_H26'| '(SMR0805AW)'                  | '100'     | '1%'    | '1/8W'   | 'IO'       | 'RES CHIP 100 1/8W +-1%(0805)'                     | 'CHIPR0805'    | ''          | ''            | '20180802'
 '10'         | '5%'      | '1/20W'  | '0201LF'  | 'CHIP'   | 'CS01001JE11'(!)        = ''              | ''                 | 'CS01001JE11'           |'R0201'| '(SMR0201AW)'                  | '10'      | '5%'    | '1/20W'  | 'DISCRETE' | 'RES CHIP 10(1/20W,+-5%,0201)'                     | 'CHIPR0201'    | ''          | ''            | '20180802'
 '10'         | '5%'      | '1/20W'  | '0201LF'  | 'EMPTY'  | 'CS01001JE11'(!)        = ''              | ''                 | 'CS01001JE11'           |'R0201'| '(SMR0201AW)'                  | '10'      | '5%'    | '1/20W'  | 'IO'       | 'RES CHIP 10(1/20W,+-5%,0201)'                     | 'CHIPR0201'    | ''          | ''            | '20180802'
 '22.0'       | '1%'      | '1/20W'  | '0201LF'  | 'CHIP'   | 'CS02201FE00'(!)        = ''              | ''                 | 'CS02201FE00'           |'R0201'| '(SMR0201AW)'                  | '22.0'    | '1%'    | '1/20W'  | 'DISCRETE' | 'RES CHIP 22.0 1/20W +-1%(0201)'                   | 'CHIPR0201'    | ''          | ''            | '20150324'
 '22.0'       | '1%'      | '1/20W'  | '0201LF'  | 'EMPTY'  | 'CS02201FE00'(!)        = ''              | ''                 | 'CS02201FE00'           |'R0201'| '(SMR0201AW)'                  | '22.0'    | '1%'    | '1/20W'  | 'IO'       | 'RES CHIP 22.0 1/20W +-1%(0201)'                   | 'CHIPR0201'    | ''          | ''            | '20150324'
 '60.4'       | '1%'      | '1/20W'  | '0201LF'  | 'CHIP'   | 'CS06041FE00'(!)        = ''              | ''                 | 'CS06041FE00'           |'R0201'| '(SMR0201AW)'                  | '60.4'    | '1%'    | '1/20W'  | 'DISCRETE' | 'RES CHIP 60.4 1/20W,+-1%(0201)'                   | 'CHIPR0201'    | ''          | ''            | '20120209'
 '60.4'       | '1%'      | '1/20W'  | '0201LF'  | 'EMPTY'  | 'CS06041FE00'(!)        = ''              | ''                 | 'CS06041FE00'           |'R0201'| '(SMR0201AW)'                  | '60.4'    | '1%'    | '1/20W'  | 'IO'       | 'RES CHIP 60.4 1/20W,+-1%(0201)'                   | 'CHIPR0201'    | ''          | ''            | '20120209'
 '150'        | '1%'      | '1/20W'  | '0201LF'  | 'CHIP'   | 'CS11501FE01'(!)        = ''              | ''                 | 'CS11501FE01'           |'R0201'| '(SMR0201AW)'                  | '150'     | '1%'    | '1/20W'  | 'DISCRETE' | 'RES CHIP 150 1/20W +-1%(0201)'                    | 'CHIPR0201'    | ''          | ''            | '20170825'
 '150'        | '1%'      | '1/20W'  | '0201LF'  | 'EMPTY'  | 'CS11501FE01'(!)        = ''              | ''                 | 'CS11501FE01'           |'R0201'| '(SMR0201AW)'                  | '150'     | '1%'    | '1/20W'  | 'IO'       | 'RES CHIP 150 1/20W +-1%(0201)'                    | 'CHIPR0201'    | ''          | ''            | '20170825'
 '22.1'       | '1%'      | '1/20W'  | '0201LF'  | 'CHIP'   | 'CS02211FE01'(!)        = ''              | ''                 | 'CS02211FE01'           |'R0201'| '(SMR0201AW)'                  | '22.1'    | '1%'    | '1/20W'  | 'DISCRETE' | 'RES CHIP 22.1 1/20W(+-1%,0201)'                   | 'CHIPR0201'    | ''          | ''            | '20180803'
 '22.1'       | '1%'      | '1/20W'  | '0201LF'  | 'EMPTY'  | 'CS02211FE01'(!)        = ''              | ''                 | 'CS02211FE01'           |'R0201'| '(SMR0201AW)'                  | '22.1'    | '1%'    | '1/20W'  | 'IO'       | 'RES CHIP 22.1 1/20W(+-1%,0201)'                   | 'CHIPR0201'    | ''          | ''            | '20180803'
 '33'         | '5%'      | '1/20W'  | '0201LF'  | 'CHIP'   | 'CS03301JE09'(!)        = ''              | ''                 | 'CS03301JE09'           |'R0201'| '(SMR0201AW)'                  | '33'      | '5%'    | '1/20W'  | 'DISCRETE' | 'RES CHIP 33 1/20W +-5%(0201)'                     | 'CHIPR0201'    | ''          | ''            | '20180803'
 '33'         | '5%'      | '1/20W'  | '0201LF'  | 'EMPTY'  | 'CS03301JE09'(!)        = ''              | ''                 | 'CS03301JE09'           |'R0201'| '(SMR0201AW)'                  | '33'      | '5%'    | '1/20W'  | 'IO'       | 'RES CHIP 33 1/20W +-5%(0201)'                     | 'CHIPR0201'    | ''          | ''            | '20180803'
 '33.2'       | '1%'      | '1/20W'  | '0201LF'  | 'CHIP'   | 'CS03321FE00'(!)        = ''              | ''                 | 'CS03321FE00'           |'R0201'| '(SMR0201AW)'                  | '33.2'    | '1%'    | '1/20W'  | 'DISCRETE' | 'RES CHIP 33.2 1/20W +-1%(0201)'                   | 'CHIPR0201'    | ''          | ''            | '20180803'
 '33.2'       | '1%'      | '1/20W'  | '0201LF'  | 'EMPTY'  | 'CS03321FE00'(!)        = ''              | ''                 | 'CS03321FE00'           |'R0201'| '(SMR0201AW)'                  | '33.2'    | '1%'    | '1/20W'  | 'IO'       | 'RES CHIP 33.2 1/20W +-1%(0201)'                   | 'CHIPR0201'    | ''          | ''            | '20180803'
 '75'         | '1%'      | '1/20W'  | '0201LF'  | 'CHIP'   | 'CS07501FE05'(!)        = ''              | ''                 | 'CS07501FE05'           |'R0201'| '(SMR0201AW)'                  | '75'      | '1%'    | '1/20W'  | 'DISCRETE' | 'RES CHIP 75 1/20W +-1%(0201)'                     | 'CHIPR0201'    | ''          | ''            | '20180803'
 '75'         | '1%'      | '1/20W'  | '0201LF'  | 'EMPTY'  | 'CS07501FE05'(!)        = ''              | ''                 | 'CS07501FE05'           |'R0201'| '(SMR0201AW)'                  | '75'      | '1%'    | '1/20W'  | 'IO'       | 'RES CHIP 75 1/20W +-1%(0201)'                     | 'CHIPR0201'    | ''          | ''            | '20180803'
 '120'        | '1%'      | '1/20W'  | '0201LF'  | 'CHIP'   | 'CS11201FE01'(!)        = 'End of Design' | 'Comp-Release Qty' | 'CS11201FE01'           |'R0201'| '(SMR0201AW)'                  | '120'     | '1%'    | '1/20W'  | 'DISCRETE' | 'RES CHIP 120 1/20W +-1%(0201)'                    | 'CHIPR0201'    | ''          | ''            | '20180803'
 '120'        | '1%'      | '1/20W'  | '0201LF'  | 'EMPTY'  | 'CS11201FE01'(!)        = 'End of Design' | 'Comp-Release Qty' | 'CS11201FE01'           |'R0201'| '(SMR0201AW)'                  | '120'     | '1%'    | '1/20W'  | 'IO'       | 'RES CHIP 120 1/20W +-1%(0201)'                    | 'CHIPR0201'    | ''          | ''            | '20180803'
 '220'        | '1%'      | '1/20W'  | '0201LF'  | 'CHIP'   | 'CS12201FE11'(!)        = 'End of Design' | 'Comp-Approve'     | 'CS12201FE11'           |'R0201'| '(SMR0201AW)'                  | '220'     | '1%'    | '1/20W'  | 'DISCRETE' | 'RES CHIP 220(1/20W,+-1%,0201)'                    | 'CHIPR0201'    | ''          | ''            | '20180803'
 '220'        | '1%'      | '1/20W'  | '0201LF'  | 'EMPTY'  | 'CS12201FE11'(!)        = 'End of Design' | 'Comp-Approve'     | 'CS12201FE11'           |'R0201'| '(SMR0201AW)'                  | '220'     | '1%'    | '1/20W'  | 'IO'       | 'RES CHIP 220(1/20W,+-1%,0201)'                    | 'CHIPR0201'    | ''          | ''            | '20180803'
 '221'        | '1%'      | '1/20W'  | '0201LF'  | 'CHIP'   | 'CS12211FE07'(!)        = ''              | ''                 | 'CS12211FE07'           |'R0201'| '(SMR0201AW)'                  | '221'     | '1%'    | '1/20W'  | 'DISCRETE' | 'RES CHIP 221 1/20W +-1%(0201)'                    | 'CHIPR0201'    | ''          | ''            | '20180803'
 '221'        | '1%'      | '1/20W'  | '0201LF'  | 'EMPTY'  | 'CS12211FE07'(!)        = ''              | ''                 | 'CS12211FE07'           |'R0201'| '(SMR0201AW)'                  | '221'     | '1%'    | '1/20W'  | 'IO'       | 'RES CHIP 221 1/20W +-1%(0201)'                    | 'CHIPR0201'    | ''          | ''            | '20180803'
 '300'        | '5%'      | '1/20W'  | '0201LF'  | 'CHIP'   | 'CS13001JE00'(!)        = ''              | ''                 | 'CS13001JE00'           |'R0201'| '(SMR0201AW)'                  | '300'     | '5%'    | '1/20W'  | 'DISCRETE' | 'RES CHIP 300 1/20W +-5%(0201)'                    | 'CHIPR0201'    | ''          | ''            | '20180803'
 '300'        | '5%'      | '1/20W'  | '0201LF'  | 'EMPTY'  | 'CS13001JE00'(!)        = ''              | ''                 | 'CS13001JE00'           |'R0201'| '(SMR0201AW)'                  | '300'     | '5%'    | '1/20W'  | 'IO'       | 'RES CHIP 300 1/20W +-5%(0201)'                    | 'CHIPR0201'    | ''          | ''            | '20180803'
 '330'        | '5%'      | '1/20W'  | '0201LF'  | 'CHIP'   | 'CS13301JE00'(!)        = ''              | ''                 | 'CS13301JE00'           |'R0201'| '(SMR0201AW)'                  | '330'     | '5%'    | '1/20W'  | 'DISCRETE' | 'RES CHIP 330 1/20W +-5%(0201)'                    | 'CHIPR0201'    | ''          | ''            | '20180803'
 '330'        | '5%'      | '1/20W'  | '0201LF'  | 'EMPTY'  | 'CS13301JE00'(!)        = ''              | ''                 | 'CS13301JE00'           |'R0201'| '(SMR0201AW)'                  | '330'     | '5%'    | '1/20W'  | 'IO'       | 'RES CHIP 330 1/20W +-5%(0201)'                    | 'CHIPR0201'    | ''          | ''            | '20180803'
 '332'        | '1%'      | '1/20W'  | '0201LF'  | 'CHIP'   | 'CS13321FE01'(!)        = ''              | ''                 | 'CS13321FE01'           |'R0201'| '(SMR0201AW)'                  | '332'     | '1%'    | '1/20W'  | 'DISCRETE' | 'RES CHIP 332 1/20W +-1%(0201)'                    | 'CHIPR0201'    | ''          | ''            | '20180803'
 '332'        | '1%'      | '1/20W'  | '0201LF'  | 'EMPTY'  | 'CS13321FE01'(!)        = ''              | ''                 | 'CS13321FE01'           |'R0201'| '(SMR0201AW)'                  | '332'     | '1%'    | '1/20W'  | 'IO'       | 'RES CHIP 332 1/20W +-1%(0201)'                    | 'CHIPR0201'    | ''          | ''            | '20180803'
 '475'        | '1%'      | '1/20W'  | '0201LF'  | 'CHIP'   | 'CS14751FE00'(!)        = ''              | ''                 | 'CS14751FE00'           |'R0201'| '(SMR0201AW)'                  | '475'     | '1%'    | '1/20W'  | 'DISCRETE' | 'RES CHIP 475 1/20W,+-1%(0201)'                    | 'CHIPR0201'    | ''          | ''            | '20180803'
 '475'        | '1%'      | '1/20W'  | '0201LF'  | 'EMPTY'  | 'CS14751FE00'(!)        = ''              | ''                 | 'CS14751FE00'           |'R0201'| '(SMR0201AW)'                  | '475'     | '1%'    | '1/20W'  | 'IO'       | 'RES CHIP 475 1/20W,+-1%(0201)'                    | 'CHIPR0201'    | ''          | ''            | '20180803'
 '680'        | '5%'      | '1/20W'  | '0201LF'  | 'CHIP'   | 'CS16801JE00'(!)        = ''              | ''                 | 'CS16801JE00'           |'R0201'| '(SMR0201AW)'                  | '680'     | '5%'    | '1/20W'  | 'DISCRETE' | 'RES CHIP 680 1/20W +-5%(0201)'                    | 'CHIPR0201'    | ''          | ''            | '20180803'
 '680'        | '5%'      | '1/20W'  | '0201LF'  | 'EMPTY'  | 'CS16801JE00'(!)        = ''              | ''                 | 'CS16801JE00'           |'R0201'| '(SMR0201AW)'                  | '680'     | '5%'    | '1/20W'  | 'IO'       | 'RES CHIP 680 1/20W +-5%(0201)'                    | 'CHIPR0201'    | ''          | ''            | '20180803'
 '1.5K'       | '1%'      | '1/20W'  | '0201LF'  | 'CHIP'   | 'CS21501FE01'(!)        = ''              | ''                 | 'CS21501FE01'           |'R0201'| '(SMR0201AW)'                  | '1.5K'    | '1%'    | '1/20W'  | 'DISCRETE' | 'RES CHIP 1.5K 1/20W +-1%(0201)'                   | 'CHIPR0201'    | ''          | ''            | '20180803'
 '1.5K'       | '1%'      | '1/20W'  | '0201LF'  | 'EMPTY'  | 'CS21501FE01'(!)        = ''              | ''                 | 'CS21501FE01'           |'R0201'| '(SMR0201AW)'                  | '1.5K'    | '1%'    | '1/20W'  | 'IO'       | 'RES CHIP 1.5K 1/20W +-1%(0201)'                   | 'CHIPR0201'    | ''          | ''            | '20180803'
 '2.2K'       | '5%'      | '1/20W'  | '0201LF'  | 'CHIP'   | 'CS22201JE00'(!)        = ''              | ''                 | 'CS22201JE00'           |'R0201'| '(SMR0201AW)'                  | '2.2K'    | '5%'    | '1/20W'  | 'DISCRETE' | 'RES CHIP 2.2K 1/20W +-5%(0201)'                   | 'CHIPR0201'    | ''          | ''            | '20180803'
 '2.2K'       | '5%'      | '1/20W'  | '0201LF'  | 'EMPTY'  | 'CS22201JE00'(!)        = ''              | ''                 | 'CS22201JE00'           |'R0201'| '(SMR0201AW)'                  | '2.2K'    | '5%'    | '1/20W'  | 'IO'       | 'RES CHIP 2.2K 1/20W +-5%(0201)'                   | 'CHIPR0201'    | ''          | ''            | '20180803'
 '2.21K'      | '1%'      | '1/20W'  | '0201LF'  | 'CHIP'   | 'CS22211FE09'(!)        = ''              | ''                 | 'CS22211FE09'           |'R0201'| '(SMR0201AW)'                  | '2.21K'   | '1%'    | '1/20W'  | 'DISCRETE' | 'RES CHIP 2.21K 1/20W +-1%(0201)'                  | 'CHIPR0201'    | ''          | ''            | '20180806'
 '2.21K'      | '1%'      | '1/20W'  | '0201LF'  | 'EMPTY'  | 'CS22211FE09'(!)        = ''              | ''                 | 'CS22211FE09'           |'R0201'| '(SMR0201AW)'                  | '2.21K'   | '1%'    | '1/20W'  | 'IO'       | 'RES CHIP 2.21K 1/20W +-1%(0201)'                  | 'CHIPR0201'    | ''          | ''            | '20180806'
 '2.2'        | '1%'      | '1/20W'  | '0201LF'  | 'CHIP'   | 'CS-2201FE01'(!)        = 'End of Design' | 'Comp-Approve'     | 'CS-2201FE01'           |'R0201'| '(SMR0201AW)'                  | '2.2'     | '1%'    | '1/20W'  | 'DISCRETE' | 'RES CHIP 2.2 1/20W +-1%(0201)'                    | 'CHIPR0201'    | ''          | ''            | '20180806'
 '2.2'        | '1%'      | '1/20W'  | '0201LF'  | 'EMPTY'  | 'CS-2201FE01'(!)        = 'End of Design' | 'Comp-Approve'     | 'CS-2201FE01'           |'R0201'| '(SMR0201AW)'                  | '2.2'     | '1%'    | '1/20W'  | 'IO'       | 'RES CHIP 2.2 1/20W +-1%(0201)'                    | 'CHIPR0201'    | ''          | ''            | '20180806'
 '24.9'       | '1%'      | '1/20W'  | '0201LF'  | 'CHIP'   | 'CS02491FE00'(!)        = ''              | ''                 | 'CS02491FE00'           |'R0201'| '(SMR0201AW)'                  | '24.9'    | '1%'    | '1/20W'  | 'DISCRETE' | 'RES CHIP 24.9 1/20W +-1%(0201)'                   | 'CHIPR0201'    | ''          | ''            | '20180806'
 '24.9'       | '1%'      | '1/20W'  | '0201LF'  | 'EMPTY'  | 'CS02491FE00'(!)        = ''              | ''                 | 'CS02491FE00'           |'R0201'| '(SMR0201AW)'                  | '24.9'    | '1%'    | '1/20W'  | 'IO'       | 'RES CHIP 24.9 1/20W +-1%(0201)'                   | 'CHIPR0201'    | ''          | ''            | '20180806'
 '27.4'       | '1%'      | '1/20W'  | '0201LF'  | 'CHIP'   | 'CS02741FE07'(!)        = ''              | ''                 | 'CS02741FE07'           |'R0201'| '(SMR0201AW)'                  | '27.4'    | '1%'    | '1/20W'  | 'DISCRETE' | 'RES CHIP 27.4 1/20W +-1%(0201)'                   | 'CHIPR0201'    | ''          | ''            | '20180806'
 '27.4'       | '1%'      | '1/20W'  | '0201LF'  | 'EMPTY'  | 'CS02741FE07'(!)        = ''              | ''                 | 'CS02741FE07'           |'R0201'| '(SMR0201AW)'                  | '27.4'    | '1%'    | '1/20W'  | 'IO'       | 'RES CHIP 27.4 1/20W +-1%(0201)'                   | 'CHIPR0201'    | ''          | ''            | '20180806'
 '113'        | '1%'      | '1/20W'  | '0201LF'  | 'CHIP'   | 'CS11131FE01'(!)        = ''              | ''                 | 'CS11131FE01'           |'R0201'| '(SMR0201AW)'                  | '113'     | '1%'    | '1/20W'  | 'DISCRETE' | 'RES CHIP 113(1/20W,+-1%,0201)'                    | 'CHIPR0201'    | ''          | ''            | '20180806'
 '113'        | '1%'      | '1/20W'  | '0201LF'  | 'EMPTY'  | 'CS11131FE01'(!)        = ''              | ''                 | 'CS11131FE01'           |'R0201'| '(SMR0201AW)'                  | '113'     | '1%'    | '1/20W'  | 'IO'       | 'RES CHIP 113(1/20W,+-1%,0201)'                    | 'CHIPR0201'    | ''          | ''            | '20180806'
 '130'        | '1%'      | '1/20W'  | '0201LF'  | 'CHIP'   | 'CS11301FE03'(!)        = ''              | ''                 | 'CS11301FE03'           |'R0201'| '(SMR0201AW)'                  | '130'     | '1%'    | '1/20W'  | 'DISCRETE' | 'RES CHIP 130(1/20W,+-1%,0201)'                    | 'CHIPR0201'    | ''          | ''            | '20180806'
 '130'        | '1%'      | '1/20W'  | '0201LF'  | 'EMPTY'  | 'CS11301FE03'(!)        = ''              | ''                 | 'CS11301FE03'           |'R0201'| '(SMR0201AW)'                  | '130'     | '1%'    | '1/20W'  | 'IO'       | 'RES CHIP 130(1/20W,+-1%,0201)'                    | 'CHIPR0201'    | ''          | ''            | '20180806'
 '499'        | '1%'      | '1/20W'  | '0201LF'  | 'CHIP'   | 'CS14991FE00'(!)        = ''              | ''                 | 'CS14991FE00'           |'R0201'| '(SMR0201AW)'                  | '499'     | '1%'    | '1/20W'  | 'DISCRETE' | 'RES CHIP 499 1/20W +-1%(0201)'                    | 'CHIPR0201'    | ''          | ''            | '20180806'
 '499'        | '1%'      | '1/20W'  | '0201LF'  | 'EMPTY'  | 'CS14991FE00'(!)        = ''              | ''                 | 'CS14991FE00'           |'R0201'| '(SMR0201AW)'                  | '499'     | '1%'    | '1/20W'  | 'IO'       | 'RES CHIP 499 1/20W +-1%(0201)'                    | 'CHIPR0201'    | ''          | ''            | '20180806'
 '1.21K'      | '1%'      | '1/20W'  | '0201LF'  | 'CHIP'   | 'CS21211FE00'(!)        = ''              | ''                 | 'CS21211FE00'           |'R0201'| '(SMR0201AW)'                  | '1.21K'   | '1%'    | '1/20W'  | 'DISCRETE' | 'RES CHIP 1.21K 1/20W +-1%(0201)'                  | 'CHIPR0201'    | ''          | ''            | '20180806'
 '1.21K'      | '1%'      | '1/20W'  | '0201LF'  | 'EMPTY'  | 'CS21211FE00'(!)        = ''              | ''                 | 'CS21211FE00'           |'R0201'| '(SMR0201AW)'                  | '1.21K'   | '1%'    | '1/20W'  | 'IO'       | 'RES CHIP 1.21K 1/20W +-1%(0201)'                  | 'CHIPR0201'    | ''          | ''            | '20180806'
 '2.7K'       | '1%'      | '1/20W'  | '0201LF'  | 'CHIP'   | 'CS22701FE02'(!)        = ''              | ''                 | 'CS22701FE02'           |'R0201'| '(SMR0201AW)'                  | '2.7K'    | '1%'    | '1/20W'  | 'DISCRETE' | 'RES CHIP 2.7K(1/20W,+-1%,0201)'                   | 'CHIPR0201'    | ''          | ''            | '20180806'
 '2.7K'       | '1%'      | '1/20W'  | '0201LF'  | 'EMPTY'  | 'CS22701FE02'(!)        = ''              | ''                 | 'CS22701FE02'           |'R0201'| '(SMR0201AW)'                  | '2.7K'    | '1%'    | '1/20W'  | 'IO'       | 'RES CHIP 2.7K(1/20W,+-1%,0201)'                   | 'CHIPR0201'    | ''          | ''            | '20180806'
 '5.36K'      | '1%'      | '1/20W'  | '0201LF'  | 'CHIP'   | 'CS25361FE00'(!)        = ''              | ''                 | 'CS25361FE00'           |'R0201'| '(SMR0201AW)'                  | '5.36K'   | '1%'    | '1/20W'  | 'DISCRETE' | 'RES CHIP 5.36K 1/20W +-1%(0201)'                  | 'CHIPR0201'    | ''          | ''            | '20180806'
 '5.36K'      | '1%'      | '1/20W'  | '0201LF'  | 'EMPTY'  | 'CS25361FE00'(!)        = ''              | ''                 | 'CS25361FE00'           |'R0201'| '(SMR0201AW)'                  | '5.36K'   | '1%'    | '1/20W'  | 'IO'       | 'RES CHIP 5.36K 1/20W +-1%(0201)'                  | 'CHIPR0201'    | ''          | ''            | '20180806'
 '6.49K'      | '1%'      | '1/20W'  | '0201LF'  | 'CHIP'   | 'CS26491FE00'(!)        = ''              | ''                 | 'CS26491FE00'           |'R0201'| '(SMR0201AW)'                  | '6.49K'   | '1%'    | '1/20W'  | 'DISCRETE' | 'RES CHIP 6.49K 1/20W +-1%(0201)'                  | 'CHIPR0201'    | ''          | ''            | '20180806'
 '6.49K'      | '1%'      | '1/20W'  | '0201LF'  | 'EMPTY'  | 'CS26491FE00'(!)        = ''              | ''                 | 'CS26491FE00'           |'R0201'| '(SMR0201AW)'                  | '6.49K'   | '1%'    | '1/20W'  | 'IO'       | 'RES CHIP 6.49K 1/20W +-1%(0201)'                  | 'CHIPR0201'    | ''          | ''            | '20180806'
 '6.65K'      | '1%'      | '1/20W'  | '0201LF'  | 'CHIP'   | 'CS26651FE01'(!)        = ''              | ''                 | 'CS26651FE01'           |'R0201'| '(SMR0201AW)'                  | '6.65K'   | '1%'    | '1/20W'  | 'DISCRETE' | 'RES CHIP 6.65K 1/20W +-1%(0201)'                  | 'CHIPR0201'    | ''          | ''            | '20180806'
 '6.65K'      | '1%'      | '1/20W'  | '0201LF'  | 'EMPTY'  | 'CS26651FE01'(!)        = ''              | ''                 | 'CS26651FE01'           |'R0201'| '(SMR0201AW)'                  | '6.65K'   | '1%'    | '1/20W'  | 'IO'       | 'RES CHIP 6.65K 1/20W +-1%(0201)'                  | 'CHIPR0201'    | ''          | ''            | '20180806'
 '6.98K'      | '1%'      | '1/20W'  | '0201LF'  | 'CHIP'   | 'CS26981FE00'(!)        = ''              | ''                 | 'CS26981FE00'           |'R0201'| '(SMR0201AW)'                  | '6.98K'   | '1%'    | '1/20W'  | 'DISCRETE' | 'RES CHIP 6.98K 1/20W +-1%(0201)'                  | 'CHIPR0201'    | ''          | ''            | '20180806'
 '6.98K'      | '1%'      | '1/20W'  | '0201LF'  | 'EMPTY'  | 'CS26981FE00'(!)        = ''              | ''                 | 'CS26981FE00'           |'R0201'| '(SMR0201AW)'                  | '6.98K'   | '1%'    | '1/20W'  | 'IO'       | 'RES CHIP 6.98K 1/20W +-1%(0201)'                  | 'CHIPR0201'    | ''          | ''            | '20180806'
 '9.09K'      | '1'       | '1/20W'  | '0201LF'  | 'CHIP'   | 'CS29091FE00'(!)        = ''              | ''                 | 'CS29091FE00'           |'R0201'| '(SMR0201AW)'                  | '9.09K'   | '1'     | '1/20W'  | 'DISCRETE' | 'RES CHIP 9.09K 1/20W +-1(0201)'                   | 'CHIPR0201'    | ''          | ''            | '20180806'
 '9.09K'      | '1'       | '1/20W'  | '0201LF'  | 'EMPTY'  | 'CS29091FE00'(!)        = ''              | ''                 | 'CS29091FE00'           |'R0201'| '(SMR0201AW)'                  | '9.09K'   | '1'     | '1/20W'  | 'IO'       | 'RES CHIP 9.09K 1/20W +-1(0201)'                   | 'CHIPR0201'    | ''          | ''            | '20180806'
 '11.3K'      | '1%'      | '1/20W'  | '0201LF'  | 'CHIP'   | 'CS31131FE03'(!)        = ''              | ''                 | 'CS31131FE03'           |'R0201'| '(SMR0201AW)'                  | '11.3K'   | '1%'    | '1/20W'  | 'DISCRETE' | 'RES CHIP 11.3K(1/20W,+-1%,0201)'                  | 'CHIPR0201'    | ''          | ''            | '20180806'
 '11.3K'      | '1%'      | '1/20W'  | '0201LF'  | 'EMPTY'  | 'CS31131FE03'(!)        = ''              | ''                 | 'CS31131FE03'           |'R0201'| '(SMR0201AW)'                  | '11.3K'   | '1%'    | '1/20W'  | 'IO'       | 'RES CHIP 11.3K(1/20W,+-1%,0201)'                  | 'CHIPR0201'    | ''          | ''            | '20180806'
 '22.1K'      | '1%'      | '1/20W'  | '0201LF'  | 'CHIP'   | 'CS32211FE00'(!)        = ''              | ''                 | 'CS32211FE00'           |'R0201'| '(SMR0201AW)'                  | '22.1K'   | '1%'    | '1/20W'  | 'DISCRETE' | 'RES CHIP 22.1K 1/20W +-1%(0201)'                  | 'CHIPR0201'    | ''          | ''            | '20180806'
 '22.1K'      | '1%'      | '1/20W'  | '0201LF'  | 'EMPTY'  | 'CS32211FE00'(!)        = ''              | ''                 | 'CS32211FE00'           |'R0201'| '(SMR0201AW)'                  | '22.1K'   | '1%'    | '1/20W'  | 'IO'       | 'RES CHIP 22.1K 1/20W +-1%(0201)'                  | 'CHIPR0201'    | ''          | ''            | '20180806'
 '22.6K'      | '1%'      | '1/20W'  | '0201LF'  | 'CHIP'   | 'CS32261FE01'(!)        = ''              | ''                 | 'CS32261FE01'           |'R0201'| '(SMR0201AW)'                  | '22.6K'   | '1%'    | '1/20W'  | 'DISCRETE' | 'RES CHIP 22.6K 1/20W +-1%(0201)'                  | 'CHIPR0201'    | ''          | ''            | '20180806'
 '22.6K'      | '1%'      | '1/20W'  | '0201LF'  | 'EMPTY'  | 'CS32261FE01'(!)        = ''              | ''                 | 'CS32261FE01'           |'R0201'| '(SMR0201AW)'                  | '22.6K'   | '1%'    | '1/20W'  | 'IO'       | 'RES CHIP 22.6K 1/20W +-1%(0201)'                  | 'CHIPR0201'    | ''          | ''            | '20180806'
 '2.49K'      | '1%'      | '1/20W'  | '0201LF'  | 'CHIP'   | 'CS22491FE02'(!)        = ''              | ''                 | 'CS22491FE02'           |'R0201'| '(SMR0201AW)'                  | '2.49K'   | '1%'    | '1/20W'  | 'DISCRETE' | 'RES CHIP 2.49K(1/20W,+-1%,0201)'                  | 'CHIPR0201'    | ''          | ''            | '20180806'
 '2.49K'      | '1%'      | '1/20W'  | '0201LF'  | 'EMPTY'  | 'CS22491FE02'(!)        = ''              | ''                 | 'CS22491FE02'           |'R0201'| '(SMR0201AW)'                  | '2.49K'   | '1%'    | '1/20W'  | 'IO'       | 'RES CHIP 2.49K(1/20W,+-1%,0201)'                  | 'CHIPR0201'    | ''          | ''            | '20180806'
 '2.87K'      | '1%'      | '1/20W'  | '0201LF'  | 'CHIP'   | 'CS22871FE01'(!)        = ''              | ''                 | 'CS22871FE01'           |'R0201'| '(SMR0201AW)'                  | '2.87K'   | '1%'    | '1/20W'  | 'DISCRETE' | 'RES CHIP 2.87K(1/20W,+-1%,0201)'                  | 'CHIPR0201'    | ''          | ''            | '20180806'
 '2.87K'      | '1%'      | '1/20W'  | '0201LF'  | 'EMPTY'  | 'CS22871FE01'(!)        = ''              | ''                 | 'CS22871FE01'           |'R0201'| '(SMR0201AW)'                  | '2.87K'   | '1%'    | '1/20W'  | 'IO'       | 'RES CHIP 2.87K(1/20W,+-1%,0201)'                  | 'CHIPR0201'    | ''          | ''            | '20180806'
 '3.3K'       | '5%'      | '1/20W'  | '0201LF'  | 'CHIP'   | 'CS23301JE02'(!)        = ''              | ''                 | 'CS23301JE02'           |'R0201'| '(SMR0201AW)'                  | '3.3K'    | '5%'    | '1/20W'  | 'DISCRETE' | 'RES CHIP 3.3K 1/20W +-5%(0201)'                   | 'CHIPR0201'    | ''          | ''            | '20180806'
 '3.3K'       | '5%'      | '1/20W'  | '0201LF'  | 'EMPTY'  | 'CS23301JE02'(!)        = ''              | ''                 | 'CS23301JE02'           |'R0201'| '(SMR0201AW)'                  | '3.3K'    | '5%'    | '1/20W'  | 'IO'       | 'RES CHIP 3.3K 1/20W +-5%(0201)'                   | 'CHIPR0201'    | ''          | ''            | '20180806'
 '3.32K'      | '1%'      | '1/20W'  | '0201LF'  | 'CHIP'   | 'CS23321FE00'(!)        = ''              | ''                 | 'CS23321FE00'           |'R0201'| '(SMR0201AW)'                  | '3.32K'   | '1%'    | '1/20W'  | 'DISCRETE' | 'RES CHIP 3.32K 1/20W +-1%(0201)'                  | 'CHIPR0201'    | ''          | ''            | '20180806'
 '3.32K'      | '1%'      | '1/20W'  | '0201LF'  | 'EMPTY'  | 'CS23321FE00'(!)        = ''              | ''                 | 'CS23321FE00'           |'R0201'| '(SMR0201AW)'                  | '3.32K'   | '1%'    | '1/20W'  | 'IO'       | 'RES CHIP 3.32K 1/20W +-1%(0201)'                  | 'CHIPR0201'    | ''          | ''            | '20180806'
 '49.9K'      | '1%'      | '1/20W'  | '0201LF'  | 'CHIP'   | 'CS34991FE02'(!)        = ''              | ''                 | 'CS34991FE02'           |'R0201'| '(SMR0201AW)'                  | '49.9K'   | '1%'    | '1/20W'  | 'DISCRETE' | 'RES CHIP 49.9K 1/20W +-1%(0201)'                  | 'CHIPR0201'    | ''          | ''            | '20180806'
 '49.9K'      | '1%'      | '1/20W'  | '0201LF'  | 'EMPTY'  | 'CS34991FE02'(!)        = ''              | ''                 | 'CS34991FE02'           |'R0201'| '(SMR0201AW)'                  | '49.9K'   | '1%'    | '1/20W'  | 'IO'       | 'RES CHIP 49.9K 1/20W +-1%(0201)'                  | 'CHIPR0201'    | ''          | ''            | '20180806'
 '5.62K'      | '1%'      | '1/20W'  | '0201LF'  | 'CHIP'   | 'CS25621FE06'(!)        = ''              | ''                 | 'CS25621FE06'           |'R0201'| '(SMR0201AW)'                  | '5.62K'   | '1%'    | '1/20W'  | 'DISCRETE' | 'RES CHIP 5.62K(1/20W,+-1%,0201)'                  | 'CHIPR0201'    | ''          | ''            | '20180806'
 '5.62K'      | '1%'      | '1/20W'  | '0201LF'  | 'EMPTY'  | 'CS25621FE06'(!)        = ''              | ''                 | 'CS25621FE06'           |'R0201'| '(SMR0201AW)'                  | '5.62K'   | '1%'    | '1/20W'  | 'IO'       | 'RES CHIP 5.62K(1/20W,+-1%,0201)'                  | 'CHIPR0201'    | ''          | ''            | '20180806'
 '56K'        | '1%'      | '1/20W'  | '0201LF'  | 'CHIP'   | 'CS35601FE00'(!)        = 'End of Design' | 'Comp-Approve'     | 'CS35601FE00'           |'R0201'| '(SMR0201AW)'                  | '56K'     | '1%'    | '1/20W'  | 'DISCRETE' | 'RES CHIP 56K 1/20W +-1%(0201)'                    | 'CHIPR0201'    | ''          | ''            | '20180806'
 '56K'        | '1%'      | '1/20W'  | '0201LF'  | 'EMPTY'  | 'CS35601FE00'(!)        = 'End of Design' | 'Comp-Approve'     | 'CS35601FE00'           |'R0201'| '(SMR0201AW)'                  | '56K'     | '1%'    | '1/20W'  | 'IO'       | 'RES CHIP 56K 1/20W +-1%(0201)'                    | 'CHIPR0201'    | ''          | ''            | '20180806'
 '8.25K'      | '1%'      | '1/20W'  | '0201LF'  | 'CHIP'   | 'CS28251FE00'(!)        = ''              | ''                 | 'CS28251FE00'           |'R0201'| '(SMR0201AW)'                  | '8.25K'   | '1%'    | '1/20W'  | 'DISCRETE' | 'RES CHIP 8.25K 1/20W +-1%(0201)'                  | 'CHIPR0201'    | ''          | ''            | '20180806'
 '8.25K'      | '1%'      | '1/20W'  | '0201LF'  | 'EMPTY'  | 'CS28251FE00'(!)        = ''              | ''                 | 'CS28251FE00'           |'R0201'| '(SMR0201AW)'                  | '8.25K'   | '1%'    | '1/20W'  | 'IO'       | 'RES CHIP 8.25K 1/20W +-1%(0201)'                  | 'CHIPR0201'    | ''          | ''            | '20180806'
 '10K'        | '5%'      | '1/20W'  | '0201LF'  | 'CHIP'   | 'CS31001JE16'(!)        = ''              | ''                 | 'CS31001JE16'           |'R0201'| '(SMR0201AW)'                  | '10K'     | '5%'    | '1/20W'  | 'DISCRETE' | 'RES CHIP 10K 1/20W +-5%(0201)'                    | 'CHIPR0201'    | ''          | ''            | '20140819'
 '10K'        | '5%'      | '1/20W'  | '0201LF'  | 'EMPTY'  | 'CS31001JE16'(!)        = ''              | ''                 | 'CS31001JE16'           |'R0201'| '(SMR0201AW)'                  | '10K'     | '5%'    | '1/20W'  | 'IO'       | 'RES CHIP 10K 1/20W +-5%(0201)'                    | 'CHIPR0201'    | ''          | ''            | '20140819'
 '10.2K'      | '1%'      | '1/20W'  | '0201LF'  | 'CHIP'   | 'CS31021FE00'(!)        = ''              | ''                 | 'CS31021FE00'           |'R0201'| '(SMR0201AW)'                  | '10.2K'   | '1%'    | '1/20W'  | 'DISCRETE' | 'RES CHIP 10.2K 1/20W +-1%(0201)'                  | 'CHIPR0201'    | ''          | ''            | '20180806'
 '10.2K'      | '1%'      | '1/20W'  | '0201LF'  | 'EMPTY'  | 'CS31021FE00'(!)        = ''              | ''                 | 'CS31021FE00'           |'R0201'| '(SMR0201AW)'                  | '10.2K'   | '1%'    | '1/20W'  | 'IO'       | 'RES CHIP 10.2K 1/20W +-1%(0201)'                  | 'CHIPR0201'    | ''          | ''            | '20180806'
 '150K'       | '1%'      | '1/20W'  | '0201LF'  | 'CHIP'   | 'CS41501FE06'(!)        = ''              | ''                 | 'CS41501FE06'           |'R0201'| '(SMR0201AW)'                  | '150K'    | '1%'    | '1/20W'  | 'DISCRETE' | 'RES CHIP 150K(1/20W,+-1%,0201)'                   | 'CHIPR0201'    | ''          | ''            | '20180806'
 '150K'       | '1%'      | '1/20W'  | '0201LF'  | 'EMPTY'  | 'CS41501FE06'(!)        = ''              | ''                 | 'CS41501FE06'           |'R0201'| '(SMR0201AW)'                  | '150K'    | '1%'    | '1/20W'  | 'IO'       | 'RES CHIP 150K(1/20W,+-1%,0201)'                   | 'CHIPR0201'    | ''          | ''            | '20180806'
 '11.5K'      | '1%'      | '1/20W'  | '0201LF'  | 'CHIP'   | 'CS31151FE03'(!)        = ''              | ''                 | 'CS31151FE03'           |'R0201'| '(SMR0201AW)'                  | '11.5K'   | '1%'    | '1/20W'  | 'DISCRETE' | 'RES CHIP 11.5K(1/20W,+-1%,0201)'                  | 'CHIPR0201'    | ''          | ''            | '20180806'
 '11.5K'      | '1%'      | '1/20W'  | '0201LF'  | 'EMPTY'  | 'CS31151FE03'(!)        = ''              | ''                 | 'CS31151FE03'           |'R0201'| '(SMR0201AW)'                  | '11.5K'   | '1%'    | '1/20W'  | 'IO'       | 'RES CHIP 11.5K(1/20W,+-1%,0201)'                  | 'CHIPR0201'    | ''          | ''            | '20180806'
 '154K'       | '1%'      | '1/20W'  | '0201LF'  | 'CHIP'   | 'CS41541FE00'(!)        = ''              | ''                 | 'CS41541FE00'           |'R0201'| '(SMR0201AW)'                  | '154K'    | '1%'    | '1/20W'  | 'DISCRETE' | 'RES CHIP 154K 1/20W +-1%(0201)'                   | 'CHIPR0201'    | ''          | ''            | '20180806'
 '154K'       | '1%'      | '1/20W'  | '0201LF'  | 'EMPTY'  | 'CS41541FE00'(!)        = ''              | ''                 | 'CS41541FE00'           |'R0201'| '(SMR0201AW)'                  | '154K'    | '1%'    | '1/20W'  | 'IO'       | 'RES CHIP 154K 1/20W +-1%(0201)'                   | 'CHIPR0201'    | ''          | ''            | '20180806'
 '12K'        | '1%'      | '1/20W'  | '0201LF'  | 'CHIP'   | 'CS31201FE00'(!)        = 'End of Design' | 'Comp-Approve'     | 'CS31201FE00'           |'R0201'| '(SMR0201AW)'                  | '12K'     | '1%'    | '1/20W'  | 'DISCRETE' | 'RES CHIP 12K 1/20W +-1%(0201)'                    | 'CHIPR0201'    | ''          | ''            | '20180806'
 '12K'        | '1%'      | '1/20W'  | '0201LF'  | 'EMPTY'  | 'CS31201FE00'(!)        = 'End of Design' | 'Comp-Approve'     | 'CS31201FE00'           |'R0201'| '(SMR0201AW)'                  | '12K'     | '1%'    | '1/20W'  | 'IO'       | 'RES CHIP 12K 1/20W +-1%(0201)'                    | 'CHIPR0201'    | ''          | ''            | '20180806'
 '200K'       | '1%'      | '1/20W'  | '0201LF'  | 'CHIP'   | 'CS42001FE00'(!)        = ''              | ''                 | 'CS42001FE00'           |'R0201'| '(SMR0201AW)'                  | '200K'    | '1%'    | '1/20W'  | 'DISCRETE' | 'RES CHIP 200K 1/20W +-1%(0201)'                   | 'CHIPR0201'    | ''          | ''            | '20180806'
 '200K'       | '1%'      | '1/20W'  | '0201LF'  | 'EMPTY'  | 'CS42001FE00'(!)        = ''              | ''                 | 'CS42001FE00'           |'R0201'| '(SMR0201AW)'                  | '200K'    | '1%'    | '1/20W'  | 'IO'       | 'RES CHIP 200K 1/20W +-1%(0201)'                   | 'CHIPR0201'    | ''          | ''            | '20180806'
 '15K'        | '1%'      | '1/20W'  | '0201LF'  | 'CHIP'   | 'CS31501FE00'(!)        = ''              | ''                 | 'CS31501FE00'           |'R0201'| '(SMR0201AW)'                  | '15K'     | '1%'    | '1/20W'  | 'DISCRETE' | 'RES CHIP 15K 1/20W +-1%(0201)'                    | 'CHIPR0201'    | ''          | ''            | '20180806'
 '15K'        | '1%'      | '1/20W'  | '0201LF'  | 'EMPTY'  | 'CS31501FE00'(!)        = ''              | ''                 | 'CS31501FE00'           |'R0201'| '(SMR0201AW)'                  | '15K'     | '1%'    | '1/20W'  | 'IO'       | 'RES CHIP 15K 1/20W +-1%(0201)'                    | 'CHIPR0201'    | ''          | ''            | '20180806'
 '15.8K'      | '1%'      | '1/20W'  | '0201LF'  | 'CHIP'   | 'CS31581FE00'(!)        = ''              | ''                 | 'CS31581FE00'           |'R0201'| '(SMR0201AW)'                  | '15.8K'   | '1%'    | '1/20W'  | 'DISCRETE' | 'RES CHIP 15.8K 1/20W +-1%(0201)'                  | 'CHIPR0201'    | ''          | ''            | '20180806'
 '15.8K'      | '1%'      | '1/20W'  | '0201LF'  | 'EMPTY'  | 'CS31581FE00'(!)        = ''              | ''                 | 'CS31581FE00'           |'R0201'| '(SMR0201AW)'                  | '15.8K'   | '1%'    | '1/20W'  | 'IO'       | 'RES CHIP 15.8K 1/20W +-1%(0201)'                  | 'CHIPR0201'    | ''          | ''            | '20180806'
 '475K'       | '1%'      | '1/20W'  | '0201LF'  | 'CHIP'   | 'CS44751FE01'(!)        = ''              | ''                 | 'CS44751FE01'           |'R0201'| '(SMR0201AW)'                  | '475K'    | '1%'    | '1/20W'  | 'DISCRETE' | 'RES CHIP 475K 1/20W +-1%(0201)'                   | 'CHIPR0201'    | ''          | ''            | '20180806'
 '475K'       | '1%'      | '1/20W'  | '0201LF'  | 'EMPTY'  | 'CS44751FE01'(!)        = ''              | ''                 | 'CS44751FE01'           |'R0201'| '(SMR0201AW)'                  | '475K'    | '1%'    | '1/20W'  | 'IO'       | 'RES CHIP 475K 1/20W +-1%(0201)'                   | 'CHIPR0201'    | ''          | ''            | '20180806'
 '10M'        | '5%'      | '1/20W'  | '0201LF'  | 'CHIP'   | 'CS61001JE00'(!)        = ''              | ''                 | 'CS61001JE00'           |'R0201'| '(SMR0201AW)'                  | '10M'     | '5%'    | '1/20W'  | 'DISCRETE' | 'RES CHIP 10M 1/20W +-5%(0201)'                    | 'CHIPR0201'    | ''          | ''            | '20180806'
 '10M'        | '5%'      | '1/20W'  | '0201LF'  | 'EMPTY'  | 'CS61001JE00'(!)        = ''              | ''                 | 'CS61001JE00'           |'R0201'| '(SMR0201AW)'                  | '10M'     | '5%'    | '1/20W'  | 'IO'       | 'RES CHIP 10M 1/20W +-5%(0201)'                    | 'CHIPR0201'    | ''          | ''            | '20180806'
 '18K'        | '1%'      | '1/20W'  | '0201LF'  | 'CHIP'   | 'CS31801FE01'(!)        = ''              | ''                 | 'CS31801FE01'           |'R0201'| '(SMR0201AW)'                  | '18K'     | '1%'    | '1/20W'  | 'DISCRETE' | 'RES CHIP 18K 1/20W +-1%(0201)'                    | 'CHIPR0201'    | ''          | ''            | '20180806'
 '18K'        | '1%'      | '1/20W'  | '0201LF'  | 'EMPTY'  | 'CS31801FE01'(!)        = ''              | ''                 | 'CS31801FE01'           |'R0201'| '(SMR0201AW)'                  | '18K'     | '1%'    | '1/20W'  | 'IO'       | 'RES CHIP 18K 1/20W +-1%(0201)'                    | 'CHIPR0201'    | ''          | ''            | '20180806'
 '1.24K'      | '1%'      | '1/20W'  | '0201LF'  | 'CHIP'   | 'CS21241FE00'(!)        = ''              | ''                 | 'CS21241FE00'           |'R0201'| '(SMR0201AW)'                  | '1.24K'   | '1%'    | '1/20W'  | 'DISCRETE' | 'RES CHIP 1.24K(1/20W,+-1%,0201)'                  | 'CHIPR0201'    | ''          | ''            | '20180806'
 '1.24K'      | '1%'      | '1/20W'  | '0201LF'  | 'EMPTY'  | 'CS21241FE00'(!)        = ''              | ''                 | 'CS21241FE00'           |'R0201'| '(SMR0201AW)'                  | '1.24K'   | '1%'    | '1/20W'  | 'IO'       | 'RES CHIP 1.24K(1/20W,+-1%,0201)'                  | 'CHIPR0201'    | ''          | ''            | '20180806'
 '20K'        | '1%'      | '1/20W'  | '0201LF'  | 'CHIP'   | 'CS32001FE00'(!)        = ''              | ''                 | 'CS32001FE00'           |'R0201'| '(SMR0201AW)'                  | '20K'     | '1%'    | '1/20W'  | 'DISCRETE' | 'RES CHIP 20K 1/20W +-1%(0201)'                    | 'CHIPR0201'    | ''          | ''            | '20180806'
 '20K'        | '1%'      | '1/20W'  | '0201LF'  | 'EMPTY'  | 'CS32001FE00'(!)        = ''              | ''                 | 'CS32001FE00'           |'R0201'| '(SMR0201AW)'                  | '20K'     | '1%'    | '1/20W'  | 'IO'       | 'RES CHIP 20K 1/20W +-1%(0201)'                    | 'CHIPR0201'    | ''          | ''            | '20180806'
 '20K'        | '5%'      | '1/20W'  | '0201LF'  | 'CHIP'   | 'CS32001JE01'(!)        = ''              | ''                 | 'CS32001JE01'           |'R0201'| '(SMR0201AW)'                  | '20K'     | '5%'    | '1/20W'  | 'DISCRETE' | 'RES CHIP 20K 1/20W +-5%(0201)'                    | 'CHIPR0201'    | ''          | ''            | '20180806'
 '20K'        | '5%'      | '1/20W'  | '0201LF'  | 'EMPTY'  | 'CS32001JE01'(!)        = ''              | ''                 | 'CS32001JE01'           |'R0201'| '(SMR0201AW)'                  | '20K'     | '5%'    | '1/20W'  | 'IO'       | 'RES CHIP 20K 1/20W +-5%(0201)'                    | 'CHIPR0201'    | ''          | ''            | '20180806'
 '23.2K'      | '1%'      | '1/20W'  | '0201LF'  | 'CHIP'   | 'CS32321FE00'(!)        = ''              | ''                 | 'CS32321FE00'           |'R0201'| '(SMR0201AW)'                  | '23.2K'   | '1%'    | '1/20W'  | 'DISCRETE' | 'RES CHIP 23.2K 1/20W +-1%(0201)'                  | 'CHIPR0201'    | ''          | ''            | '20180806'
 '23.2K'      | '1%'      | '1/20W'  | '0201LF'  | 'EMPTY'  | 'CS32321FE00'(!)        = ''              | ''                 | 'CS32321FE00'           |'R0201'| '(SMR0201AW)'                  | '23.2K'   | '1%'    | '1/20W'  | 'IO'       | 'RES CHIP 23.2K 1/20W +-1%(0201)'                  | 'CHIPR0201'    | ''          | ''            | '20180806'
 '24.3K'      | '1%'      | '1/20W'  | '0201LF'  | 'CHIP'   | 'CS32431FE01'(!)        = ''              | ''                 | 'CS32431FE01'           |'R0201'| '(SMR0201AW)'                  | '24.3K'   | '1%'    | '1/20W'  | 'DISCRETE' | 'RES CHIP 24.3K 1/20W(+-1%,0201)'                  | 'CHIPR0201'    | ''          | ''            | '20180807'
 '24.3K'      | '1%'      | '1/20W'  | '0201LF'  | 'EMPTY'  | 'CS32431FE01'(!)        = ''              | ''                 | 'CS32431FE01'           |'R0201'| '(SMR0201AW)'                  | '24.3K'   | '1%'    | '1/20W'  | 'IO'       | 'RES CHIP 24.3K 1/20W(+-1%,0201)'                  | 'CHIPR0201'    | ''          | ''            | '20180807'
 '24.9K'      | '1%'      | '1/20W'  | '0201LF'  | 'CHIP'   | 'CS32491FE04'(!)        = ''              | ''                 | 'CS32491FE04'           |'R0201'| '(SMR0201AW)'                  | '24.9K'   | '1%'    | '1/20W'  | 'DISCRETE' | 'RES CHIP 24.9K 1/20W +-1%(0201)'                  | 'CHIPR0201'    | ''          | ''            | '20180807'
 '24.9K'      | '1%'      | '1/20W'  | '0201LF'  | 'EMPTY'  | 'CS32491FE04'(!)        = ''              | ''                 | 'CS32491FE04'           |'R0201'| '(SMR0201AW)'                  | '24.9K'   | '1%'    | '1/20W'  | 'IO'       | 'RES CHIP 24.9K 1/20W +-1%(0201)'                  | 'CHIPR0201'    | ''          | ''            | '20180807'
 '25.5K'      | '1%'      | '1/20W'  | '0201LF'  | 'CHIP'   | 'CS32551FE00'(!)        = ''              | ''                 | 'CS32551FE00'           |'R0201'| '(SMR0201AW)'                  | '25.5K'   | '1%'    | '1/20W'  | 'DISCRETE' | 'RES CHIP 25.5K 1/20W +-1%(0201)'                  | 'CHIPR0201'    | ''          | ''            | '20180807'
 '25.5K'      | '1%'      | '1/20W'  | '0201LF'  | 'EMPTY'  | 'CS32551FE00'(!)        = ''              | ''                 | 'CS32551FE00'           |'R0201'| '(SMR0201AW)'                  | '25.5K'   | '1%'    | '1/20W'  | 'IO'       | 'RES CHIP 25.5K 1/20W +-1%(0201)'                  | 'CHIPR0201'    | ''          | ''            | '20180807'
 '100K'       | '1%'      | '1/20W'  | '0201LF'  | 'CHIP'   | 'CS41001FE08'(!)        = ''              | ''                 | 'CS41001FE08'           |'R0201'| '(SMR0201AW)'                  | '100K'    | '1%'    | '1/20W'  | 'DISCRETE' | 'RES CHIP 100K(1/20W,+-1%,0201)'                   | 'CHIPR0201'    | ''          | ''            | '20180807'
 '100K'       | '1%'      | '1/20W'  | '0201LF'  | 'EMPTY'  | 'CS41001FE08'(!)        = ''              | ''                 | 'CS41001FE08'           |'R0201'| '(SMR0201AW)'                  | '100K'    | '1%'    | '1/20W'  | 'IO'       | 'RES CHIP 100K(1/20W,+-1%,0201)'                   | 'CHIPR0201'    | ''          | ''            | '20180807'
 '133K'       | '1%'      | '1/20W'  | '0201LF'  | 'CHIP'   | 'CS41331FE00'(!)        = ''              | ''                 | 'CS41331FE00'           |'R0201'| '(SMR0201AW)'                  | '133K'    | '1%'    | '1/20W'  | 'DISCRETE' | 'RES CHIP 133K 1/20W +-1%(0201)'                   | 'CHIPR0201'    | ''          | ''            | '20180807'
 '133K'       | '1%'      | '1/20W'  | '0201LF'  | 'EMPTY'  | 'CS41331FE00'(!)        = ''              | ''                 | 'CS41331FE00'           |'R0201'| '(SMR0201AW)'                  | '133K'    | '1%'    | '1/20W'  | 'IO'       | 'RES CHIP 133K 1/20W +-1%(0201)'                   | 'CHIPR0201'    | ''          | ''            | '20180807'
 '169K'       | '1%'      | '1/20W'  | '0201LF'  | 'CHIP'   | 'CS41691FE00'(!)        = ''              | ''                 | 'CS41691FE00'           |'R0201'| '(SMR0201AW)'                  | '169K'    | '1%'    | '1/20W'  | 'DISCRETE' | 'RES CHIP 169K 1/20W +-1%(0201)'                   | 'CHIPR0201'    | ''          | ''            | '20180807'
 '169K'       | '1%'      | '1/20W'  | '0201LF'  | 'EMPTY'  | 'CS41691FE00'(!)        = ''              | ''                 | 'CS41691FE00'           |'R0201'| '(SMR0201AW)'                  | '169K'    | '1%'    | '1/20W'  | 'IO'       | 'RES CHIP 169K 1/20W +-1%(0201)'                   | 'CHIPR0201'    | ''          | ''            | '20180807'
 '249K'       | '1%'      | '1/20W'  | '0201LF'  | 'CHIP'   | 'CS42491FE01'(!)        = ''              | ''                 | 'CS42491FE01'           |'R0201'| '(SMR0201AW)'                  | '249K'    | '1%'    | '1/20W'  | 'DISCRETE' | 'RES CHIP 249K 1/20W +-1%(0201)'                   | 'CHIPR0201'    | ''          | ''            | '20180807'
 '249K'       | '1%'      | '1/20W'  | '0201LF'  | 'EMPTY'  | 'CS42491FE01'(!)        = ''              | ''                 | 'CS42491FE01'           |'R0201'| '(SMR0201AW)'                  | '249K'    | '1%'    | '1/20W'  | 'IO'       | 'RES CHIP 249K 1/20W +-1%(0201)'                   | 'CHIPR0201'    | ''          | ''            | '20180807'
 '1M'         | '1%'      | '1/20W'  | '0201LF'  | 'CHIP'   | 'CS51001FE00'(!)        = ''              | ''                 | 'CS51001FE00'           |'R0201'| '(SMR0201AW)'                  | '1M'      | '1%'    | '1/20W'  | 'DISCRETE' | 'RES CHIP 1M 1/20W +-1%(0201)'                     | 'CHIPR0201'    | ''          | ''            | '20180807'
 '1M'         | '1%'      | '1/20W'  | '0201LF'  | 'EMPTY'  | 'CS51001FE00'(!)        = ''              | ''                 | 'CS51001FE00'           |'R0201'| '(SMR0201AW)'                  | '1M'      | '1%'    | '1/20W'  | 'IO'       | 'RES CHIP 1M 1/20W +-1%(0201)'                     | 'CHIPR0201'    | ''          | ''            | '20180807'
 '10'         | '1%'      | '1/20W'  | '0201LF'  | 'CHIP'   | 'CS01001FE00'(!)        = ''              | ''                 | 'CS01001FE00'           |'R0201'| '(SMR0201AW)'                  | '10'      | '1%'    | '1/20W'  | 'DISCRETE' | 'RES CHIP 10 1/20W +-1%(0201)'                     | 'CHIPR0201'    | ''          | ''            | '20180807'
 '10'         | '1%'      | '1/20W'  | '0201LF'  | 'EMPTY'  | 'CS01001FE00'(!)        = ''              | ''                 | 'CS01001FE00'           |'R0201'| '(SMR0201AW)'                  | '10'      | '1%'    | '1/20W'  | 'IO'       | 'RES CHIP 10 1/20W +-1%(0201)'                     | 'CHIPR0201'    | ''          | ''            | '20180807'
 '510'        | '5%'      | '1/20W'  | '0201LF'  | 'CHIP'   | 'CS15101JE00'(!)        = ''              | ''                 | 'CS15101JE00'           |'R0201'| '(SMR0201AW)'                  | '510'     | '5%'    | '1/20W'  | 'DISCRETE' | 'RES CHIP 510(1/20W,+-5%,0201)'                    | 'CHIPR0201'    | ''          | ''            | '20180807'
 '510'        | '5%'      | '1/20W'  | '0201LF'  | 'EMPTY'  | 'CS15101JE00'(!)        = ''              | ''                 | 'CS15101JE00'           |'R0201'| '(SMR0201AW)'                  | '510'     | '5%'    | '1/20W'  | 'IO'       | 'RES CHIP 510(1/20W,+-5%,0201)'                    | 'CHIPR0201'    | ''          | ''            | '20180807'
 '68.1'       | '1%'      | '1/20W'  | '0201LF'  | 'CHIP'   | 'CS06811FE01'(!)        = ''              | ''                 | 'CS06811FE01'           |'R0201'| '(SMR0201AW)'                  | '68.1'    | '1%'    | '1/20W'  | 'DISCRETE' | 'RES CHIP 68.1 1/20W +-1%(0201)'                   | 'CHIPR0201'    | ''          | ''            | '20180807'
 '68.1'       | '1%'      | '1/20W'  | '0201LF'  | 'EMPTY'  | 'CS06811FE01'(!)        = ''              | ''                 | 'CS06811FE01'           |'R0201'| '(SMR0201AW)'                  | '68.1'    | '1%'    | '1/20W'  | 'IO'       | 'RES CHIP 68.1 1/20W +-1%(0201)'                   | 'CHIPR0201'    | ''          | ''            | '20180807'
 '750'        | '1%'      | '1/20W'  | '0201LF'  | 'CHIP'   | 'CS17501FE00'(!)        = ''              | ''                 | 'CS17501FE00'           |'R0201'| '(SMR0201AW)'                  | '750'     | '1%'    | '1/20W'  | 'DISCRETE' | 'RES CHIP 750 1/20W +-1%(0201)'                    | 'CHIPR0201'    | ''          | ''            | '20180807'
 '750'        | '1%'      | '1/20W'  | '0201LF'  | 'EMPTY'  | 'CS17501FE00'(!)        = ''              | ''                 | 'CS17501FE00'           |'R0201'| '(SMR0201AW)'                  | '750'     | '1%'    | '1/20W'  | 'IO'       | 'RES CHIP 750 1/20W +-1%(0201)'                    | 'CHIPR0201'    | ''          | ''            | '20180807'
 '8.45K'      | '1%'      | '1/20W'  | '0201LF'  | 'CHIP'   | 'CS28451FE01'(!)        = ''              | ''                 | 'CS28451FE01'           |'R0201'| '(SMR0201AW)'                  | '8.45K'   | '1%'    | '1/20W'  | 'DISCRETE' | 'RES CHIP 8.45K 1/20W +-1%(0201)'                  | 'CHIPR0201'    | ''          | ''            | '20180807'
 '8.45K'      | '1%'      | '1/20W'  | '0201LF'  | 'EMPTY'  | 'CS28451FE01'(!)        = ''              | ''                 | 'CS28451FE01'           |'R0201'| '(SMR0201AW)'                  | '8.45K'   | '1%'    | '1/20W'  | 'IO'       | 'RES CHIP 8.45K 1/20W +-1%(0201)'                  | 'CHIPR0201'    | ''          | ''            | '20180807'
 '12.4K'      | '1%'      | '1/20W'  | '0201LF'  | 'CHIP'   | 'CS31241FE02'(!)        = ''              | ''                 | 'CS31241FE02'           |'R0201'| '(SMR0201AW)'                  | '12.4K'   | '1%'    | '1/20W'  | 'DISCRETE' | 'RES CHIP 12.4K 1/20W +-1% (0201) '                | 'CHIPR0201'    | ''          | ''            | '20180807'
 '12.4K'      | '1%'      | '1/20W'  | '0201LF'  | 'EMPTY'  | 'CS31241FE02'(!)        = ''              | ''                 | 'CS31241FE02'           |'R0201'| '(SMR0201AW)'                  | '12.4K'   | '1%'    | '1/20W'  | 'IO'       | 'RES CHIP 12.4K 1/20W +-1% (0201) '                | 'CHIPR0201'    | ''          | ''            | '20180807'
 '19.6K'      | '1%'      | '1/20W'  | '0201LF'  | 'CHIP'   | 'CS31961FE01'(!)        = ''              | ''                 | 'CS31961FE01'           |'R0201'| '(SMR0201AW)'                  | '19.6K'   | '1%'    | '1/20W'  | 'DISCRETE' | 'RES CHIP 19.6K 1/20W +-1%(0201)'                  | 'CHIPR0201'    | ''          | ''            | '20180807'
 '19.6K'      | '1%'      | '1/20W'  | '0201LF'  | 'EMPTY'  | 'CS31961FE01'(!)        = ''              | ''                 | 'CS31961FE01'           |'R0201'| '(SMR0201AW)'                  | '19.6K'   | '1%'    | '1/20W'  | 'IO'       | 'RES CHIP 19.6K 1/20W +-1%(0201)'                  | 'CHIPR0201'    | ''          | ''            | '20180807'
 '44.2'       | '1%'      | '1/20W'  | '0201LF'  | 'CHIP'   | 'CS04421FE00'(!)        = ''              | ''                 | 'CS04421FE00'           |'R0201'| '(SMR0201AW)'                  | '44.2'    | '1%'    | '1/20W'  | 'DISCRETE' | 'RES CHIP 44.2 1/20W +-1%(0201)'                   | 'CHIPR0201'    | ''          | ''            | '20180807'
 '44.2'       | '1%'      | '1/20W'  | '0201LF'  | 'EMPTY'  | 'CS04421FE00'(!)        = ''              | ''                 | 'CS04421FE00'           |'R0201'| '(SMR0201AW)'                  | '44.2'    | '1%'    | '1/20W'  | 'IO'       | 'RES CHIP 44.2 1/20W +-1%(0201)'                   | 'CHIPR0201'    | ''          | ''            | '20180807'
 '33K'        | '1%'      | '1/20W'  | '0201LF'  | 'CHIP'   | 'CS33301FE00'(!)        = ''              | ''                 | 'CS33301FE00'           |'R0201'| '(SMR0201AW)'                  | '33K'     | '1%'    | '1/20W'  | 'DISCRETE' | 'RES CHIP 33K(1/20W,+-1%,0201)'                    | 'CHIPR0201'    | ''          | ''            | '20180807'
 '33K'        | '1%'      | '1/20W'  | '0201LF'  | 'EMPTY'  | 'CS33301FE00'(!)        = ''              | ''                 | 'CS33301FE00'           |'R0201'| '(SMR0201AW)'                  | '33K'     | '1%'    | '1/20W'  | 'IO'       | 'RES CHIP 33K(1/20W,+-1%,0201)'                    | 'CHIPR0201'    | ''          | ''            | '20180807'
 '37.4K'      | '1%'      | '1/20W'  | '0201LF'  | 'CHIP'   | 'CS33741FE01'(!)        = ''              | ''                 | 'CS33741FE01'           |'R0201'| '(SMR0201AW)'                  | '37.4K'   | '1%'    | '1/20W'  | 'DISCRETE' | 'RES CHIP 37.4K(1/20W,+-1%,0201)'                  | 'CHIPR0201'    | ''          | ''            | '20180807'
 '37.4K'      | '1%'      | '1/20W'  | '0201LF'  | 'EMPTY'  | 'CS33741FE01'(!)        = ''              | ''                 | 'CS33741FE01'           |'R0201'| '(SMR0201AW)'                  | '37.4K'   | '1%'    | '1/20W'  | 'IO'       | 'RES CHIP 37.4K(1/20W,+-1%,0201)'                  | 'CHIPR0201'    | ''          | ''            | '20180807'
 '39.2K'      | '1%'      | '1/20W'  | '0201LF'  | 'CHIP'   | 'CS33921FE00'(!)        = ''              | ''                 | 'CS33921FE00'           |'R0201'| '(SMR0201AW)'                  | '39.2K'   | '1%'    | '1/20W'  | 'DISCRETE' | 'RES CHIP 39.2K 1/20W +-1%(0201)'                  | 'CHIPR0201'    | ''          | ''            | '20180807'
 '39.2K'      | '1%'      | '1/20W'  | '0201LF'  | 'EMPTY'  | 'CS33921FE00'(!)        = ''              | ''                 | 'CS33921FE00'           |'R0201'| '(SMR0201AW)'                  | '39.2K'   | '1%'    | '1/20W'  | 'IO'       | 'RES CHIP 39.2K 1/20W +-1%(0201)'                  | 'CHIPR0201'    | ''          | ''            | '20180807'
 '47.5K'      | '1%'      | '1/20W'  | '0201LF'  | 'CHIP'   | 'CS34751FE02'(!)        = ''              | ''                 | 'CS34751FE02'           |'R0201'| '(SMR0201AW)'                  | '47.5K'   | '1%'    | '1/20W'  | 'DISCRETE' | 'RES CHIP 47.5K 1/20W +-1%(0201)'                  | 'CHIPR0201'    | ''          | ''            | '20180807'
 '47.5K'      | '1%'      | '1/20W'  | '0201LF'  | 'EMPTY'  | 'CS34751FE02'(!)        = ''              | ''                 | 'CS34751FE02'           |'R0201'| '(SMR0201AW)'                  | '47.5K'   | '1%'    | '1/20W'  | 'IO'       | 'RES CHIP 47.5K 1/20W +-1%(0201)'                  | 'CHIPR0201'    | ''          | ''            | '20180807'
 '52.3K'      | '1%'      | '1/20W'  | '0201LF'  | 'CHIP'   | 'CS35231FE01'(!)        = ''              | ''                 | 'CS35231FE01'           |'R0201'| '(SMR0201AW)'                  | '52.3K'   | '1%'    | '1/20W'  | 'DISCRETE' | 'RES CHIP 52.3K 1/20W +-1%(0201)'                  | 'CHIPR0201'    | ''          | ''            | '20180807'
 '52.3K'      | '1%'      | '1/20W'  | '0201LF'  | 'EMPTY'  | 'CS35231FE01'(!)        = ''              | ''                 | 'CS35231FE01'           |'R0201'| '(SMR0201AW)'                  | '52.3K'   | '1%'    | '1/20W'  | 'IO'       | 'RES CHIP 52.3K 1/20W +-1%(0201)'                  | 'CHIPR0201'    | ''          | ''            | '20180807'
 '64.9K'      | '1%'      | '1/20W'  | '0201LF'  | 'CHIP'   | 'CS36491FE00'(!)        = ''              | ''                 | 'CS36491FE00'           |'R0201'| '(SMR0201AW)'                  | '64.9K'   | '1%'    | '1/20W'  | 'DISCRETE' | 'RES CHIP 64.9K 1/20W +-1%(0201)'                  | 'CHIPR0201'    | ''          | ''            | '20180807'
 '64.9K'      | '1%'      | '1/20W'  | '0201LF'  | 'EMPTY'  | 'CS36491FE00'(!)        = ''              | ''                 | 'CS36491FE00'           |'R0201'| '(SMR0201AW)'                  | '64.9K'   | '1%'    | '1/20W'  | 'IO'       | 'RES CHIP 64.9K 1/20W +-1%(0201)'                  | 'CHIPR0201'    | ''          | ''            | '20180807'
 '66.5K'      | '1%'      | '1/20W'  | '0201LF'  | 'CHIP'   | 'CS36651FE04'(!)        = ''              | ''                 | 'CS36651FE04'           |'R0201'| '(SMR0201AW)'                  | '66.5K'   | '1%'    | '1/20W'  | 'DISCRETE' | 'RES CHIP 66.5K 1/20W +-1%(0201)'                  | 'CHIPR0201'    | ''          | ''            | '20180807'
 '66.5K'      | '1%'      | '1/20W'  | '0201LF'  | 'EMPTY'  | 'CS36651FE04'(!)        = ''              | ''                 | 'CS36651FE04'           |'R0201'| '(SMR0201AW)'                  | '66.5K'   | '1%'    | '1/20W'  | 'IO'       | 'RES CHIP 66.5K 1/20W +-1%(0201)'                  | 'CHIPR0201'    | ''          | ''            | '20180807'
 '97.6K'      | '1%'      | '1/20W'  | '0201LF'  | 'CHIP'   | 'CS39761FE00'(!)        = ''              | ''                 | 'CS39761FE00'           |'R0201'| '(SMR0201AW)'                  | '97.6K'   | '1%'    | '1/20W'  | 'DISCRETE' | 'RES CHIP 97.6K 1/20W,+-1%(0201)'                  | 'CHIPR0201'    | ''          | ''            | '20180807'
 '97.6K'      | '1%'      | '1/20W'  | '0201LF'  | 'EMPTY'  | 'CS39761FE00'(!)        = ''              | ''                 | 'CS39761FE00'           |'R0201'| '(SMR0201AW)'                  | '97.6K'   | '1%'    | '1/20W'  | 'IO'       | 'RES CHIP 97.6K 1/20W,+-1%(0201)'                  | 'CHIPR0201'    | ''          | ''            | '20180807'
 '107K'       | '1%'      | '1/20W'  | '0201LF'  | 'CHIP'   | 'CS41071FE00'(!)        = ''              | ''                 | 'CS41071FE00'           |'R0201'| '(SMR0201AW)'                  | '107K'    | '1%'    | '1/20W'  | 'DISCRETE' | 'RES CHIP 107K 1/20W +-1%(0201)'                   | 'CHIPR0201'    | ''          | ''            | '20180807'
 '107K'       | '1%'      | '1/20W'  | '0201LF'  | 'EMPTY'  | 'CS41071FE00'(!)        = ''              | ''                 | 'CS41071FE00'           |'R0201'| '(SMR0201AW)'                  | '107K'    | '1%'    | '1/20W'  | 'IO'       | 'RES CHIP 107K 1/20W +-1%(0201)'                   | 'CHIPR0201'    | ''          | ''            | '20180807'
 '124K'       | '1%'      | '1/20W'  | '0201LF'  | 'CHIP'   | 'CS41241FE01'(!)        = ''              | ''                 | 'CS41241FE01'           |'R0201'| '(SMR0201AW)'                  | '124K'    | '1%'    | '1/20W'  | 'DISCRETE' | 'RES CHIP 124K 1/20W +-1%(0201)'                   | 'CHIPR0201'    | ''          | ''            | '20180807'
 '124K'       | '1%'      | '1/20W'  | '0201LF'  | 'EMPTY'  | 'CS41241FE01'(!)        = ''              | ''                 | 'CS41241FE01'           |'R0201'| '(SMR0201AW)'                  | '124K'    | '1%'    | '1/20W'  | 'IO'       | 'RES CHIP 124K 1/20W +-1%(0201)'                   | 'CHIPR0201'    | ''          | ''            | '20180807'
 '130K'       | '1%'      | '1/20W'  | '0201LF'  | 'CHIP'   | 'CS41301FE00'(!)        = ''              | ''                 | 'CS41301FE00'           |'R0201'| '(SMR0201AW)'                  | '130K'    | '1%'    | '1/20W'  | 'DISCRETE' | 'RES CHIP 130K 1/20W +-1%(0201)'                   | 'CHIPR0201'    | ''          | ''            | '20180807'
 '130K'       | '1%'      | '1/20W'  | '0201LF'  | 'EMPTY'  | 'CS41301FE00'(!)        = ''              | ''                 | 'CS41301FE00'           |'R0201'| '(SMR0201AW)'                  | '130K'    | '1%'    | '1/20W'  | 'IO'       | 'RES CHIP 130K 1/20W +-1%(0201)'                   | 'CHIPR0201'    | ''          | ''            | '20180807'
 '412K'       | '1%'      | '1/20W'  | '0201LF'  | 'CHIP'   | 'CS44121FE00'(!)        = ''              | ''                 | 'CS44121FE00'           |'R0201'| '(SMR0201AW)'                  | '412K'    | '1%'    | '1/20W'  | 'DISCRETE' | 'RES CHIP 412K 1/20W +1%(0201)'                    | 'CHIPR0201'    | ''          | ''            | '20180807'
 '412K'       | '1%'      | '1/20W'  | '0201LF'  | 'EMPTY'  | 'CS44121FE00'(!)        = ''              | ''                 | 'CS44121FE00'           |'R0201'| '(SMR0201AW)'                  | '412K'    | '1%'    | '1/20W'  | 'IO'       | 'RES CHIP 412K 1/20W +1%(0201)'                    | 'CHIPR0201'    | ''          | ''            | '20180807'
 '470K'       | '1%'      | '1/20W'  | '0201LF'  | 'CHIP'   | 'CS44701FE00'(!)        = 'End of Design' | 'Comp-Approve'     | 'CS44701FE00'           |'R0201'| '(SMR0201AW)'                  | '470K'    | '1%'    | '1/20W'  | 'DISCRETE' | 'RES CHIP 470K 1/20W +-1%(0201)'                   | 'CHIPR0201'    | ''          | ''            | '20180807'
 '470K'       | '1%'      | '1/20W'  | '0201LF'  | 'EMPTY'  | 'CS44701FE00'(!)        = 'End of Design' | 'Comp-Approve'     | 'CS44701FE00'           |'R0201'| '(SMR0201AW)'                  | '470K'    | '1%'    | '1/20W'  | 'IO'       | 'RES CHIP 470K 1/20W +-1%(0201)'                   | 'CHIPR0201'    | ''          | ''            | '20180807'
 '510K'       | '5%'      | '1/20W'  | '0201LF'  | 'CHIP'   | 'CS45101JE00'(!)        = ''              | ''                 | 'CS45101JE00'           |'R0201'| '(SMR0201AW)'                  | '510K'    | '5%'    | '1/20W'  | 'DISCRETE' | 'RES CHIP 510K 1/20W +-5%(0201)'                   | 'CHIPR0201'    | ''          | ''            | '20180807'
 '510K'       | '5%'      | '1/20W'  | '0201LF'  | 'EMPTY'  | 'CS45101JE00'(!)        = ''              | ''                 | 'CS45101JE00'           |'R0201'| '(SMR0201AW)'                  | '510K'    | '5%'    | '1/20W'  | 'IO'       | 'RES CHIP 510K 1/20W +-5%(0201)'                   | 'CHIPR0201'    | ''          | ''            | '20180807'
 '562K'       | '1%'      | '1/20W'  | '0201LF'  | 'CHIP'   | 'CS45621FE00'(!)        = ''              | ''                 | 'CS45621FE00'           |'R0201'| '(SMR0201AW)'                  | '562K'    | '1%'    | '1/20W'  | 'DISCRETE' | 'RES CHIP 562K 1/20W +-1%(0201)'                   | 'CHIPR0201'    | ''          | ''            | '20180807'
 '562K'       | '1%'      | '1/20W'  | '0201LF'  | 'EMPTY'  | 'CS45621FE00'(!)        = ''              | ''                 | 'CS45621FE00'           |'R0201'| '(SMR0201AW)'                  | '562K'    | '1%'    | '1/20W'  | 'IO'       | 'RES CHIP 562K 1/20W +-1%(0201)'                   | 'CHIPR0201'    | ''          | ''            | '20180807'
 '10M'        | '1%'      | '1/20W'  | '0201LF'  | 'CHIP'   | 'CS61001FE00'(!)        = ''              | ''                 | 'CS61001FE00'           |'R0201'| '(SMR0201AW)'                  | '10M'     | '1%'    | '1/20W'  | 'DISCRETE' | 'RES CHIP 10M 1/20W +-1%(0201)'                    | 'CHIPR0201'    | ''          | ''            | '20180807'
 '10M'        | '1%'      | '1/20W'  | '0201LF'  | 'EMPTY'  | 'CS61001FE00'(!)        = ''              | ''                 | 'CS61001FE00'           |'R0201'| '(SMR0201AW)'                  | '10M'     | '1%'    | '1/20W'  | 'IO'       | 'RES CHIP 10M 1/20W +-1%(0201)'                    | 'CHIPR0201'    | ''          | ''            | '20180807'
 '27K'        | '1%'      | '1/20W'  | '0201LF'  | 'CHIP'   | 'CS32701FE01'(!)        = ''              | ''                 | 'CS32701FE01'           |'R0201'| '(SMR0201AW)'                  | '27K'     | '1%'    | '1/20W'  | 'DISCRETE' | 'RES CHIP 27K(1/20W,+-1%,0201)'                    | 'CHIPR0201'    | ''          | ''            | '20180807'
 '27K'        | '1%'      | '1/20W'  | '0201LF'  | 'EMPTY'  | 'CS32701FE01'(!)        = ''              | ''                 | 'CS32701FE01'           |'R0201'| '(SMR0201AW)'                  | '27K'     | '1%'    | '1/20W'  | 'IO'       | 'RES CHIP 27K(1/20W,+-1%,0201)'                    | 'CHIPR0201'    | ''          | ''            | '20180807'
 '30.1K'      | '1%'      | '1/20W'  | '0201LF'  | 'CHIP'   | 'CS33011FE00'(!)        = 'End of Design' | 'Comp-Approve'     | 'CS33011FE00'           |'R0201'| '(SMR0201AW)'                  | '30.1K'   | '1%'    | '1/20W'  | 'DISCRETE' | 'RES CHIP 30.1K 1/20W +-1%(0201)'                  | 'CHIPR0201'    | ''          | ''            | '20180807'
 '30.1K'      | '1%'      | '1/20W'  | '0201LF'  | 'EMPTY'  | 'CS33011FE00'(!)        = 'End of Design' | 'Comp-Approve'     | 'CS33011FE00'           |'R0201'| '(SMR0201AW)'                  | '30.1K'   | '1%'    | '1/20W'  | 'IO'       | 'RES CHIP 30.1K 1/20W +-1%(0201)'                  | 'CHIPR0201'    | ''          | ''            | '20180807'
 '220K'       | '5%'      | '1/20W'  | '0201LF'  | 'CHIP'   | 'CS42201JE00'(!)        = ''              | ''                 | 'CS42201JE00'           |'R0201'| '(SMR0201AW)'                  | '220K'    | '5%'    | '1/20W'  | 'DISCRETE' | 'RES CHIP 220K 1/20W +-5% (0201)'                  | 'CHIPR0201'    | ''          | ''            | '20180807'
 '220K'       | '5%'      | '1/20W'  | '0201LF'  | 'EMPTY'  | 'CS42201JE00'(!)        = ''              | ''                 | 'CS42201JE00'           |'R0201'| '(SMR0201AW)'                  | '220K'    | '5%'    | '1/20W'  | 'IO'       | 'RES CHIP 220K 1/20W +-5% (0201)'                  | 'CHIPR0201'    | ''          | ''            | '20180807'
 '20'         | '1%'      | '1/20W'  | '0201LF'  | 'CHIP'   | 'CS02001FE00'(!)        = ''              | ''                 | 'CS02001FE00'           |'R0201'| '(SMR0201AW)'                  | '20'      | '1%'    | '1/20W'  | 'DISCRETE' | 'RES CHIP 20 1/20W +-1%(0201)'                     | 'CHIPR0201'    | ''          | ''            | '20120118'
 '20'         | '1%'      | '1/20W'  | '0201LF'  | 'EMPTY'  | 'CS02001FE00'(!)        = ''              | ''                 | 'CS02001FE00'           |'R0201'| '(SMR0201AW)'                  | '20'      | '1%'    | '1/20W'  | 'IO'       | 'RES CHIP 20 1/20W +-1%(0201)'                     | 'CHIPR0201'    | ''          | ''            | '20120118'
 '121'        | '1%'      | '1/20W'  | '0201LF'  | 'CHIP'   | 'CS11211FE00'(!)        = ''              | ''                 | 'CS11211FE00'           |'R0201'| '(SMR0201AW)'                  | '121'     | '1%'    | '1/20W'  | 'DISCRETE' | 'RES CHIP 121 1/20W +-1%(0201)'                    | 'CHIPR0201'    | ''          | ''            | '20180808'
 '121'        | '1%'      | '1/20W'  | '0201LF'  | 'EMPTY'  | 'CS11211FE00'(!)        = ''              | ''                 | 'CS11211FE00'           |'R0201'| '(SMR0201AW)'                  | '121'     | '1%'    | '1/20W'  | 'IO'       | 'RES CHIP 121 1/20W +-1%(0201)'                    | 'CHIPR0201'    | ''          | ''            | '20180808'
 '2.4K'       | '1%'      | '1/20W'  | '0201LF'  | 'CHIP'   | 'CS22401FE00'(!)        = ''              | ''                 | 'CS22401FE00'           |'R0201'| '(SMR0201AW)'                  | '2.4K'    | '1%'    | '1/20W'  | 'DISCRETE' | 'RES CHIP 2.4K 1/20W +-1%(0201)'                   | 'CHIPR0201'    | ''          | ''            | '20180808'
 '2.4K'       | '1%'      | '1/20W'  | '0201LF'  | 'EMPTY'  | 'CS22401FE00'(!)        = ''              | ''                 | 'CS22401FE00'           |'R0201'| '(SMR0201AW)'                  | '2.4K'    | '1%'    | '1/20W'  | 'IO'       | 'RES CHIP 2.4K 1/20W +-1%(0201)'                   | 'CHIPR0201'    | ''          | ''            | '20180808'
 '2.49K'      | '1%'      | '1/20W'  | '0201LF'  | 'CHIP'   | 'CS22491FE00'(!)        = 'End of Design' | 'Comp-Approve'     | 'CS22491FE00'           |'R0201'| '(SMR0201AW)'                  | '2.49K'   | '1%'    | '1/20W'  | 'DISCRETE' | 'RES CHIP 2.49K(1/20W.+-1%.0201)HF'                | 'CHIPR0201'    | ''          | ''            | '20110106'
 '2.49K'      | '1%'      | '1/20W'  | '0201LF'  | 'EMPTY'  | 'CS22491FE00'(!)        = 'End of Design' | 'Comp-Approve'     | 'CS22491FE00'           |'R0201'| '(SMR0201AW)'                  | '2.49K'   | '1%'    | '1/20W'  | 'IO'       | 'RES CHIP 2.49K(1/20W.+-1%.0201)HF'                | 'CHIPR0201'    | ''          | ''            | '20110106'
 '2.7K'       | '5%'      | '1/20W'  | '0201LF'  | 'CHIP'   | 'CS22701JE00'(!)        = ''              | ''                 | 'CS22701JE00'           |'R0201'| '(SMR0201AW)'                  | '2.7K'    | '5%'    | '1/20W'  | 'DISCRETE' | 'RES CHIP 2.7K 1/20W +-5%(0201)'                   | 'CHIPR0201'    | ''          | ''            | '20180808'
 '2.7K'       | '5%'      | '1/20W'  | '0201LF'  | 'EMPTY'  | 'CS22701JE00'(!)        = ''              | ''                 | 'CS22701JE00'           |'R0201'| '(SMR0201AW)'                  | '2.7K'    | '5%'    | '1/20W'  | 'IO'       | 'RES CHIP 2.7K 1/20W +-5%(0201)'                   | 'CHIPR0201'    | ''          | ''            | '20180808'
 '4.02K'      | '1%'      | '1/20W'  | '0201LF'  | 'CHIP'   | 'CS24021FE01'(!)        = ''              | ''                 | 'CS24021FE01'           |'R0201'| '(SMR0201AW)'                  | '4.02K'   | '1%'    | '1/20W'  | 'DISCRETE' | 'RES CHIP 4.02K 1/20W +-1%(0201)'                  | 'CHIPR0201'    | ''          | ''            | '20180808'
 '4.02K'      | '1%'      | '1/20W'  | '0201LF'  | 'EMPTY'  | 'CS24021FE01'(!)        = ''              | ''                 | 'CS24021FE01'           |'R0201'| '(SMR0201AW)'                  | '4.02K'   | '1%'    | '1/20W'  | 'IO'       | 'RES CHIP 4.02K 1/20W +-1%(0201)'                  | 'CHIPR0201'    | ''          | ''            | '20180808'
 '4.42K'      | '1%'      | '1/20W'  | '0201LF'  | 'CHIP'   | 'CS24421FE01'(!)        = ''              | ''                 | 'CS24421FE01'           |'R0201'| '(SMR0201AW)'                  | '4.42K'   | '1%'    | '1/20W'  | 'DISCRETE' | 'RES CHIP 4.42K 1/20W +-1%(0201)'                  | 'CHIPR0201'    | ''          | ''            | '20180808'
 '4.42K'      | '1%'      | '1/20W'  | '0201LF'  | 'EMPTY'  | 'CS24421FE01'(!)        = ''              | ''                 | 'CS24421FE01'           |'R0201'| '(SMR0201AW)'                  | '4.42K'   | '1%'    | '1/20W'  | 'IO'       | 'RES CHIP 4.42K 1/20W +-1%(0201)'                  | 'CHIPR0201'    | ''          | ''            | '20180808'
 '4.75K'      | '1%'      | '1/20W'  | '0201LF'  | 'CHIP'   | 'CS24751FE01'(!)        = ''              | ''                 | 'CS24751FE01'           |'R0201'| '(SMR0201AW)'                  | '4.75K'   | '1%'    | '1/20W'  | 'DISCRETE' | 'RES CHIP 4.75K (1/20W,+-1%,0201)'                 | 'CHIPR0201'    | ''          | ''            | '20180808'
 '4.75K'      | '1%'      | '1/20W'  | '0201LF'  | 'EMPTY'  | 'CS24751FE01'(!)        = ''              | ''                 | 'CS24751FE01'           |'R0201'| '(SMR0201AW)'                  | '4.75K'   | '1%'    | '1/20W'  | 'IO'       | 'RES CHIP 4.75K (1/20W,+-1%,0201)'                 | 'CHIPR0201'    | ''          | ''            | '20180808'
 '4.87K'      | '1%'      | '1/20W'  | '0201LF'  | 'CHIP'   | 'CS24871FE00'(!)        = ''              | ''                 | 'CS24871FE00'           |'R0201'| '(SMR0201AW)'                  | '4.87K'   | '1%'    | '1/20W'  | 'DISCRETE' | 'RES CHIP 4.87K 1/20W +-1%(0201)'                  | 'CHIPR0201'    | ''          | ''            | '20180808'
 '4.87K'      | '1%'      | '1/20W'  | '0201LF'  | 'EMPTY'  | 'CS24871FE00'(!)        = ''              | ''                 | 'CS24871FE00'           |'R0201'| '(SMR0201AW)'                  | '4.87K'   | '1%'    | '1/20W'  | 'IO'       | 'RES CHIP 4.87K 1/20W +-1%(0201)'                  | 'CHIPR0201'    | ''          | ''            | '20180808'
 '34.8K'      | '1%'      | '1/20W'  | '0201LF'  | 'CHIP'   | 'CS33481FE01'(!)        = ''              | ''                 | 'CS33481FE01'           |'R0201'| '(SMR0201AW)'                  | '34.8K'   | '1%'    | '1/20W'  | 'DISCRETE' | 'RES CHIP 34.8K 1/20W +-1%(0201)'                  | 'CHIPR0201'    | ''          | ''            | '20180808'
 '34.8K'      | '1%'      | '1/20W'  | '0201LF'  | 'EMPTY'  | 'CS33481FE01'(!)        = ''              | ''                 | 'CS33481FE01'           |'R0201'| '(SMR0201AW)'                  | '34.8K'   | '1%'    | '1/20W'  | 'IO'       | 'RES CHIP 34.8K 1/20W +-1%(0201)'                  | 'CHIPR0201'    | ''          | ''            | '20180808'
 '6.19K'      | '1%'      | '1/20W'  | '0201LF'  | 'CHIP'   | 'CS26191FE00'(!)        = ''              | ''                 | 'CS26191FE00'           |'R0201'| '(SMR0201AW)'                  | '6.19K'   | '1%'    | '1/20W'  | 'DISCRETE' | 'RES CHIP 6.19K 1/20W +-1%(0201)'                  | 'CHIPR0201'    | ''          | ''            | '20180808'
 '6.19K'      | '1%'      | '1/20W'  | '0201LF'  | 'EMPTY'  | 'CS26191FE00'(!)        = ''              | ''                 | 'CS26191FE00'           |'R0201'| '(SMR0201AW)'                  | '6.19K'   | '1%'    | '1/20W'  | 'IO'       | 'RES CHIP 6.19K 1/20W +-1%(0201)'                  | 'CHIPR0201'    | ''          | ''            | '20180808'
 '402'        | '1%'      | '1/20W'  | '0201LF'  | 'CHIP'   | 'CS14021FE01'(!)        = ''              | ''                 | 'CS14021FE01'           |'R0201'| '(SMR0201AW)'                  | '402'     | '1%'    | '1/20W'  | 'DISCRETE' | 'RES CHIP 402 1/20W +-1%(0201)'                    | 'CHIPR0201'    | ''          | ''            | '20180808'
 '402'        | '1%'      | '1/20W'  | '0201LF'  | 'EMPTY'  | 'CS14021FE01'(!)        = ''              | ''                 | 'CS14021FE01'           |'R0201'| '(SMR0201AW)'                  | '402'     | '1%'    | '1/20W'  | 'IO'       | 'RES CHIP 402 1/20W +-1%(0201)'                    | 'CHIPR0201'    | ''          | ''            | '20180808'
 '6.81K'      | '1%'      | '1/20W'  | '0201LF'  | 'CHIP'   | 'CS26811FE00'(!)        = ''              | ''                 | 'CS26811FE00'           |'R0201'| '(SMR0201AW)'                  | '6.81K'   | '1%'    | '1/20W'  | 'DISCRETE' | 'RES CHIP 6.81K 1/20W +-1%(0201)'                  | 'CHIPR0201'    | ''          | ''            | '20180808'
 '6.81K'      | '1%'      | '1/20W'  | '0201LF'  | 'EMPTY'  | 'CS26811FE00'(!)        = ''              | ''                 | 'CS26811FE00'           |'R0201'| '(SMR0201AW)'                  | '6.81K'   | '1%'    | '1/20W'  | 'IO'       | 'RES CHIP 6.81K 1/20W +-1%(0201)'                  | 'CHIPR0201'    | ''          | ''            | '20180808'
 '7.5K'       | '1%'      | '1/20W'  | '0201LF'  | 'CHIP'   | 'CS27501FE00'(!)        = ''              | ''                 | 'CS27501FE00'           |'R0201'| '(SMR0201AW)'                  | '7.5K'    | '1%'    | '1/20W'  | 'DISCRETE' | 'RES CHIP 7.5K 1/20W +-1%(0201)'                   | 'CHIPR0201'    | ''          | ''            | '20180808'
 '7.5K'       | '1%'      | '1/20W'  | '0201LF'  | 'EMPTY'  | 'CS27501FE00'(!)        = ''              | ''                 | 'CS27501FE00'           |'R0201'| '(SMR0201AW)'                  | '7.5K'    | '1%'    | '1/20W'  | 'IO'       | 'RES CHIP 7.5K 1/20W +-1%(0201)'                   | 'CHIPR0201'    | ''          | ''            | '20180808'
 '8.66K'      | '1%'      | '1/20W'  | '0201LF'  | 'CHIP'   | 'CS28661FE00'(!)        = ''              | ''                 | 'CS28661FE00'           |'R0201'| '(SMR0201AW)'                  | '8.66K'   | '1%'    | '1/20W'  | 'DISCRETE' | 'RES CHIP 8.66K 1/20W,+-1%(0201)'                  | 'CHIPR0201'    | ''          | ''            | '20180808'
 '8.66K'      | '1%'      | '1/20W'  | '0201LF'  | 'EMPTY'  | 'CS28661FE00'(!)        = ''              | ''                 | 'CS28661FE00'           |'R0201'| '(SMR0201AW)'                  | '8.66K'   | '1%'    | '1/20W'  | 'IO'       | 'RES CHIP 8.66K 1/20W,+-1%(0201)'                  | 'CHIPR0201'    | ''          | ''            | '20180808'
 '11K'        | '1%'      | '1/20W'  | '0201LF'  | 'CHIP'   | 'CS31101FE00'(!)        = ''              | ''                 | 'CS31101FE00'           |'R0201'| '(SMR0201AW)'                  | '11K'     | '1%'    | '1/20W'  | 'DISCRETE' | 'RES CHIP 11K 1/20W +-1% (0201)'                   | 'CHIPR0201'    | ''          | ''            | '20180808'
 '11K'        | '1%'      | '1/20W'  | '0201LF'  | 'EMPTY'  | 'CS31101FE00'(!)        = ''              | ''                 | 'CS31101FE00'           |'R0201'| '(SMR0201AW)'                  | '11K'     | '1%'    | '1/20W'  | 'IO'       | 'RES CHIP 11K 1/20W +-1% (0201)'                   | 'CHIPR0201'    | ''          | ''            | '20180808'
 '11.8K'      | '1%'      | '1/20W'  | '0201LF'  | 'CHIP'   | 'CS31181FE01'(!)        = ''              | ''                 | 'CS31181FE01'           |'R0201'| '(SMR0201AW)'                  | '11.8K'   | '1%'    | '1/20W'  | 'DISCRETE' | 'RES CHIP 11.8K 1/20W +-1%(0201)'                  | 'CHIPR0201'    | ''          | ''            | '20180809'
 '11.8K'      | '1%'      | '1/20W'  | '0201LF'  | 'EMPTY'  | 'CS31181FE01'(!)        = ''              | ''                 | 'CS31181FE01'           |'R0201'| '(SMR0201AW)'                  | '11.8K'   | '1%'    | '1/20W'  | 'IO'       | 'RES CHIP 11.8K 1/20W +-1%(0201)'                  | 'CHIPR0201'    | ''          | ''            | '20180809'
 '12.1K'      | '1%'      | '1/20W'  | '0201LF'  | 'CHIP'   | 'CS31211FE08'(!)        = ''              | ''                 | 'CS31211FE08'           |'R0201'| '(SMR0201AW)'                  | '12.1K'   | '1%'    | '1/20W'  | 'DISCRETE' | 'RES CHIP 12.1K 1/20W +-1%(0201)'                  | 'CHIPR0201'    | ''          | ''            | '20180809'
 '12.1K'      | '1%'      | '1/20W'  | '0201LF'  | 'EMPTY'  | 'CS31211FE08'(!)        = ''              | ''                 | 'CS31211FE08'           |'R0201'| '(SMR0201AW)'                  | '12.1K'   | '1%'    | '1/20W'  | 'IO'       | 'RES CHIP 12.1K 1/20W +-1%(0201)'                  | 'CHIPR0201'    | ''          | ''            | '20180809'
 '13K'        | '1%'      | '1/20W'  | '0201LF'  | 'CHIP'   | 'CS31301FE01'(!)        = ''              | ''                 | 'CS31301FE01'           |'R0201'| '(SMR0201AW)'                  | '13K'     | '1%'    | '1/20W'  | 'DISCRETE' | 'RES CHIP 13K 1/20W +-1%(0201)'                    | 'CHIPR0201'    | ''          | ''            | '20180808'
 '13K'        | '1%'      | '1/20W'  | '0201LF'  | 'EMPTY'  | 'CS31301FE01'(!)        = ''              | ''                 | 'CS31301FE01'           |'R0201'| '(SMR0201AW)'                  | '13K'     | '1%'    | '1/20W'  | 'IO'       | 'RES CHIP 13K 1/20W +-1%(0201)'                    | 'CHIPR0201'    | ''          | ''            | '20180808'
 '14K'        | '1%'      | '1/20W'  | '0201LF'  | 'CHIP'   | 'CS31401FE01'(!)        = ''              | ''                 | 'CS31401FE01'           |'R0201'| '(SMR0201AW)'                  | '14K'     | '1%'    | '1/20W'  | 'DISCRETE' | 'RES CHIP 14K 1/20W +-1%(0201)'                    | 'CHIPR0201'    | ''          | ''            | '20180808'
 '14K'        | '1%'      | '1/20W'  | '0201LF'  | 'EMPTY'  | 'CS31401FE01'(!)        = ''              | ''                 | 'CS31401FE01'           |'R0201'| '(SMR0201AW)'                  | '14K'     | '1%'    | '1/20W'  | 'IO'       | 'RES CHIP 14K 1/20W +-1%(0201)'                    | 'CHIPR0201'    | ''          | ''            | '20180808'
 '14.3K'      | '1%'      | '1/20W'  | '0201LF'  | 'CHIP'   | 'CS31431FE00'(!)        = ''              | ''                 | 'CS31431FE00'           |'R0201'| '(SMR0201AW)'                  | '14.3K'   | '1%'    | '1/20W'  | 'DISCRETE' | 'RES CHIP 14.3K 1/20W +-1%(0201)'                  | 'CHIPR0201'    | ''          | ''            | '20180808'
 '14.3K'      | '1%'      | '1/20W'  | '0201LF'  | 'EMPTY'  | 'CS31431FE00'(!)        = ''              | ''                 | 'CS31431FE00'           |'R0201'| '(SMR0201AW)'                  | '14.3K'   | '1%'    | '1/20W'  | 'IO'       | 'RES CHIP 14.3K 1/20W +-1%(0201)'                  | 'CHIPR0201'    | ''          | ''            | '20180808'
 '47.5'       | '1%'      | '1/20W'  | '0201LF'  | 'CHIP'   | 'CS04751FE00'(!)        = ''              | ''                 | 'CS04751FE00'           |'R0201'| '(SMR0201AW)'                  | '47.5'    | '1%'    | '1/20W'  | 'DISCRETE' | 'RES CHIP 47.5 1/20W +-1%(0201)'                   | 'CHIPR0201'    | ''          | ''            | '20180808'
 '47.5'       | '1%'      | '1/20W'  | '0201LF'  | 'EMPTY'  | 'CS04751FE00'(!)        = ''              | ''                 | 'CS04751FE00'           |'R0201'| '(SMR0201AW)'                  | '47.5'    | '1%'    | '1/20W'  | 'IO'       | 'RES CHIP 47.5 1/20W +-1%(0201)'                   | 'CHIPR0201'    | ''          | ''            | '20180808'
 '21K'        | '1%'      | '1/20W'  | '0201LF'  | 'CHIP'   | 'CS32101FE00'(!)        = ''              | ''                 | 'CS32101FE00'           |'R0201'| '(SMR0201AW)'                  | '21K'     | '1%'    | '1/20W'  | 'DISCRETE' | 'RES CHIP 21K(1/20W,+-1%,0201)'                    | 'CHIPR0201'    | ''          | ''            | '20180808'
 '21K'        | '1%'      | '1/20W'  | '0201LF'  | 'EMPTY'  | 'CS32101FE00'(!)        = ''              | ''                 | 'CS32101FE00'           |'R0201'| '(SMR0201AW)'                  | '21K'     | '1%'    | '1/20W'  | 'IO'       | 'RES CHIP 21K(1/20W,+-1%,0201)'                    | 'CHIPR0201'    | ''          | ''            | '20180808'
 '22K'        | '1%'      | '1/20W'  | '0201LF'  | 'CHIP'   | 'CS32201FE00'(!)        = 'End of Design' | 'Comp-Approve'     | 'CS32201FE00'           |'R0201'| '(SMR0201AW)'                  | '22K'     | '1%'    | '1/20W'  | 'DISCRETE' | 'RES CHIP 22K 1/20W +-1%(0201)'                    | 'CHIPR0201'    | ''          | ''            | '20180808'
 '22K'        | '1%'      | '1/20W'  | '0201LF'  | 'EMPTY'  | 'CS32201FE00'(!)        = 'End of Design' | 'Comp-Approve'     | 'CS32201FE00'           |'R0201'| '(SMR0201AW)'                  | '22K'     | '1%'    | '1/20W'  | 'IO'       | 'RES CHIP 22K 1/20W +-1%(0201)'                    | 'CHIPR0201'    | ''          | ''            | '20180808'
 '26.1K'      | '1%'      | '1/20W'  | '0201LF'  | 'CHIP'   | 'CS32611FE01'(!)        = ''              | ''                 | 'CS32611FE01'           |'R0201'| '(SMR0201AW)'                  | '26.1K'   | '1%'    | '1/20W'  | 'DISCRETE' | 'RES CHIP 26.1K 1/20W +-1%(0201)'                  | 'CHIPR0201'    | ''          | ''            | '20180808'
 '26.1K'      | '1%'      | '1/20W'  | '0201LF'  | 'EMPTY'  | 'CS32611FE01'(!)        = ''              | ''                 | 'CS32611FE01'           |'R0201'| '(SMR0201AW)'                  | '26.1K'   | '1%'    | '1/20W'  | 'IO'       | 'RES CHIP 26.1K 1/20W +-1%(0201)'                  | 'CHIPR0201'    | ''          | ''            | '20180808'
 '26.7K'      | '1%'      | '1/20W'  | '0201LF'  | 'CHIP'   | 'CS32671FE00'(!)        = ''              | ''                 | 'CS32671FE00'           |'R0201'| '(SMR0201AW)'                  | '26.7K'   | '1%'    | '1/20W'  | 'DISCRETE' | 'RES CHIP 26.7K 1/20W +-1%(0201)'                  | 'CHIPR0201'    | ''          | ''            | '20180809'
 '26.7K'      | '1%'      | '1/20W'  | '0201LF'  | 'EMPTY'  | 'CS32671FE00'(!)        = ''              | ''                 | 'CS32671FE00'           |'R0201'| '(SMR0201AW)'                  | '26.7K'   | '1%'    | '1/20W'  | 'IO'       | 'RES CHIP 26.7K 1/20W +-1%(0201)'                  | 'CHIPR0201'    | ''          | ''            | '20180809'
 '1K'         | '5%'      | '1/20W'  | '0201LF'  | 'CHIP'   | 'CS21001JE14'(!)        = ''              | ''                 | 'CS21001JE14'           |'R0201'| '(SMR0201AW)'                  | '1K'      | '5%'    | '1/20W'  | 'DISCRETE' | 'RES CHIP 1K(1/20W,+-5%,0201)'                     | 'CHIPR0201'    | ''          | ''            | '20180808'
 '1K'         | '5%'      | '1/20W'  | '0201LF'  | 'EMPTY'  | 'CS21001JE14'(!)        = ''              | ''                 | 'CS21001JE14'           |'R0201'| '(SMR0201AW)'                  | '1K'      | '5%'    | '1/20W'  | 'IO'       | 'RES CHIP 1K(1/20W,+-5%,0201)'                     | 'CHIPR0201'    | ''          | ''            | '20180808'
 '8.2K'       | '5%'      | '1/20W'  | '0201LF'  | 'CHIP'   | 'CS28201JE00'(!)        = ''              | ''                 | 'CS28201JE00'           |'R0201'| '(SMR0201AW)'                  | '8.2K'    | '5%'    | '1/20W'  | 'DISCRETE' | 'RES CHIP 8.2K 1/20W +-5%(0201)'                   | 'CHIPR0201'    | ''          | ''            | '20180808'
 '8.2K'       | '5%'      | '1/20W'  | '0201LF'  | 'EMPTY'  | 'CS28201JE00'(!)        = ''              | ''                 | 'CS28201JE00'           |'R0201'| '(SMR0201AW)'                  | '8.2K'    | '5%'    | '1/20W'  | 'IO'       | 'RES CHIP 8.2K 1/20W +-5%(0201)'                   | 'CHIPR0201'    | ''          | ''            | '20180808'
 '47'         | '1%'      | '1/20W'  | '0201LF'  | 'CHIP'   | 'CS04701FE01'(!)        = ''              | ''                 | 'CS04701FE01'           |'R0201'| '(SMR0201AW)'                  | '47'      | '1%'    | '1/20W'  | 'DISCRETE' | 'RES CHIP 47 1/20W +-1%(0201)'                     | 'CHIPR0201'    | ''          | ''            | '20180809'
 '47'         | '1%'      | '1/20W'  | '0201LF'  | 'EMPTY'  | 'CS04701FE01'(!)        = ''              | ''                 | 'CS04701FE01'           |'R0201'| '(SMR0201AW)'                  | '47'      | '1%'    | '1/20W'  | 'IO'       | 'RES CHIP 47 1/20W +-1%(0201)'                     | 'CHIPR0201'    | ''          | ''            | '20180809'
 '1'          | '1%'      | '1/20W'  | '0201LF'  | 'CHIP'   | 'CS-1001FE00'(!)        = ''              | ''                 | 'CS-1001FE00'           |'R0201'| '(SMR0201AW)'                  | '1'       | '1%'    | '1/20W'  | 'DISCRETE' | 'RES CHIP 1 1/20W +-1%(0201)'                      | 'CHIPR0201'    | ''          | ''            | '20180809'
 '1'          | '1%'      | '1/20W'  | '0201LF'  | 'EMPTY'  | 'CS-1001FE00'(!)        = ''              | ''                 | 'CS-1001FE00'           |'R0201'| '(SMR0201AW)'                  | '1'       | '1%'    | '1/20W'  | 'IO'       | 'RES CHIP 1 1/20W +-1%(0201)'                      | 'CHIPR0201'    | ''          | ''            | '20180809'
 '5.9K'       | '0.1%'    | '1/20W'  | '0201LF'  | 'CHIP'   | 'CS25901BE00'(!)        = ''              | ''                 | 'CS25901BE00'           |'R0201'| '(SMR0201AW)'                  | '5.9K'    | '0.1%'  | '1/20W'  | 'DISCRETE' | 'RES CHIP 5.9K 1/20W +-0.1%(0201) '                | 'CHIPR0201'    | ''          | ''            | '20180809'
 '5.9K'       | '0.1%'    | '1/20W'  | '0201LF'  | 'EMPTY'  | 'CS25901BE00'(!)        = ''              | ''                 | 'CS25901BE00'           |'R0201'| '(SMR0201AW)'                  | '5.9K'    | '0.1%'  | '1/20W'  | 'IO'       | 'RES CHIP 5.9K 1/20W +-0.1%(0201) '                | 'CHIPR0201'    | ''          | ''            | '20180809'
 '10K'        | '0.1%'    | '1/20W'  | '0201LF'  | 'CHIP'   | 'CS31001BE02'(!)        = ''              | ''                 | 'CS31001BE02'           |'R0201'| '(SMR0201AW)'                  | '10K'     | '0.1%'  | '1/20W'  | 'DISCRETE' | 'RES CHIP 10K 1/20W +-0.1%(0201) '                 | 'CHIPR0201'    | ''          | ''            | '20180809'
 '10K'        | '0.1%'    | '1/20W'  | '0201LF'  | 'EMPTY'  | 'CS31001BE02'(!)        = ''              | ''                 | 'CS31001BE02'           |'R0201'| '(SMR0201AW)'                  | '10K'     | '0.1%'  | '1/20W'  | 'IO'       | 'RES CHIP 10K 1/20W +-0.1%(0201) '                 | 'CHIPR0201'    | ''          | ''            | '20180809'
 '249'        | '1%'      | '1/20W'  | '0201LF'  | 'CHIP'   | 'CS12491FE00'(!)        = ''              | ''                 | 'CS12491FE00'           |'R0201'| '(SMR0201AW)'                  | '249'     | '1%'    | '1/20W'  | 'DISCRETE' | 'RES CHIP 249 1/20W +-1%(0201)'                    | 'CHIPR0201'    | ''          | ''            | '20180809'
 '249'        | '1%'      | '1/20W'  | '0201LF'  | 'EMPTY'  | 'CS12491FE00'(!)        = ''              | ''                 | 'CS12491FE00'           |'R0201'| '(SMR0201AW)'                  | '249'     | '1%'    | '1/20W'  | 'IO'       | 'RES CHIP 249 1/20W +-1%(0201)'                    | 'CHIPR0201'    | ''          | ''            | '20180809'
 '562'        | '1%'      | '1/20W'  | '0201LF'  | 'CHIP'   | 'CS15621FE00'(!)        = ''              | ''                 | 'CS15621FE00'           |'R0201'| '(SMR0201AW)'                  | '562'     | '1%'    | '1/20W'  | 'DISCRETE' | 'RES CHIP 562 1/20W +-1% (0201)  '                 | 'CHIPR0201'    | ''          | ''            | '20180809'
 '562'        | '1%'      | '1/20W'  | '0201LF'  | 'EMPTY'  | 'CS15621FE00'(!)        = ''              | ''                 | 'CS15621FE00'           |'R0201'| '(SMR0201AW)'                  | '562'     | '1%'    | '1/20W'  | 'IO'       | 'RES CHIP 562 1/20W +-1% (0201)  '                 | 'CHIPR0201'    | ''          | ''            | '20180809'
 '1K'         | '0.1%'    | '1/20W'  | '0201LF'  | 'CHIP'   | 'CS21001BE01'(!)        = ''              | ''                 | 'CS21001BE01'           |'R0201'| '(SMR0201AW)'                  | '1K'      | '0.1%'  | '1/20W'  | 'DISCRETE' | 'RES CHIP 1K 1/20W +-0.1%(0201) '                  | 'CHIPR0201'    | ''          | ''            | '20180809'
 '1K'         | '0.1%'    | '1/20W'  | '0201LF'  | 'EMPTY'  | 'CS21001BE01'(!)        = ''              | ''                 | 'CS21001BE01'           |'R0201'| '(SMR0201AW)'                  | '1K'      | '0.1%'  | '1/20W'  | 'IO'       | 'RES CHIP 1K 1/20W +-0.1%(0201) '                  | 'CHIPR0201'    | ''          | ''            | '20180809'
 '1.02K'      | '1%'      | '1/20W'  | '0201LF'  | 'CHIP'   | 'CS21021FE00'(!)        = ''              | ''                 | 'CS21021FE00'           |'R0201'| '(SMR0201AW)'                  | '1.02K'   | '1%'    | '1/20W'  | 'DISCRETE' | 'RES CHIP 1.02K 1/20W +-1%(0201)'                  | 'CHIPR0201'    | ''          | ''            | '20180809'
 '1.02K'      | '1%'      | '1/20W'  | '0201LF'  | 'EMPTY'  | 'CS21021FE00'(!)        = ''              | ''                 | 'CS21021FE00'           |'R0201'| '(SMR0201AW)'                  | '1.02K'   | '1%'    | '1/20W'  | 'IO'       | 'RES CHIP 1.02K 1/20W +-1%(0201)'                  | 'CHIPR0201'    | ''          | ''            | '20180809'
 '1.82K'      | '1%'      | '1/20W'  | '0201LF'  | 'CHIP'   | 'CS21821FE00'(!)        = ''              | ''                 | 'CS21821FE00'           |'R0201'| '(SMR0201AW)'                  | '1.82K'   | '1%'    | '1/20W'  | 'DISCRETE' | 'RES CHIP 1.82K 1/20W +-1%(0201)'                  | 'CHIPR0201'    | ''          | ''            | '20180809'
 '1.82K'      | '1%'      | '1/20W'  | '0201LF'  | 'EMPTY'  | 'CS21821FE00'(!)        = ''              | ''                 | 'CS21821FE00'           |'R0201'| '(SMR0201AW)'                  | '1.82K'   | '1%'    | '1/20W'  | 'IO'       | 'RES CHIP 1.82K 1/20W +-1%(0201)'                  | 'CHIPR0201'    | ''          | ''            | '20180809'
 '27'         | '1%'      | '1/20W'  | '0201LF'  | 'CHIP'   | 'CS02701FE00'(!)        = 'End of Design' | 'Comp-Approve'     | 'CS02701FE00'           |'R0201'| '(SMR0201AW)'                  | '27'      | '1%'    | '1/20W'  | 'DISCRETE' | 'RES CHIP 27 1/20W +-1% (0201)'                    | 'CHIPR0201'    | ''          | ''            | '20180809'
 '27'         | '1%'      | '1/20W'  | '0201LF'  | 'EMPTY'  | 'CS02701FE00'(!)        = 'End of Design' | 'Comp-Approve'     | 'CS02701FE00'           |'R0201'| '(SMR0201AW)'                  | '27'      | '1%'    | '1/20W'  | 'IO'       | 'RES CHIP 27 1/20W +-1% (0201)'                    | 'CHIPR0201'    | ''          | ''            | '20180809'
 '1.43K'      | '1%'      | '1/20W'  | '0201LF'  | 'CHIP'   | 'CS21431FE01'(!)        = ''              | ''                 | 'CS21431FE01'           |'R0201'| '(SMR0201AW)'                  | '1.43K'   | '1%'    | '1/20W'  | 'DISCRETE' | 'RES CHIP 1.43K 1/20W +-1%(0201)'                  | 'CHIPR0201'    | ''          | ''            | '20180809'
 '1.43K'      | '1%'      | '1/20W'  | '0201LF'  | 'EMPTY'  | 'CS21431FE01'(!)        = ''              | ''                 | 'CS21431FE01'           |'R0201'| '(SMR0201AW)'                  | '1.43K'   | '1%'    | '1/20W'  | 'IO'       | 'RES CHIP 1.43K 1/20W +-1%(0201)'                  | 'CHIPR0201'    | ''          | ''            | '20180809'
 '2.21K'      | '1%'      | '1/20W'  | '0201LF'  | 'CHIP'   | 'CS22211FE00'(!)        = ''              | ''                 | 'CS22211FE00'           |'R0201'| '(SMR0201AW)'                  | '2.21K'   | '1%'    | '1/20W'  | 'DISCRETE' | 'RES CHIP 2.21K 1/20W +-1%(0201)HF'                | 'CHIPR0201'    | ''          | ''            | '20180809'
 '2.21K'      | '1%'      | '1/20W'  | '0201LF'  | 'EMPTY'  | 'CS22211FE00'(!)        = ''              | ''                 | 'CS22211FE00'           |'R0201'| '(SMR0201AW)'                  | '2.21K'   | '1%'    | '1/20W'  | 'IO'       | 'RES CHIP 2.21K 1/20W +-1%(0201)HF'                | 'CHIPR0201'    | ''          | ''            | '20180809'
 '54.9K'      | '1%'      | '1/20W'  | '0201LF'  | 'CHIP'   | 'CS35491FE01'(!)        = ''              | ''                 | 'CS35491FE01'           |'R0201'| '(SMR0201AW)'                  | '54.9K'   | '1%'    | '1/20W'  | 'DISCRETE' | 'RES CHIP 54.9K 1/20W +-1% (0201)'                 | 'CHIPR0201'    | ''          | ''            | '20180809'
 '54.9K'      | '1%'      | '1/20W'  | '0201LF'  | 'EMPTY'  | 'CS35491FE01'(!)        = ''              | ''                 | 'CS35491FE01'           |'R0201'| '(SMR0201AW)'                  | '54.9K'   | '1%'    | '1/20W'  | 'IO'       | 'RES CHIP 54.9K 1/20W +-1% (0201)'                 | 'CHIPR0201'    | ''          | ''            | '20180809'
 '36K'        | '1%'      | '1/20W'  | '0201LF'  | 'CHIP'   | 'CS33601FE02'(!)        = 'End of Design' | 'Comp-Approve'     | 'CS33601FE02'           |'R0201'| '(SMR0201AW)'                  | '36K'     | '1%'    | '1/20W'  | 'DISCRETE' | 'RES CHIP 36K 1/20W +-1%(0201)'                    | 'CHIPR0201'    | ''          | ''            | '20180809'
 '36K'        | '1%'      | '1/20W'  | '0201LF'  | 'EMPTY'  | 'CS33601FE02'(!)        = 'End of Design' | 'Comp-Approve'     | 'CS33601FE02'           |'R0201'| '(SMR0201AW)'                  | '36K'     | '1%'    | '1/20W'  | 'IO'       | 'RES CHIP 36K 1/20W +-1%(0201)'                    | 'CHIPR0201'    | ''          | ''            | '20180809'
 '165K'       | '1%'      | '1/20W'  | '0201LF'  | 'CHIP'   | 'CS41651FE01'(!)        = ''              | ''                 | 'CS41651FE01'           |'R0201'| '(SMR0201AW)'                  | '165K'    | '1%'    | '1/20W'  | 'DISCRETE' | 'RES CHIP 165K 1/20W +-1%(0201)'                   | 'CHIPR0201'    | ''          | ''            | '20180809'
 '165K'       | '1%'      | '1/20W'  | '0201LF'  | 'EMPTY'  | 'CS41651FE01'(!)        = ''              | ''                 | 'CS41651FE01'           |'R0201'| '(SMR0201AW)'                  | '165K'    | '1%'    | '1/20W'  | 'IO'       | 'RES CHIP 165K 1/20W +-1%(0201)'                   | 'CHIPR0201'    | ''          | ''            | '20180809'
 '100'        | '0.1%'    | '1/20W'  | '0201LF'  | 'CHIP'   | 'CS11001BE00'(!)        = ''              | ''                 | 'CS11001BE00'           |'R0201'| '(SMR0201AW)'                  | '100'     | '0.1%'  | '1/20W'  | 'DISCRETE' | 'RES CHIP 100 1/20W +-0.1%(0201) '                 | 'CHIPR0201'    | ''          | ''            | '20180809'
 '100'        | '0.1%'    | '1/20W'  | '0201LF'  | 'EMPTY'  | 'CS11001BE00'(!)        = ''              | ''                 | 'CS11001BE00'           |'R0201'| '(SMR0201AW)'                  | '100'     | '0.1%'  | '1/20W'  | 'IO'       | 'RES CHIP 100 1/20W +-0.1%(0201) '                 | 'CHIPR0201'    | ''          | ''            | '20180809'
 '2K'         | '0.1%'    | '1/20W'  | '0201LF'  | 'CHIP'   | 'CS22001BE00'(!)        = ''              | ''                 | 'CS22001BE00'           |'R0201'| '(SMR0201AW)'                  | '2K'      | '0.1%'  | '1/20W'  | 'DISCRETE' | 'RES CHIP 2K 1/20W +-0.1%(0201) '                  | 'CHIPR0201'    | ''          | ''            | '20180809'
 '2K'         | '0.1%'    | '1/20W'  | '0201LF'  | 'EMPTY'  | 'CS22001BE00'(!)        = ''              | ''                 | 'CS22001BE00'           |'R0201'| '(SMR0201AW)'                  | '2K'      | '0.1%'  | '1/20W'  | 'IO'       | 'RES CHIP 2K 1/20W +-0.1%(0201) '                  | 'CHIPR0201'    | ''          | ''            | '20180809'
 '249'        | '0.1%'    | '1/20W'  | '0201LF'  | 'CHIP'   | 'CS12491BE00'(!)        = ''              | ''                 | 'CS12491BE00'           |'R0201'| '(SMR0201AW)'                  | '249'     | '0.1%'  | '1/20W'  | 'DISCRETE' | 'RES CHIP 249 1/20W +-0.1%(0201) '                 | 'CHIPR0201'    | ''          | ''            | '20180809'
 '249'        | '0.1%'    | '1/20W'  | '0201LF'  | 'EMPTY'  | 'CS12491BE00'(!)        = ''              | ''                 | 'CS12491BE00'           |'R0201'| '(SMR0201AW)'                  | '249'     | '0.1%'  | '1/20W'  | 'IO'       | 'RES CHIP 249 1/20W +-0.1%(0201) '                 | 'CHIPR0201'    | ''          | ''            | '20180809'
 '22'         | '5%'      | '1/20W'  | '0201LF'  | 'CHIP'   | 'CS02201JE00'(!)        = ''              | ''                 | 'CS02201JE00'           |'R0201'| '(SMR0201AW)'                  | '22'      | '5%'    | '1/20W'  | 'DISCRETE' | 'RES CHIP 22 1/20W +-5%(0201)'                     | 'CHIPR0201'    | ''          | ''            | '20180809'
 '22'         | '5%'      | '1/20W'  | '0201LF'  | 'EMPTY'  | 'CS02201JE00'(!)        = ''              | ''                 | 'CS02201JE00'           |'R0201'| '(SMR0201AW)'                  | '22'      | '5%'    | '1/20W'  | 'IO'       | 'RES CHIP 22 1/20W +-5%(0201)'                     | 'CHIPR0201'    | ''          | ''            | '20180809'
 '49.9'       | '0.1%'    | '1/20W'  | '0201LF'  | 'CHIP'   | 'CS04991BE00'(!)        = ''              | ''                 | 'CS04991BE00'           |'R0201'| '(SMR0201AW)'                  | '49.9'    | '0.1%'  | '1/20W'  | 'DISCRETE' | 'RES CHIP 49.9 1/20W +-0.1%(0201) '                | 'CHIPR0201'    | ''          | ''            | '20180809'
 '49.9'       | '0.1%'    | '1/20W'  | '0201LF'  | 'EMPTY'  | 'CS04991BE00'(!)        = ''              | ''                 | 'CS04991BE00'           |'R0201'| '(SMR0201AW)'                  | '49.9'    | '0.1%'  | '1/20W'  | 'IO'       | 'RES CHIP 49.9 1/20W +-0.1%(0201) '                | 'CHIPR0201'    | ''          | ''            | '20180809'
 '86.6K'      | '1%'      | '1/20W'  | '0201LF'  | 'CHIP'   | 'CS38661FE00'(!)        = ''              | ''                 | 'CS38661FE00'           |'R0201'| '(SMR0201AW)'                  | '86.6K'   | '1%'    | '1/20W'  | 'DISCRETE' | 'RES CHIP 86.6K 1/20W +-1%(0201)'                  | 'CHIPR0201'    | ''          | ''            | '20180810'
 '86.6K'      | '1%'      | '1/20W'  | '0201LF'  | 'EMPTY'  | 'CS38661FE00'(!)        = ''              | ''                 | 'CS38661FE00'           |'R0201'| '(SMR0201AW)'                  | '86.6K'   | '1%'    | '1/20W'  | 'IO'       | 'RES CHIP 86.6K 1/20W +-1%(0201)'                  | 'CHIPR0201'    | ''          | ''            | '20180810'
 '470'        | '5%'      | '1/20W'  | '0201LF'  | 'CHIP'   | 'CS14701JE00'(!)        = ''              | ''                 | 'CS14701JE00'           |'R0201'| '(SMR0201AW)'                  | '470'     | '5%'    | '1/20W'  | 'DISCRETE' | 'RES CHIP 470 1/20W +-5%(0201)'                    | 'CHIPR0201'    | ''          | ''            | '20180810'
 '470'        | '5%'      | '1/20W'  | '0201LF'  | 'EMPTY'  | 'CS14701JE00'(!)        = ''              | ''                 | 'CS14701JE00'           |'R0201'| '(SMR0201AW)'                  | '470'     | '5%'    | '1/20W'  | 'IO'       | 'RES CHIP 470 1/20W +-5%(0201)'                    | 'CHIPR0201'    | ''          | ''            | '20180810'
 '165'        | '1%'      | '1/20W'  | '0201LF'  | 'CHIP'   | 'CS11651FE00'(!)        = ''              | ''                 | 'CS11651FE00'           |'R0201'| '(SMR0201AW)'                  | '165'     | '1%'    | '1/20W'  | 'DISCRETE' | 'RES CHIP 165 1/20W +-1%(0201)'                    | 'CHIPR0201'    | ''          | ''            | '20180823'
 '165'        | '1%'      | '1/20W'  | '0201LF'  | 'EMPTY'  | 'CS11651FE00'(!)        = ''              | ''                 | 'CS11651FE00'           |'R0201'| '(SMR0201AW)'                  | '165'     | '1%'    | '1/20W'  | 'IO'       | 'RES CHIP 165 1/20W +-1%(0201)'                    | 'CHIPR0201'    | ''          | ''            | '20180823'
 '3K'         | '1%'      | '1/20W'  | '0201LF'  | 'CHIP'   | 'CS23001FE02'(!)        = ''              | ''                 | 'CS23001FE02'           |'R0201'| '(SMR0201AW)'                  | '3K'      | '1%'    | '1/20W'  | 'DISCRETE' | 'RES CHIP 3K 1/20W+-1%(0201)'                      | 'CHIPR0201'    | ''          | ''            | '20180823'
 '3K'         | '1%'      | '1/20W'  | '0201LF'  | 'EMPTY'  | 'CS23001FE02'(!)        = ''              | ''                 | 'CS23001FE02'           |'R0201'| '(SMR0201AW)'                  | '3K'      | '1%'    | '1/20W'  | 'IO'       | 'RES CHIP 3K 1/20W+-1%(0201)'                      | 'CHIPR0201'    | ''          | ''            | '20180823'
 '665'        | '1%'      | '1/20W'  | '0201LF'  | 'CHIP'   | 'CS16651FE00'(!)        = ''              | ''                 | 'CS16651FE00'           |'R0201'| '(SMR0201AW)'                  | '665'     | '1%'    | '1/20W'  | 'DISCRETE' | 'RES CHIP 665 1/20W +-1%(0201) '                   | 'CHIPR0201'    | ''          | ''            | '20180823'
 '665'        | '1%'      | '1/20W'  | '0201LF'  | 'EMPTY'  | 'CS16651FE00'(!)        = ''              | ''                 | 'CS16651FE00'           |'R0201'| '(SMR0201AW)'                  | '665'     | '1%'    | '1/20W'  | 'IO'       | 'RES CHIP 665 1/20W +-1%(0201) '                   | 'CHIPR0201'    | ''          | ''            | '20180823'
 '549K'       | '1%'      | '1/16W'  | '0402LF'  | 'CHIP'   | 'CS45492FB16'(!)        = 'End of Design' | 'Comp-Approve'     | 'CS45492FB16'           |'R0402'| '(R0402-0201)'                 | '549K'    | '1%'    | '1/16W'  | 'DISCRETE' | 'RES CHIP 549K 1/16W +-1%( 0402)'                  | 'CHIPR0402'    | ''          | ''            | '20180830'
 '549K'       | '1%'      | '1/16W'  | '0402LF'  | 'EMPTY'  | 'CS45492FB16'(!)        = 'End of Design' | 'Comp-Approve'     | 'CS45492FB16'           |'R0402'| '(R0402-0201)'                 | '549K'    | '1%'    | '1/16W'  | 'IO'       | 'RES CHIP 549K 1/16W +-1%( 0402)'                  | 'CHIPR0402'    | ''          | ''            | '20180830'
 '1.74K'      | '1%'      | '1/20W'  | '0201LF'  | 'CHIP'   | 'CS21741FE00'(!)        = ''              | ''                 | 'CS21741FE00'           |'R0201'| '(SMR0201AW)'                  | '1.74K'   | '1%'    | '1/20W'  | 'DISCRETE' | 'RES CHIP 1.74K 1/20W +-1%(0201) '                 | 'CHIPR0201'    | ''          | ''            | '20180830'
 '1.74K'      | '1%'      | '1/20W'  | '0201LF'  | 'EMPTY'  | 'CS21741FE00'(!)        = ''              | ''                 | 'CS21741FE00'           |'R0201'| '(SMR0201AW)'                  | '1.74K'   | '1%'    | '1/20W'  | 'IO'       | 'RES CHIP 1.74K 1/20W +-1%(0201) '                 | 'CHIPR0201'    | ''          | ''            | '20180830'
 '15.4K'      | '1%'      | '1/20W'  | '0201LF'  | 'CHIP'   | 'CS31541FE00'(!)        = ''              | ''                 | 'CS31541FE00'           |'R0201'| '(SMR0201AW)'                  | '15.4K'   | '1%'    | '1/20W'  | 'DISCRETE' | 'RES CHIP 15.4K 1/20W +-1%(0201)'                  | 'CHIPR0201'    | ''          | ''            | '20180830'
 '15.4K'      | '1%'      | '1/20W'  | '0201LF'  | 'EMPTY'  | 'CS31541FE00'(!)        = ''              | ''                 | 'CS31541FE00'           |'R0201'| '(SMR0201AW)'                  | '15.4K'   | '1%'    | '1/20W'  | 'IO'       | 'RES CHIP 15.4K 1/20W +-1%(0201)'                  | 'CHIPR0201'    | ''          | ''            | '20180830'
 '19.1K'      | '1%'      | '1/20W'  | '0201LF'  | 'CHIP'   | 'CS31911FE01'(!)        = ''              | ''                 | 'CS31911FE01'           |'R0201'| '(SMR0201AW)'                  | '19.1K'   | '1%'    | '1/20W'  | 'DISCRETE' | 'RES CHIP 19.1K 1/20W +-1%(0201)'                  | 'CHIPR0201'    | ''          | ''            | '20180830'
 '19.1K'      | '1%'      | '1/20W'  | '0201LF'  | 'EMPTY'  | 'CS31911FE01'(!)        = ''              | ''                 | 'CS31911FE01'           |'R0201'| '(SMR0201AW)'                  | '19.1K'   | '1%'    | '1/20W'  | 'IO'       | 'RES CHIP 19.1K 1/20W +-1%(0201)'                  | 'CHIPR0201'    | ''          | ''            | '20180830'
 '3.74K'      | '1%'      | '1/20W'  | '0201LF'  | 'CHIP'   | 'CS23741FE01'(!)        = ''              | ''                 | 'CS23741FE01'           |'R0201'| '(SMR0201AW)'                  | '3.74K'   | '1%'    | '1/20W'  | 'DISCRETE' | 'RES CHIP 3.74K 1/20W +-1%(0201)'                  | 'CHIPR0201'    | ''          | ''            | '20180830'
 '3.74K'      | '1%'      | '1/20W'  | '0201LF'  | 'EMPTY'  | 'CS23741FE01'(!)        = ''              | ''                 | 'CS23741FE01'           |'R0201'| '(SMR0201AW)'                  | '3.74K'   | '1%'    | '1/20W'  | 'IO'       | 'RES CHIP 3.74K 1/20W +-1%(0201)'                  | 'CHIPR0201'    | ''          | ''            | '20180830'
 '42.2K'      | '1%'      | '1/20W'  | '0201LF'  | 'CHIP'   | 'CS34221FE01'(!)        = ''              | ''                 | 'CS34221FE01'           |'R0201'| '(SMR0201AW)'                  | '42.2K'   | '1%'    | '1/20W'  | 'DISCRETE' | 'RES CHIP 42.2K 1/20W +-1%(0201)'                  | 'CHIPR0201'    | ''          | ''            | '20180830'
 '42.2K'      | '1%'      | '1/20W'  | '0201LF'  | 'EMPTY'  | 'CS34221FE01'(!)        = ''              | ''                 | 'CS34221FE01'           |'R0201'| '(SMR0201AW)'                  | '42.2K'   | '1%'    | '1/20W'  | 'IO'       | 'RES CHIP 42.2K 1/20W +-1%(0201)'                  | 'CHIPR0201'    | ''          | ''            | '20180830'
 '75K'        | '1%'      | '1/20W'  | '0201LF'  | 'CHIP'   | 'CS37501FE00'(!)        = ''              | ''                 | 'CS37501FE00'           |'R0201'| '(SMR0201AW)'                  | '75K'     | '1%'    | '1/20W'  | 'DISCRETE' | 'RES CHIP 75K 1/20W +-1%(0201)'                    | 'CHIPR0201'    | ''          | ''            | '20180830'
 '75K'        | '1%'      | '1/20W'  | '0201LF'  | 'EMPTY'  | 'CS37501FE00'(!)        = ''              | ''                 | 'CS37501FE00'           |'R0201'| '(SMR0201AW)'                  | '75K'     | '1%'    | '1/20W'  | 'IO'       | 'RES CHIP 75K 1/20W +-1%(0201)'                    | 'CHIPR0201'    | ''          | ''            | '20180830'
 '84.5K'      | '1%'      | '1/20W'  | '0201LF'  | 'CHIP'   | 'CS38451FE00'(!)        = ''              | ''                 | 'CS38451FE00'           |'R0201'| '(SMR0201AW)'                  | '84.5K'   | '1%'    | '1/20W'  | 'DISCRETE' | 'RES CHIP 84.5K 1/20W,+-1%(0201)'                  | 'CHIPR0201'    | ''          | ''            | '20180830'
 '84.5K'      | '1%'      | '1/20W'  | '0201LF'  | 'EMPTY'  | 'CS38451FE00'(!)        = ''              | ''                 | 'CS38451FE00'           |'R0201'| '(SMR0201AW)'                  | '84.5K'   | '1%'    | '1/20W'  | 'IO'       | 'RES CHIP 84.5K 1/20W,+-1%(0201)'                  | 'CHIPR0201'    | ''          | ''            | '20180830'
 '9.76K'      | '1%'      | '1/20W'  | '0201LF'  | 'CHIP'   | 'CS29761FE00'(!)        = ''              | ''                 | 'CS29761FE00'           |'R0201'| '(SMR0201AW)'                  | '9.76K'   | '1%'    | '1/20W'  | 'DISCRETE' | 'RES CHIP 9.76K 1/20W +-1%(0201)'                  | 'CHIPR0201'    | ''          | ''            | '20180831'
 '9.76K'      | '1%'      | '1/20W'  | '0201LF'  | 'EMPTY'  | 'CS29761FE00'(!)        = ''              | ''                 | 'CS29761FE00'           |'R0201'| '(SMR0201AW)'                  | '9.76K'   | '1%'    | '1/20W'  | 'IO'       | 'RES CHIP 9.76K 1/20W +-1%(0201)'                  | 'CHIPR0201'    | ''          | ''            | '20180831'
 '45.3K'      | '1%'      | '1/20W'  | '0201LF'  | 'CHIP'   | 'CS34531FE01'(!)        = ''              | ''                 | 'CS34531FE01'           |'R0201'| '(SMR0201AW)'                  | '45.3K'   | '1%'    | '1/20W'  | 'DISCRETE' | 'RES CHIP 45.3K 1/20W +-1%(0201)'                  | 'CHIPR0201'    | ''          | ''            | '20180831'
 '45.3K'      | '1%'      | '1/20W'  | '0201LF'  | 'EMPTY'  | 'CS34531FE01'(!)        = ''              | ''                 | 'CS34531FE01'           |'R0201'| '(SMR0201AW)'                  | '45.3K'   | '1%'    | '1/20W'  | 'IO'       | 'RES CHIP 45.3K 1/20W +-1%(0201)'                  | 'CHIPR0201'    | ''          | ''            | '20180831'
 '147K'       | '1%'      | '1/20W'  | '0201LF'  | 'CHIP'   | 'CS41471FE00'(!)        = ''              | ''                 | 'CS41471FE00'           |'R0201'| '(SMR0201AW)'                  | '147K'    | '1%'    | '1/20W'  | 'DISCRETE' | 'RES CHIP 147K 1/20W +-1%(0201)'                   | 'CHIPR0201'    | ''          | ''            | '20180903'
 '147K'       | '1%'      | '1/20W'  | '0201LF'  | 'EMPTY'  | 'CS41471FE00'(!)        = ''              | ''                 | 'CS41471FE00'           |'R0201'| '(SMR0201AW)'                  | '147K'    | '1%'    | '1/20W'  | 'IO'       | 'RES CHIP 147K 1/20W +-1%(0201)'                   | 'CHIPR0201'    | ''          | ''            | '20180903'
 '28K'        | '1%'      | '1/20W'  | '0201LF'  | 'CHIP'   | 'CS32801FE00'(!)        = ''              | ''                 | 'CS32801FE00'           |'R0201'| '(SMR0201AW)'                  | '28K'     | '1%'    | '1/20W'  | 'DISCRETE' | 'RES CHIP 28K 1/20W +-1%(0201)'                    | 'CHIPR0201'    | ''          | ''            | '20180903'
 '28K'        | '1%'      | '1/20W'  | '0201LF'  | 'EMPTY'  | 'CS32801FE00'(!)        = ''              | ''                 | 'CS32801FE00'           |'R0201'| '(SMR0201AW)'                  | '28K'     | '1%'    | '1/20W'  | 'IO'       | 'RES CHIP 28K 1/20W +-1%(0201)'                    | 'CHIPR0201'    | ''          | ''            | '20180903'
 '7.68K'      | '1%'      | '1/20W'  | '0201LF'  | 'CHIP'   | 'CS27681FE00'(!)        = ''              | ''                 | 'CS27681FE00'           |'R0201'| '(SMR0201AW)'                  | '7.68K'   | '1%'    | '1/20W'  | 'DISCRETE' | 'RES CHIP 7.68K 1/20W +-1%(0201)'                  | 'CHIPR0201'    | ''          | ''            | '20180903'
 '7.68K'      | '1%'      | '1/20W'  | '0201LF'  | 'EMPTY'  | 'CS27681FE00'(!)        = ''              | ''                 | 'CS27681FE00'           |'R0201'| '(SMR0201AW)'                  | '7.68K'   | '1%'    | '1/20W'  | 'IO'       | 'RES CHIP 7.68K 1/20W +-1%(0201)'                  | 'CHIPR0201'    | ''          | ''            | '20180903'
 '38.3K'      | '1%'      | '1/20W'  | '0201LF'  | 'CHIP'   | 'CS33831FE01'(!)        = ''              | ''                 | 'CS33831FE01'           |'R0201'| '(SMR0201AW)'                  | '38.3K'   | '1%'    | '1/20W'  | 'DISCRETE' | 'RES CHIP 38.3K 1/20W +-1%(0201)'                  | 'CHIPR0201'    | ''          | ''            | '20180903'
 '38.3K'      | '1%'      | '1/20W'  | '0201LF'  | 'EMPTY'  | 'CS33831FE01'(!)        = ''              | ''                 | 'CS33831FE01'           |'R0201'| '(SMR0201AW)'                  | '38.3K'   | '1%'    | '1/20W'  | 'IO'       | 'RES CHIP 38.3K 1/20W +-1%(0201)'                  | 'CHIPR0201'    | ''          | ''            | '20180903'
 '63.4K'      | '1%'      | '1/20W'  | '0201LF'  | 'CHIP'   | 'CS36341FE00'(!)        = ''              | ''                 | 'CS36341FE00'           |'R0201'| '(SMR0201AW)'                  | '63.4K'   | '1%'    | '1/20W'  | 'DISCRETE' | 'RES CHIP 63.4K 1/20W +-1% (0201) '                | 'CHIPR0201'    | ''          | ''            | '20180903'
 '63.4K'      | '1%'      | '1/20W'  | '0201LF'  | 'EMPTY'  | 'CS36341FE00'(!)        = ''              | ''                 | 'CS36341FE00'           |'R0201'| '(SMR0201AW)'                  | '63.4K'   | '1%'    | '1/20W'  | 'IO'       | 'RES CHIP 63.4K 1/20W +-1% (0201) '                | 'CHIPR0201'    | ''          | ''            | '20180903'
 '560'        | '1%'      | '1/16W'  | '0402LF'  | 'CHIP'   | 'CS15602FB17'(!)        = 'End of Design' | 'Comp-Approve'     | 'CS15602FB17'           |'R0402'| '(R0402-0201)'                 | '560'     | '1%'    | '1/16W'  | 'DISCRETE' | 'RES CHIP 560 1/16W +-1%(0402)'                    | 'CHIPR0402'    | ''          | ''            | '20100429'
 '560'        | '1%'      | '1/16W'  | '0402LF'  | 'EMPTY'  | 'CS15602FB17'(!)        = 'End of Design' | 'Comp-Approve'     | 'CS15602FB17'           |'R0402'| '(R0402-0201)'                 | '560'     | '1%'    | '1/16W'  | 'IO'       | 'RES CHIP 560 1/16W +-1%(0402)'                    | 'CHIPR0402'    | ''          | ''            | '20100429'
 '2K'         | '0.1%'    | '1/16W'  | '0402LF'  | 'CHIP'   | 'CS22002BB01'(!)        = ''              | ''                 | 'CS22002BB01'           |'R0402'| '(R0402-0201)'                 | '2K'      | '0.1%'  | '1/16W'  | 'DISCRETE' | 'RES CHIP 2K 1/16W +-0.1% (0402)'                  | 'CHIPR0402'    | ''          | ''            | '20150911'
 '2K'         | '0.1%'    | '1/16W'  | '0402LF'  | 'EMPTY'  | 'CS22002BB01'(!)        = ''              | ''                 | 'CS22002BB01'           |'R0402'| '(R0402-0201)'                 | '2K'      | '0.1%'  | '1/16W'  | 'IO'       | 'RES CHIP 2K 1/16W +-0.1% (0402)'                  | 'CHIPR0402'    | ''          | ''            | '20150911'
 '220'        | '5%'      | '1/20W'  | '0201LF'  | 'CHIP '  | 'CS12201JE04'(!)        = ''              | ''                 | 'CS12201JE04'           |'R0201'| '(SMR0201AW)'                  | '220'     | '5%'    | '1/20W'  | 'DISCRETE' | 'RES CHIP 220(1/20W,+-5%,0201)'                    | 'CHIPR0201'    | ''          | ''            | '20181024'
 '220'        | '5%'      | '1/20W'  | '0201LF'  | 'EMPTY'  | 'CS12201JE04'(!)        = ''              | ''                 | 'CS12201JE04'           |'R0201'| '(SMR0201AW)'                  | '220'     | '5%'    | '1/20W'  | 'IO'       | 'RES CHIP 220(1/20W,+-5%,0201)'                    | 'CHIPR0201'    | ''          | ''            | '20181024'
 '330'        | '1%'      | '1/4W'   | '1206LF'  | 'CHIP'   | 'CS13306F200'(!)        = ''              | ''                 | 'CS13306F200'           |'R1206XJ'| '(SMR1206AW)'                  | '330'     | '1%'    | '1/4W'   | 'DISCRETE' | 'RES CHIP 330 1/4W+-1%(1206)'                      | 'CHIPR1206'    | ''          | ''            | '20100429'
 '330'        | '1%'      | '1/4W'   | '1206LF'  | 'EMPTY'  | 'CS13306F200'(!)        = ''              | ''                 | 'CS13306F200'           |'R1206XJ'| '(SMR1206AW)'                  | '330'     | '1%'    | '1/4W'   | 'IO'       | 'RES CHIP 330 1/4W+-1%(1206)'                      | 'CHIPR1206'    | ''          | ''            | '20100429'
 '249'        | '1%'      | '1/4W'   | '1206LF'  | 'CHIP'   | 'CS12496F200'(!)        = ''              | ''                 | 'CS12496F200'           |'R1206XJ'| '(SMR1206AW)'                  | '249'     | '1%'    | '1/4W'   | 'DISCRETE' | 'RES CHIP 249 1/4W +-1%(1206)'                     | 'CHIPR1206'    | ''          | ''            | '20181031'
 '249'        | '1%'      | '1/4W'   | '1206LF'  | 'EMPTY'  | 'CS12496F200'(!)        = ''              | ''                 | 'CS12496F200'           |'R1206XJ'| '(SMR1206AW)'                  | '249'     | '1%'    | '1/4W'   | 'IO'       | 'RES CHIP 249 1/4W +-1%(1206)'                     | 'CHIPR1206'    | ''          | ''            | '20181031'
 '910K'       | '1%'      | '1/16W'  | '0402LF'  | 'CHIP'   | 'CS49102FB07'(!)        = 'End of Design' | 'Comp-Approve'     | 'CS49102FB07'           |'R0402'| '(R0402-0201)'                 | '910K'    | '1%'    | '1/16W'  | 'DISCRETE' | 'RES CHIP 910K 1/16W +-1%(0402)'                   | 'CHIPR0402'    | ''          | ''            | '20181031'
 '910K'       | '1%'      | '1/16W'  | '0402LF'  | 'EMPTY'  | 'CS49102FB07'(!)        = 'End of Design' | 'Comp-Approve'     | 'CS49102FB07'           |'R0402'| '(R0402-0201)'                 | '910K'    | '1%'    | '1/16W'  | 'IO'       | 'RES CHIP 910K 1/16W +-1%(0402)'                   | 'CHIPR0402'    | ''          | ''            | '20181031'
 '1.78M'      | '1%'      | '1/16W'  | '0402LF'  | 'CHIP'   | 'CS51782FB00'(!)        = ''              | ''                 | 'CS51782FB00'           |'R0402'| '(R0402-0201)'                 | '1.78M'   | '1%'    | '1/16W'  | 'DISCRETE' | 'RES CHIP 1.78M 1/16W +-1%(0402)'                  | 'CHIPR0402'    | ''          | ''            | '20181101'
 '1.78M'      | '1%'      | '1/16W'  | '0402LF'  | 'EMPTY'  | 'CS51782FB00'(!)        = ''              | ''                 | 'CS51782FB00'           |'R0402'| '(R0402-0201)'                 | '1.78M'   | '1%'    | '1/16W'  | 'IO'       | 'RES CHIP 1.78M 1/16W +-1%(0402)'                  | 'CHIPR0402'    | ''          | ''            | '20181101'
 '0.005'      | '1%'      | '1W'     | '1206LF'  | 'CHIP'   | 'CS+0058F200'(!)        = ''              | ''                 | 'CS+0058F200'           |'R1206XK'| '(SMR1206AW)'                  | '0.005'   | '1%'    | '1W'     | 'DISCRETE' | 'RES CHIP  0.005  1W +-1%(1206)'                   | 'CHIPR1206'    | ''          | ''            | '20181113'
 '0.005'      | '1%'      | '1W'     | '1206LF'  | 'EMPTY'  | 'CS+0058F200'(!)        = ''              | ''                 | 'CS+0058F200'           |'R1206XK'| '(SMR1206AW)'                  | '0.005'   | '1%'    | '1W'     | 'IO'       | 'RES CHIP  0.005  1W +-1%(1206)'                   | 'CHIPR1206'    | ''          | ''            | '20181113'
 '316'        | '1%'      | '1/16W'  | '0402LF'  | 'CHIP'   | 'CS13162FB02'(!)        = 'End of Design' | 'Comp-Approve'     | 'CS13162FB02'           |'R0402'| '(R0402-0201)'                 | '316'     | '1%'    | '1/16W'  | 'DISCRETE' | 'RES CHIP 316 1/16W +-1%(0402)'                    | 'CHIPR0402'    | ''          | ''            | '20181113'
 '316'        | '1%'      | '1/16W'  | '0402LF'  | 'EMPTY'  | 'CS13162FB02'(!)        = 'End of Design' | 'Comp-Approve'     | 'CS13162FB02'           |'R0402'| '(R0402-0201)'                 | '316'     | '1%'    | '1/16W'  | 'IO'       | 'RES CHIP 316 1/16W +-1%(0402)'                    | 'CHIPR0402'    | ''          | ''            | '20181113'
 '1.69K'      | '1%'      | '1/4W'   | '1206LF'  | 'CHIP'   | 'CS21696F200'(!)        = ''              | ''                 | 'CS21696F200'           |'R1206XB'| '(SMR1206AW)'                  | '1.69K'   | '1%'    | '1/4W'   | 'DISCRETE' | 'RES CHIP 1.69K 1/4W +-1% (1206)'                  | 'CHIPR1206'    | ''          | ''            | '20150413'
 '1.69K'      | '1%'      | '1/4W'   | '1206LF'  | 'EMPTY'  | 'CS21696F200'(!)        = ''              | ''                 | 'CS21696F200'           |'R1206XB'| '(SMR1206AW)'                  | '1.69K'   | '1%'    | '1/4W'   | 'IO'       | 'RES CHIP 1.69K 1/4W +-1% (1206)'                  | 'CHIPR1206'    | ''          | ''            | '20150413'
 '1.47K'      | '1%'      | '1/4W'   | '1206LF'  | 'CHIP'   | 'CS21476F200'(!)        = ''              | ''                 | 'CS21476F200'           |'R1206XI'| '(SMR1206AW)'                  | '1.47K'   | '1%'    | '1/4W'   | 'DISCRETE' | 'RES CHIP 1.47K 1/4W +-1%(1206)'                   | 'CHIPR1206'    | ''          | ''            | '20181113'
 '1.47K'      | '1%'      | '1/4W'   | '1206LF'  | 'EMPTY'  | 'CS21476F200'(!)        = ''              | ''                 | 'CS21476F200'           |'R1206XI'| '(SMR1206AW)'                  | '1.47K'   | '1%'    | '1/4W'   | 'IO'       | 'RES CHIP 1.47K 1/4W +-1%(1206)'                   | 'CHIPR1206'    | ''          | ''            | '20181113'
 '866'        | '1%'      | '1/4W'   | '1206LF'  | 'CHIP'   | 'CS18666F200'(!)        = ''              | ''                 | 'CS18666F200'           |'R1206XF'| '(SMR1206AW)'                  | '866'     | '1%'    | '1/4W'   | 'DISCRETE' | 'RES CHIP 866 1/4W +-1%(1206)'                     | 'CHIPR1206'    | ''          | ''            | '20181122'
 '866'        | '1%'      | '1/4W'   | '1206LF'  | 'EMPTY'  | 'CS18666F200'(!)        = ''              | ''                 | 'CS18666F200'           |'R1206XF'| '(SMR1206AW)'                  | '866'     | '1%'    | '1/4W'   | 'IO'       | 'RES CHIP 866 1/4W +-1%(1206)'                     | 'CHIPR1206'    | ''          | ''            | '20181122'
 '910'        | '1%'      | '1/4W'   | '1206LF'  | 'CHIP'   | 'CS19106F200'(!)        = ''              | ''                 | 'CS19106F200'           |'R1206XF'| '(SMR1206AW)'                  | '910'     | '1%'    | '1/4W'   | 'DISCRETE' | 'RES CHIP 910 1/4W +-1%(1206)'                     | 'CHIPR1206'    | ''          | ''            | '20181122'
 '910'        | '1%'      | '1/4W'   | '1206LF'  | 'EMPTY'  | 'CS19106F200'(!)        = ''              | ''                 | 'CS19106F200'           |'R1206XF'| '(SMR1206AW)'                  | '910'     | '1%'    | '1/4W'   | 'IO'       | 'RES CHIP 910 1/4W +-1%(1206)'                     | 'CHIPR1206'    | ''          | ''            | '20181122'
 '237K'       | '1%'      | '1/8W'   | '0805LF'  | 'CHIP'   | 'CS42374FA19'(!)        = ''              | ''                 | 'CS42374FA19'           |'R0805'| '(SMR0805AW)'                  | '237K'    | '1%'    | '1/8W'   | 'DISCRETE' | 'RES CHIP 237K 1/8W +-1%(2012)'                    | 'CHIPR0805'    | ''          | ''            | '20181122'
 '237K'       | '1%'      | '1/8W'   | '0805LF'  | 'EMPTY'  | 'CS42374FA19'(!)        = ''              | ''                 | 'CS42374FA19'           |'R0805'| '(SMR0805AW)'                  | '237K'    | '1%'    | '1/8W'   | 'IO'       | 'RES CHIP 237K 1/8W +-1%(2012)'                    | 'CHIPR0805'    | ''          | ''            | '20181122'
 '7.32K'      | '1%'      | '1/20W'  | '0201LF'  | 'CHIP'   | 'CS27321FE01'(!)        = ''              | ''                 | 'CS27321FE01'           |'R0201'| '(SMR0201AW)'                  | '7.32K'   | '1%'    | '1/20W'  | 'DISCRETE' | 'RES CHIP 7.32K 1/20W +-1%(0201)'                  | 'CHIPR0201'    | ''          | ''            | '20181219'
 '7.32K'      | '1%'      | '1/20W'  | '0201LF'  | 'EMPTY'  | 'CS27321FE01'(!)        = ''              | ''                 | 'CS27321FE01'           |'R0201'| '(SMR0201AW)'                  | '7.32K'   | '1%'    | '1/20W'  | 'IO'       | 'RES CHIP 7.32K 1/20W +-1%(0201)'                  | 'CHIPR0201'    | ''          | ''            | '20181219'
 '0.01'       | '1%'      | '2W'     | '2512LF'  | 'CHIP'   | 'CS+010AFR01'(!)        = ''              | ''                 | 'CS+010AFR01'           |'R2512XT'| '(SMR2512AW)'                  | '0.01'    | '1%'    | '2W'     | 'DISCRETE' | 'RES CHIP 0.01 2W +-1%(2512)AEC'                   | 'CHIP2512'     | ''          | ''            | '20190103'
 '0.01'       | '1%'      | '2W'     | '2512LF'  | 'EMPTY'  | 'CS+010AFR01'(!)        = ''              | ''                 | 'CS+010AFR01'           |'R2512XT'| '(SMR2512AW)'                  | '0.01'    | '1%'    | '2W'     | 'IO'       | 'RES CHIP 0.01 2W +-1%(2512)AEC'                   | 'CHIP2512'     | ''          | ''            | '20190103'
 '360'        | '1%'      | '1/8W'   | '0805LF'  | 'CHIP'   | 'CS13604FA00'(!)        = ''              | ''                 | 'CS13604FA00'           |'R0805'| '(SMR0805AW)'                  | '360'     | '1%'    | '1/8W'   | 'DISCRETE' | 'RES CHIP 360 1/8W +-1%(0805)'                     | 'CHIPR0805'    | ''          | ''            | '20190103'
 '360'        | '1%'      | '1/8W'   | '0805LF'  | 'EMPTY'  | 'CS13604FA00'(!)        = ''              | ''                 | 'CS13604FA00'           |'R0805'| '(SMR0805AW)'                  | '360'     | '1%'    | '1/8W'   | 'IO'       | 'RES CHIP 360 1/8W +-1%(0805)'                     | 'CHIPR0805'    | ''          | ''            | '20190103'
 '887'        | '1%'      | '1/8W'   | '0805LF'  | 'CHIP'   | 'CS18874FA00'(!)        = ''              | ''                 | 'CS18874FA00'           |'R0805'| '(SMR0805AW)'                  | '887'     | '1%'    | '1/8W'   | 'DISCRETE' | 'RES CHIP 887 1/8W +-1%(0805)'                     | 'CHIPR0805'    | ''          | ''            | '20190104'
 '887'        | '1%'      | '1/8W'   | '0805LF'  | 'EMPTY'  | 'CS18874FA00'(!)        = ''              | ''                 | 'CS18874FA00'           |'R0805'| '(SMR0805AW)'                  | '887'     | '1%'    | '1/8W'   | 'IO'       | 'RES CHIP 887 1/8W +-1%(0805)'                     | 'CHIPR0805'    | ''          | ''            | '20190104'
 '43.2K'      | '1%'      | '1/16W'  | '0402LF'  | 'CHIP'   | 'CS34322FB00'(!)        = 'End of Design' | 'Comp-Approve'     | 'CS34322FB00'           |'R0402'| '(R0402-0201)'                 | '43.2K'   | '1%'    | '1/16W'  | 'DISCRETE' | 'RES CHIP 43.2K 1/16W +-1%(0402)'                  | 'CHIPR0402'    | ''          | ''            | '20190107'
 '43.2K'      | '1%'      | '1/16W'  | '0402LF'  | 'EMPTY'  | 'CS34322FB00'(!)        = 'End of Design' | 'Comp-Approve'     | 'CS34322FB00'           |'R0402'| '(R0402-0201)'                 | '43.2K'   | '1%'    | '1/16W'  | 'IO'       | 'RES CHIP 43.2K 1/16W +-1%(0402)'                  | 'CHIPR0402'    | ''          | ''            | '20190107'
 '21K'        | '1%'      | '1/10W'  | '0603LF'  | 'CHIP'   | 'CS32103F911'(!)        = ''              | ''                 | 'CS32103F911'           |'R0603'| '(SMR0603AW)'                  | '21K'     | '1%'    | '1/10W'  | 'DISCRETE' | 'RES CHIP 21K 1/10W+-1%(0603)'                     | 'CHIPR0603'    | ''          | ''            | '20190111'
 '21K'        | '1%'      | '1/10W'  | '0603LF'  | 'EMPTY'  | 'CS32103F911'(!)        = ''              | ''                 | 'CS32103F911'           |'R0603'| '(SMR0603AW)'                  | '21K'     | '1%'    | '1/10W'  | 'IO'       | 'RES CHIP 21K 1/10W+-1%(0603)'                     | 'CHIPR0603'    | ''          | ''            | '20190111'
 '909'        | '0.1%'    | '1/16W'  | '0402LF'  | 'CHIP'   | 'CS19092BB00'(!)        = ''              | ''                 | 'CS19092BB00'           |'R0402'| '(R0402-0201)'                 | '909'     | '0.1%'  | '1/16W'  | 'DISCRETE' | 'RES CHIP 909 1/16W +-0.1%(0402)EF'                | 'CHIPR0402'    | ''          | ''            | '20190115'
 '909'        | '0.1%'    | '1/16W'  | '0402LF'  | 'EMPTY'  | 'CS19092BB00'(!)        = ''              | ''                 | 'CS19092BB00'           |'R0402'| '(R0402-0201)'                 | '909'     | '0.1%'  | '1/16W'  | 'IO'       | 'RES CHIP 909 1/16W +-0.1%(0402)EF'                | 'CHIPR0402'    | ''          | ''            | '20190115'
 '90.9K'      | '0.1%'    | '1/16W'  | '0402LF'  | 'CHIP'   | 'CS39092BB00'(!)        = ''              | ''                 | 'CS39092BB00'           |'R0402'| '(R0402-0201)'                 | '90.9K'   | '0.1%'  | '1/16W'  | 'DISCRETE' | 'RES CHIP 90.9K 1/16W +-0.1%(0402)EF'              | 'CHIPR0402'    | ''          | ''            | '20190115'
 '90.9K'      | '0.1%'    | '1/16W'  | '0402LF'  | 'EMPTY'  | 'CS39092BB00'(!)        = ''              | ''                 | 'CS39092BB00'           |'R0402'| '(R0402-0201)'                 | '90.9K'   | '0.1%'  | '1/16W'  | 'IO'       | 'RES CHIP 90.9K 1/16W +-0.1%(0402)EF'              | 'CHIPR0402'    | ''          | ''            | '20190115'
 '240'        | '0.5%'    | '1/16W'  | '0402LF'  | 'CHIP'   | 'CS12402DB00'(!)        = 'End of Design' | 'Comp-Approve'     | 'CS12402DB00'           |'R0402'| '(R0402-0201)'                 | '240'     | '0.5%'  | '1/16W'  | 'DISCRETE' | 'RES CHIP 240 1/16W +-0.5%(0402)'                  | 'CHIPR0402'    | ''          | ''            | '20190115'
 '240'        | '0.5%'    | '1/16W'  | '0402LF'  | 'EMPTY'  | 'CS12402DB00'(!)        = 'End of Design' | 'Comp-Approve'     | 'CS12402DB00'           |'R0402'| '(R0402-0201)'                 | '240'     | '0.5%'  | '1/16W'  | 'IO'       | 'RES CHIP 240 1/16W +-0.5%(0402)'                  | 'CHIPR0402'    | ''          | ''            | '20190115'
 '11.8K'      | '0.1%'    | '1/16W'  | '0402LF'  | 'CHIP'   | 'CS31182BB00'(!)        = ''              | ''                 | 'CS31182BB00'           |'R0402'| '(R0402-0201)'                 | '11.8K'   | '0.1%'  | '1/16W'  | 'DISCRETE' | 'RES CHIP 11.8K 1/16W +-0.1%(0402)'                | 'CHIPR0402'    | ''          | ''            | '20190117'
 '11.8K'      | '0.1%'    | '1/16W'  | '0402LF'  | 'EMPTY'  | 'CS31182BB00'(!)        = ''              | ''                 | 'CS31182BB00'           |'R0402'| '(R0402-0201)'                 | '11.8K'   | '0.1%'  | '1/16W'  | 'IO'       | 'RES CHIP 11.8K 1/16W +-0.1%(0402)'                | 'CHIPR0402'    | ''          | ''            | '20190117'
 '12.4K'      | '0.1%'    | '1/16W'  | '0402LF'  | 'CHIP'   | 'CS31242BB00'(!)        = 'End of Design' | 'Comp-Approve'     | 'CS31242BB00'           |'R0402'| '(R0402-0201)'                 | '12.4K'   | '0.1%'  | '1/16W'  | 'DISCRETE' | 'RES CHIP 12.4K 1/16W +-0.1%( 0402)'               | 'CHIPR0402'    | ''          | ''            | '20190117'
 '12.4K'      | '0.1%'    | '1/16W'  | '0402LF'  | 'EMPTY'  | 'CS31242BB00'(!)        = 'End of Design' | 'Comp-Approve'     | 'CS31242BB00'           |'R0402'| '(R0402-0201)'                 | '12.4K'   | '0.1%'  | '1/16W'  | 'IO'       | 'RES CHIP 12.4K 1/16W +-0.1%( 0402)'               | 'CHIPR0402'    | ''          | ''            | '20190117'
 '42.2'       | '1%'      | '1/20W'  | '0201LF'  | 'CHIP'   | 'CS04221FE00'(!)        = ''              | ''                 | 'CS04221FE00'           |'R0201'| '(SMR0201AW)'                  | '42.2'    | '1%'    | '1/20W'  | 'DISCRETE' | 'RES CHIP 42.2 (1/20W,+-1%,0201)'                  | 'CHIPR0201'    | ''          | ''            | '20190123'
 '42.2'       | '1%'      | '1/20W'  | '0201LF'  | 'EMPTY'  | 'CS04221FE00'(!)        = ''              | ''                 | 'CS04221FE00'           |'R0201'| '(SMR0201AW)'                  | '42.2'    | '1%'    | '1/20W'  | 'IO'       | 'RES CHIP 42.2 (1/20W,+-1%,0201)'                  | 'CHIPR0201'    | ''          | ''            | '20190123'
 '43.2'       | '1%'      | '1/20W'  | '0201LF'  | 'CHIP'   | 'CS04321FE01'(!)        = ''              | ''                 | 'CS04321FE01'           |'R0201'| '(SMR0201AW)'                  | '43.2'    | '1%'    | '1/20W'  | 'DISCRETE' | 'RES CHIP 43.2 1/20W +-1%(0201)'                   | 'CHIPR0201'    | ''          | ''            | '20190124'
 '43.2'       | '1%'      | '1/20W'  | '0201LF'  | 'EMPTY'  | 'CS04321FE01'(!)        = ''              | ''                 | 'CS04321FE01'           |'R0201'| '(SMR0201AW)'                  | '43.2'    | '1%'    | '1/20W'  | 'IO'       | 'RES CHIP 43.2 1/20W +-1%(0201)'                   | 'CHIPR0201'    | ''          | ''            | '20190124'
 '4.75K'      | '1%'      | '1/16W'  | '0402LF'  | 'CHIP'   | 'CS24752FB03'(!)        = 'End of Design' | 'Comp-Approve'     | 'CS24752FB03'           |'R0402'| '(R0402-0201)'                 | '4.75K'   | '1%'    | '1/16W'  | 'DISCRETE' | 'RES CHIP 4.75K 1/16W +-1%(0402)EF'                | 'CHIPR0402'    | ''          | ''            | '20190124'
 '4.75K'      | '1%'      | '1/16W'  | '0402LF'  | 'EMPTY'  | 'CS24752FB03'(!)        = 'End of Design' | 'Comp-Approve'     | 'CS24752FB03'           |'R0402'| '(R0402-0201)'                 | '4.75K'   | '1%'    | '1/16W'  | 'IO'       | 'RES CHIP 4.75K 1/16W +-1%(0402)EF'                | 'CHIPR0402'    | ''          | ''            | '20190124'
 '15'         | '1%'      | '1/16W'  | '0402LF'  | 'CHIP'   | 'CS01502FB03'(!)        = 'End of Design' | 'Comp-Approve'     | 'CS01502FB03'           |'R0402'| '(R0402-0201)'                 | '15'      | '1%'    | '1/16W'  | 'DISCRETE' | 'RES CHIP 15 1/16W +-1%(0402)EF'                   | 'CHIPR0402'    | ''          | ''            | '20190212'
 '15'         | '1%'      | '1/16W'  | '0402LF'  | 'EMPTY'  | 'CS01502FB03'(!)        = 'End of Design' | 'Comp-Approve'     | 'CS01502FB03'           |'R0402'| '(R0402-0201)'                 | '15'      | '1%'    | '1/16W'  | 'IO'       | 'RES CHIP 15 1/16W +-1%(0402)EF'                   | 'CHIPR0402'    | ''          | ''            | '20190212'
 '825'        | '1%'      | '1/4W'   | '1206LF'  | 'CHIP'   | 'CS18256F200'(!)        = ''              | ''                 | 'CS18256F200'           |'R1206XF'| '(SMR1206AW)'                  | '825'     | '1%'    | '1/4W'   | 'DISCRETE' | 'RES CHIP 825 1/4W +-1%(1206)'                     | 'CHIPR1206'    | ''          | ''            | '20190214'
 '825'        | '1%'      | '1/4W'   | '1206LF'  | 'EMPTY'  | 'CS18256F200'(!)        = ''              | ''                 | 'CS18256F200'           |'R1206XF'| '(SMR1206AW)'                  | '825'     | '1%'    | '1/4W'   | 'IO'       | 'RES CHIP 825 1/4W +-1%(1206)'                     | 'CHIPR1206'    | ''          | ''            | '20190214'
 '20M'        | '5%'      | '1/10W'  | '0603LF'  | 'CHIP'   | 'CS62003J914'(!)        = ''              | ''                 | 'CS62003J914'           |'R0603'| '(SMR0603AW)'                  | '20M'     | '5%'    | '1/10W'  | 'DISCRETE' | 'RES CHIP 20M  1/10W +-5%(0603)'                   | 'CHIPR0603'    | ''          | ''            | '20100429'
 '20M'        | '5%'      | '1/10W'  | '0603LF'  | 'EMPTY'  | 'CS62003J914'(!)        = ''              | ''                 | 'CS62003J914'           |'R0603'| '(SMR0603AW)'                  | '20M'     | '5%'    | '1/10W'  | 'IO'       | 'RES CHIP 20M  1/10W +-5%(0603)'                   | 'CHIPR0603'    | ''          | ''            | '20100429'
 '3.3K'       | '5%'      | '1/8W'   | '0805LF'  | 'CHIP'   | 'CS23304JA01'(!)        = ''              | ''                 | 'CS23304JA01'           |'R0805'| '(SMR0805AW)'                  | '3.3K'    | '5%'    | '1/8W'   | 'DISCRETE' | 'RES CHIP 3.3K 1/8W +-5%(0805)'                    | 'CHIPR0805'    | ''          | ''            | '20190318'
 '3.3K'       | '5%'      | '1/8W'   | '0805LF'  | 'EMPTY'  | 'CS23304JA01'(!)        = ''              | ''                 | 'CS23304JA01'           |'R0805'| '(SMR0805AW)'                  | '3.3K'    | '5%'    | '1/8W'   | 'IO'       | 'RES CHIP 3.3K 1/8W +-5%(0805)'                    | 'CHIPR0805'    | ''          | ''            | '20190318'
 '162'        | '1%'      | '1/16W'  | '0402LF'  | 'CHIP'   | 'CS11622FB01'(!)        = 'End of Design' | 'Comp-Approve'     | 'CS11622FB01'           |'R0402'| '(R0402-0201)'                 | '162'     | '1%'    | '1/16W'  | 'DISCRETE' | 'RES CHIP 162 1/16W +-1%(0402)EF'                  | 'CHIPR0402'    | ''          | ''            | '20190325'
 '162'        | '1%'      | '1/16W'  | '0402LF'  | 'EMPTY'  | 'CS11622FB01'(!)        = 'End of Design' | 'Comp-Approve'     | 'CS11622FB01'           |'R0402'| '(R0402-0201)'                 | '162'     | '1%'    | '1/16W'  | 'IO'       | 'RES CHIP 162 1/16W +-1%(0402)EF'                  | 'CHIPR0402'    | ''          | ''            | '20190325'
 '681'        | '1%'      | '1/16W'  | '0402LF'  | 'CHIP'   | 'CS16812FB02'(!)        = 'End of Design' | 'Comp-Approve'     | 'CS16812FB02'           |'R0402'| '(R0402-0201)'                 | '681'     | '1%'    | '1/16W'  | 'DISCRETE' | 'RES CHIP 681 1/16W +-1%(0402)EF'                  | 'CHIPR0402'    | ''          | ''            | '20190325'
 '681'        | '1%'      | '1/16W'  | '0402LF'  | 'EMPTY'  | 'CS16812FB02'(!)        = 'End of Design' | 'Comp-Approve'     | 'CS16812FB02'           |'R0402'| '(R0402-0201)'                 | '681'     | '1%'    | '1/16W'  | 'IO'       | 'RES CHIP 681 1/16W +-1%(0402)EF'                  | 'CHIPR0402'    | ''          | ''            | '20190325'
 '1.82M'      | '1%'      | '1/16W'  | '0402LF'  | 'CHIP'   | 'CS51822FB00'(!)        = ''              | ''                 | 'CS51822FB00'           |'R0402'| '(R0402-0201)'                 | '1.82M'   | '1%'    | '1/16W'  | 'DISCRETE' | 'RES CHIP 1.82M 1/16W +-1%(0402)'                  | 'CHIPR0402'    | ''          | ''            | '20190429'
 '1.82M'      | '1%'      | '1/16W'  | '0402LF'  | 'EMPTY'  | 'CS51822FB00'(!)        = ''              | ''                 | 'CS51822FB00'           |'R0402'| '(R0402-0201)'                 | '1.82M'   | '1%'    | '1/16W'  | 'IO'       | 'RES CHIP 1.82M 1/16W +-1%(0402)'                  | 'CHIPR0402'    | ''          | ''            | '20190429'
 '240'        | '1%'      | '1/8W'   | '0805LF'  | 'CHIP'   | 'CS12404FA01'(!)        = ''              | ''                 | 'CS12404FA01'           |'R0805'| '(SMR0805AW)'                  | '240'     | '1%'    | '1/8W'   | 'DISCRETE' | 'RES CHIP 240 1/8W +-1%(0805)'                     | 'CHIPR0805'    | ''          | ''            | '20190521'
 '240'        | '1%'      | '1/8W'   | '0805LF'  | 'EMPTY'  | 'CS12404FA01'(!)        = ''              | ''                 | 'CS12404FA01'           |'R0805'| '(SMR0805AW)'                  | '240'     | '1%'    | '1/8W'   | 'IO'       | 'RES CHIP 240 1/8W +-1%(0805)'                     | 'CHIPR0805'    | ''          | ''            | '20190521'
 '1.62K'      | '0.1%'    | '1/16W'  | '0402LF'  | 'CHIP'   | 'CS21622BB00'(!)        = ''              | ''                 | 'CS21622BB00'           |'R0402'| '(R0402-0201)'                 | '1.62K'   | '0.1%'  | '1/16W'  | 'DISCRETE' | 'RES CHIP 1.62K 1/16W +-0.1%(0402)'                | 'CHIPR0402'    | ''          | ''            | '20190527'
 '1.62K'      | '0.1%'    | '1/16W'  | '0402LF'  | 'EMPTY'  | 'CS21622BB00'(!)        = ''              | ''                 | 'CS21622BB00'           |'R0402'| '(R0402-0201)'                 | '1.62K'   | '0.1%'  | '1/16W'  | 'IO'       | 'RES CHIP 1.62K 1/16W +-0.1%(0402)'                | 'CHIPR0402'    | ''          | ''            | '20190527'
 '95.3K'      | '0.1%'    | '1/8W'   | '0805LF'  | 'CHIP'   | 'CS39534BA00'(!)        = ''              | ''                 | 'CS39534BA00'           |'R0805'| '(SMR0805AW)'                  | '95.3K'   | '0.1%'  | '1/8W'   | 'DISCRETE' | 'RES CHIP 95.3K 1/8W +-0.1%(0805)'                 | 'CHIPR0805'    | ''          | ''            | '20190529'
 '95.3K'      | '0.1%'    | '1/8W'   | '0805LF'  | 'EMPTY'  | 'CS39534BA00'(!)        = ''              | ''                 | 'CS39534BA00'           |'R0805'| '(SMR0805AW)'                  | '95.3K'   | '0.1%'  | '1/8W'   | 'IO'       | 'RES CHIP 95.3K 1/8W +-0.1%(0805)'                 | 'CHIPR0805'    | ''          | ''            | '20190529'
 '909'        | '1%'      | '1/16W'  | '0402LF'  | 'CHIP'   | 'CS19092FB03'(!)        = 'End of Design' | 'Comp-Approve'     | 'CS19092FB03'           |'R0402'| '(R0402-0201)'                 | '909'     | '1%'    | '1/16W'  | 'DISCRETE' | 'RES CHIP 909 1/16W +-1%(0402)EF'                  | 'CHIPR0402'    | ''          | ''            | '20190614'
 '909'        | '1%'      | '1/16W'  | '0402LF'  | 'EMPTY'  | 'CS19092FB03'(!)        = 'End of Design' | 'Comp-Approve'     | 'CS19092FB03'           |'R0402'| '(R0402-0201)'                 | '909'     | '1%'    | '1/16W'  | 'IO'       | 'RES CHIP 909 1/16W +-1%(0402)EF'                  | 'CHIPR0402'    | ''          | ''            | '20190614'
 '90.9K'      | '1%'      | '1/16W'  | '0402LF'  | 'CHIP'   | 'CS39092FB04'(!)        = 'End of Design' | 'Comp-Approve'     | 'CS39092FB04'           |'R0402'| '(R0402-0201)'                 | '90.9K'   | '1%'    | '1/16W'  | 'DISCRETE' | 'RES CHIP 90.9K 1/16W +-1%(0402)EF'                | 'CHIPR0402'    | ''          | ''            | '20190715'
 '90.9K'      | '1%'      | '1/16W'  | '0402LF'  | 'EMPTY'  | 'CS39092FB04'(!)        = 'End of Design' | 'Comp-Approve'     | 'CS39092FB04'           |'R0402'| '(R0402-0201)'                 | '90.9K'   | '1%'    | '1/16W'  | 'IO'       | 'RES CHIP 90.9K 1/16W +-1%(0402)EF'                | 'CHIPR0402'    | ''          | ''            | '20190715'
 '33.2K'      | '1%'      | '1/16W'  | '0402LF'  | 'CHIP'   | 'CS33322FB03'(!)        = 'End of Design' | 'Comp-Approve'     | 'CS33322FB03'           |'R0402'| '(R0402-0201)'                 | '33.2K'   | '1%'    | '1/16W'  | 'DISCRETE' | 'RES CHIP 33.2K 1/16W +-1%(0402)EF'                | 'CHIPR0402'    | ''          | ''            | '20190715'
 '33.2K'      | '1%'      | '1/16W'  | '0402LF'  | 'EMPTY'  | 'CS33322FB03'(!)        = 'End of Design' | 'Comp-Approve'     | 'CS33322FB03'           |'R0402'| '(R0402-0201)'                 | '33.2K'   | '1%'    | '1/16W'  | 'IO'       | 'RES CHIP 33.2K 1/16W +-1%(0402)EF'                | 'CHIPR0402'    | ''          | ''            | '20190715'
 '5.6K'       | '1%'      | '1/16W'  | '0402LF'  | 'CHIP'   | 'CS25602FB04'(!)        = ''              | ''                 | 'CS25602FB04'           |'R0402'| '(R0402-0201)'                 | '5.6K'    | '1%'    | '1/16W'  | 'DISCRETE' | 'RES CHIP 5.6K 1/16W +-1%(0402)EF'                 | 'CHIPR0402'    | ''          | ''            | '20190711'
 '5.6K'       | '1%'      | '1/16W'  | '0402LF'  | 'EMPTY'  | 'CS25602FB04'(!)        = ''              | ''                 | 'CS25602FB04'           |'R0402'| '(R0402-0201)'                 | '5.6K'    | '1%'    | '1/16W'  | 'IO'       | 'RES CHIP 5.6K 1/16W +-1%(0402)EF'                 | 'CHIPR0402'    | ''          | ''            | '20190711'
 '56K'        | '1%'      | '1/16W'  | '0402LF'  | 'CHIP'   | 'CS35602FB00'(!)        = ''              | ''                 | 'CS35602FB00'           |'R0402'| '(R0402-0201)'                 | '56K'     | '1%'    | '1/16W'  | 'DISCRETE' | 'RES CHIP 56K 1/16W +-1%(0402)EF'                  | 'CHIPR0402'    | ''          | ''            | '20190711'
 '56K'        | '1%'      | '1/16W'  | '0402LF'  | 'EMPTY'  | 'CS35602FB00'(!)        = ''              | ''                 | 'CS35602FB00'           |'R0402'| '(R0402-0201)'                 | '56K'     | '1%'    | '1/16W'  | 'IO'       | 'RES CHIP 56K 1/16W +-1%(0402)EF'                  | 'CHIPR0402'    | ''          | ''            | '20190711'
 '59K'        | '1%'      | '1/16W'  | '0402LF'  | 'CHIP'   | 'CS35902FB01'(!)        = 'End of Design' | 'Comp-Approve'     | 'CS35902FB01'           |'R0402'| '(R0402-0201)'                 | '59K'     | '1%'    | '1/16W'  | 'DISCRETE' | 'RES CHIP 59K 1/16W +-1%(0402)EF'                  | 'CHIPR0402'    | ''          | ''            | '20190711'
 '59K'        | '1%'      | '1/16W'  | '0402LF'  | 'EMPTY'  | 'CS35902FB01'(!)        = 'End of Design' | 'Comp-Approve'     | 'CS35902FB01'           |'R0402'| '(R0402-0201)'                 | '59K'     | '1%'    | '1/16W'  | 'IO'       | 'RES CHIP 59K 1/16W +-1%(0402)EF'                  | 'CHIPR0402'    | ''          | ''            | '20190711'
 '71.5K'      | '1%'      | '1/16W'  | '0402LF'  | 'CHIP'   | 'CS37152FB05'(!)        = ''              | ''                 | 'CS37152FB05'           |'R0402'| '(R0402-0201)'                 | '71.5K'   | '1%'    | '1/16W'  | 'DISCRETE' | 'RES CHIP 71.5K 1/16W +-1%(0402)EF'                | 'CHIPR0402'    | ''          | ''            | '20190717'
 '71.5K'      | '1%'      | '1/16W'  | '0402LF'  | 'EMPTY'  | 'CS37152FB05'(!)        = ''              | ''                 | 'CS37152FB05'           |'R0402'| '(R0402-0201)'                 | '71.5K'   | '1%'    | '1/16W'  | 'IO'       | 'RES CHIP 71.5K 1/16W +-1%(0402)EF'                | 'CHIPR0402'    | ''          | ''            | '20190717'
 '24.3K'      | '1%'      | '1/16W'  | '0402LF'  | 'CHIP'   | 'CS32432FB03'(!)        = ''              | ''                 | 'CS32432FB03'           |'R0402'| '(R0402-0201)'                 | '24.3K'   | '1%'    | '1/16W'  | 'DISCRETE' | 'RES CHIP 24.3K 1/16W +-1%(0402)EF'                | 'CHIPR0402'    | ''          | ''            | '20190717'
 '24.3K'      | '1%'      | '1/16W'  | '0402LF'  | 'EMPTY'  | 'CS32432FB03'(!)        = ''              | ''                 | 'CS32432FB03'           |'R0402'| '(R0402-0201)'                 | '24.3K'   | '1%'    | '1/16W'  | 'IO'       | 'RES CHIP 24.3K 1/16W +-1%(0402)EF'                | 'CHIPR0402'    | ''          | ''            | '20190717'
 '115K'       | '1%'      | '1/16W'  | '0402LF'  | 'CHIP'   | 'CS41152FB03'(!)        = 'End of Design' | 'Comp-Approve'     | 'CS41152FB03'           |'R0402'| '(R0402-0201)'                 | '115K'    | '1%'    | '1/16W'  | 'DISCRETE' | 'RES CHIP 115K 1/16W +-1%(0402)EF'                 | 'CHIPR0402'    | ''          | ''            | '20190718'
 '115K'       | '1%'      | '1/16W'  | '0402LF'  | 'EMPTY'  | 'CS41152FB03'(!)        = 'End of Design' | 'Comp-Approve'     | 'CS41152FB03'           |'R0402'| '(R0402-0201)'                 | '115K'    | '1%'    | '1/16W'  | 'IO'       | 'RES CHIP 115K 1/16W +-1%(0402)EF'                 | 'CHIPR0402'    | ''          | ''            | '20190718'
 '6.04K'      | '1%'      | '1/16W'  | '0402LF'  | 'CHIP'   | 'CS26042FB04'(!)        = 'End of Design' | 'Comp-Approve'     | 'CS26042FB04'           |'R0402'| '(R0402-0201)'                 | '6.04K'   | '1%'    | '1/16W'  | 'DISCRETE' | 'RES CHIP 6.04K 1/16W +-1%(0402)EF'                | 'CHIPR0402'    | ''          | ''            | '20190717'
 '6.04K'      | '1%'      | '1/16W'  | '0402LF'  | 'EMPTY'  | 'CS26042FB04'(!)        = 'End of Design' | 'Comp-Approve'     | 'CS26042FB04'           |'R0402'| '(R0402-0201)'                 | '6.04K'   | '1%'    | '1/16W'  | 'IO'       | 'RES CHIP 6.04K 1/16W +-1%(0402)EF'                | 'CHIPR0402'    | ''          | ''            | '20190717'
 '1.33K'      | '1%'      | '1/16W'  | '0402LF'  | 'CHIP'   | 'CS21332FB05'(!)        = ''              | ''                 | 'CS21332FB05'           |'R0402'| '(R0402-0201)'                 | '1.33K'   | '1%'    | '1/16W'  | 'DISCRETE' | 'RES CHIP 1.33K 1/16W +-1%(0402)EF'                | 'CHIPR0402'    | ''          | ''            | '20190717'
 '1.33K'      | '1%'      | '1/16W'  | '0402LF'  | 'EMPTY'  | 'CS21332FB05'(!)        = ''              | ''                 | 'CS21332FB05'           |'R0402'| '(R0402-0201)'                 | '1.33K'   | '1%'    | '1/16W'  | 'IO'       | 'RES CHIP 1.33K 1/16W +-1%(0402)EF'                | 'CHIPR0402'    | ''          | ''            | '20190717'
 '1'          | '5%'      | '1/16W'  | '0402LF'  | 'CHIP'   | 'CS-1002JB10'(!)        = 'End of Design' | 'Comp-Approve'     | 'CS-1002JB10'           |'R0402'| '(R0402-0201)'                 | '1'       | '5%'    | '1/16W'  | 'DISCRETE' | 'RES CHIP 1 1/16W +-5%(0402)EF'                    | 'CHIPR0402'    | ''          | ''            | '20190717'
 '1'          | '5%'      | '1/16W'  | '0402LF'  | 'EMPTY'  | 'CS-1002JB10'(!)        = 'End of Design' | 'Comp-Approve'     | 'CS-1002JB10'           |'R0402'| '(R0402-0201)'                 | '1'       | '5%'    | '1/16W'  | 'IO'       | 'RES CHIP 1 1/16W +-5%(0402)EF'                    | 'CHIPR0402'    | ''          | ''            | '20190717'
 '40.2K'      | '1%'      | '1/20W'  | '0201LF'  | 'CHIP'   | 'CS34021FE02'(!)        = ''              | ''                 | 'CS34021FE02'           |'R0201'| '(SMR0201AW)'                  | '40.2K'   | '1%'    | '1/20W'  | 'DISCRETE' | 'RES CHIP 40.2K 1/20W +-1%(0201)'                  | 'CHIPR0201'    | ''          | ''            | '20190718'
 '40.2K'      | '1%'      | '1/20W'  | '0201LF'  | 'EMPTY'  | 'CS34021FE02'(!)        = ''              | ''                 | 'CS34021FE02'           |'R0201'| '(SMR0201AW)'                  | '40.2K'   | '1%'    | '1/20W'  | 'IO'       | 'RES CHIP 40.2K 1/20W +-1%(0201)'                  | 'CHIPR0201'    | ''          | ''            | '20190718'
 '200'        | '5%'      | '1/10W'  | '0603LF'  | 'CHIP'   | 'CS12003J901'(!)        = ''              | ''                 | 'CS12003J901'           |'R0603_H24'| '(SMR0603AW)'                  | '200'     | '5%'    | '1/10W'  | 'DISCRETE' | 'RES CHIP 200 1/10W +-5%(0603)EF'                  | 'CHIPR0603'    | ''          | ''            | '20190717'
 '200'        | '5%'      | '1/10W'  | '0603LF'  | 'EMPTY'  | 'CS12003J901'(!)        = ''              | ''                 | 'CS12003J901'           |'R0603_H24'| '(SMR0603AW)'                  | '200'     | '5%'    | '1/10W'  | 'IO'       | 'RES CHIP 200 1/10W +-5%(0603)EF'                  | 'CHIPR0603'    | ''          | ''            | '20190717'
 '2.2'        | '5%'      | '1/16W'  | '0402LF'  | 'CHIP'   | 'CS-2202JB07'(!)        = 'End of Design' | 'Comp-Approve'     | 'CS-2202JB07'           |'R0402'| '(R0402-0201)'                 | '2.2'     | '5%'    | '1/16W'  | 'DISCRETE' | 'RES CHIP 2.2 1/16W +-5%  (0402) EF'               | 'CHIPR0402'    | ''          | ''            | '20190717'
 '2.2'        | '5%'      | '1/16W'  | '0402LF'  | 'EMPTY'  | 'CS-2202JB07'(!)        = 'End of Design' | 'Comp-Approve'     | 'CS-2202JB07'           |'R0402'| '(R0402-0201)'                 | '2.2'     | '5%'    | '1/16W'  | 'IO'       | 'RES CHIP 2.2 1/16W +-5%  (0402) EF'               | 'CHIPR0402'    | ''          | ''            | '20190717'
 '4.42K'      | '1%'      | '1/16W'  | '0402LF'  | 'CHIP'   | 'CS24422FB03'(!)        = 'End of Design' | 'Comp-Approve'     | 'CS24422FB03'           |'R0402'| '(R0402-0201)'                 | '4.42K'   | '1%'    | '1/16W'  | 'DISCRETE' | 'RES CHIP 4.42K 1/16W +-1%(0402)EF'                | 'CHIPR0402'    | ''          | ''            | '20190717'
 '4.42K'      | '1%'      | '1/16W'  | '0402LF'  | 'EMPTY'  | 'CS24422FB03'(!)        = 'End of Design' | 'Comp-Approve'     | 'CS24422FB03'           |'R0402'| '(R0402-0201)'                 | '4.42K'   | '1%'    | '1/16W'  | 'IO'       | 'RES CHIP 4.42K 1/16W +-1%(0402)EF'                | 'CHIPR0402'    | ''          | ''            | '20190717'
 '4.99K'      | '1%'      | '1/16W'  | '0402LF'  | 'CHIP'   | 'CS24992FB07'(!)        = 'End of Design' | 'Comp-Approve'     | 'CS24992FB07'           |'R0402'| '(R0402-0201)'                 | '4.99K'   | '1%'    | '1/16W'  | 'DISCRETE' | 'RES CHIP 4.99K 1/16W +-1%(0402)EF'                | 'CHIPR0402'    | ''          | ''            | '20190717'
 '4.99K'      | '1%'      | '1/16W'  | '0402LF'  | 'EMPTY'  | 'CS24992FB07'(!)        = 'End of Design' | 'Comp-Approve'     | 'CS24992FB07'           |'R0402'| '(R0402-0201)'                 | '4.99K'   | '1%'    | '1/16W'  | 'IO'       | 'RES CHIP 4.99K 1/16W +-1%(0402)EF'                | 'CHIPR0402'    | ''          | ''            | '20190717'
 '8.25K'      | '0.1%'    | '1/16W'  | '0402LF'  | 'CHIP'   | 'CS28252BB01'(!)        = ''              | ''                 | 'CS28252BB01'           |'R0402'| '(R0402-0201)'                 | '8.25K'   | '0.1%'  | '1/16W'  | 'DISCRETE' | 'RES CHIP 8.25K 1/16W +-0.1%(0402)EF'              | 'CHIPR0402'    | ''          | ''            | '20190717'
 '8.25K'      | '0.1%'    | '1/16W'  | '0402LF'  | 'EMPTY'  | 'CS28252BB01'(!)        = ''              | ''                 | 'CS28252BB01'           |'R0402'| '(R0402-0201)'                 | '8.25K'   | '0.1%'  | '1/16W'  | 'IO'       | 'RES CHIP 8.25K 1/16W +-0.1%(0402)EF'              | 'CHIPR0402'    | ''          | ''            | '20190717'
 '8.87K'      | '1%'      | '1/16W'  | '0402LF'  | 'CHIP'   | 'CS28872FB01'(!)        = 'End of Design' | 'Comp-Approve'     | 'CS28872FB01'           |'R0402'| '(R0402-0201)'                 | '8.87K'   | '1%'    | '1/16W'  | 'DISCRETE' | 'RES CHIP 8.87K 1/16W +-1%(0402)EF'                | 'CHIPR0402'    | ''          | ''            | '20190718'
 '8.87K'      | '1%'      | '1/16W'  | '0402LF'  | 'EMPTY'  | 'CS28872FB01'(!)        = 'End of Design' | 'Comp-Approve'     | 'CS28872FB01'           |'R0402'| '(R0402-0201)'                 | '8.87K'   | '1%'    | '1/16W'  | 'IO'       | 'RES CHIP 8.87K 1/16W +-1%(0402)EF'                | 'CHIPR0402'    | ''          | ''            | '20190718'
 '18.2K'      | '1%'      | '1/16W'  | '0402LF'  | 'CHIP'   | 'CS31822FB02'(!)        = 'End of Design' | 'Comp-Approve'     | 'CS31822FB02'           |'R0402'| '(R0402-0201)'                 | '18.2K'   | '1%'    | '1/16W'  | 'DISCRETE' | 'RES CHIP 18.2K 1/16W +-1%(0402)EF'                | 'CHIPR0402'    | ''          | ''            | '20190718'
 '18.2K'      | '1%'      | '1/16W'  | '0402LF'  | 'EMPTY'  | 'CS31822FB02'(!)        = 'End of Design' | 'Comp-Approve'     | 'CS31822FB02'           |'R0402'| '(R0402-0201)'                 | '18.2K'   | '1%'    | '1/16W'  | 'IO'       | 'RES CHIP 18.2K 1/16W +-1%(0402)EF'                | 'CHIPR0402'    | ''          | ''            | '20190718'
 '31.6K'      | '1%'      | '1/16W'  | '0402LF'  | 'CHIP'   | 'CS33162FB02'(!)        = 'End of Design' | 'Comp-Approve'     | 'CS33162FB02'           |'R0402'| '(R0402-0201)'                 | '31.6K'   | '1%'    | '1/16W'  | 'DISCRETE' | 'RES CHIP 31.6K 1/16W +-1%(0402)EF'                | 'CHIPR0402'    | ''          | ''            | '20190718'
 '31.6K'      | '1%'      | '1/16W'  | '0402LF'  | 'EMPTY'  | 'CS33162FB02'(!)        = 'End of Design' | 'Comp-Approve'     | 'CS33162FB02'           |'R0402'| '(R0402-0201)'                 | '31.6K'   | '1%'    | '1/16W'  | 'IO'       | 'RES CHIP 31.6K 1/16W +-1%(0402)EF'                | 'CHIPR0402'    | ''          | ''            | '20190718'
 '41.2K'      | '1%'      | '1/16W'  | '0402LF'  | 'CHIP'   | 'CS34122FB03'(!)        = 'End of Design' | 'Comp-Approve'     | 'CS34122FB03'           |'R0402'| '(R0402-0201)'                 | '41.2K'   | '1%'    | '1/16W'  | 'DISCRETE' | 'RES CHIP 41.2K 1/16W +-1%(0402)EF'                | 'CHIPR0402'    | ''          | ''            | '20190718'
 '41.2K'      | '1%'      | '1/16W'  | '0402LF'  | 'EMPTY'  | 'CS34122FB03'(!)        = 'End of Design' | 'Comp-Approve'     | 'CS34122FB03'           |'R0402'| '(R0402-0201)'                 | '41.2K'   | '1%'    | '1/16W'  | 'IO'       | 'RES CHIP 41.2K 1/16W +-1%(0402)EF'                | 'CHIPR0402'    | ''          | ''            | '20190718'
 '47K'        | '5%'      | '1/16W'  | '0402LF'  | 'CHIP'   | 'CS34702JB09'(!)        = ''              | ''                 | 'CS34702JB09'           |'R0402'| '(R0402-0201)'                 | '47K'     | '5%'    | '1/16W'  | 'DISCRETE' | 'RES CHIP 47K 1/16W +-5%(0402)EF'                  | 'CHIPR0402'    | ''          | ''            | '20190718'
 '47K'        | '5%'      | '1/16W'  | '0402LF'  | 'EMPTY'  | 'CS34702JB09'(!)        = ''              | ''                 | 'CS34702JB09'           |'R0402'| '(R0402-0201)'                 | '47K'     | '5%'    | '1/16W'  | 'IO'       | 'RES CHIP 47K 1/16W +-5%(0402)EF'                  | 'CHIPR0402'    | ''          | ''            | '20190718'
 '53.6K'      | '1%'      | '1/16W'  | '0402LF'  | 'CHIP'   | 'CS35362FB02'(!)        = 'End of Design' | 'Comp-Approve'     | 'CS35362FB02'           |'R0402'| '(R0402-0201)'                 | '53.6K'   | '1%'    | '1/16W'  | 'DISCRETE' | 'RES CHIP 53.6K 1/16W +-1%(0402)EF'                | 'CHIPR0402'    | ''          | ''            | '20190718'
 '53.6K'      | '1%'      | '1/16W'  | '0402LF'  | 'EMPTY'  | 'CS35362FB02'(!)        = 'End of Design' | 'Comp-Approve'     | 'CS35362FB02'           |'R0402'| '(R0402-0201)'                 | '53.6K'   | '1%'    | '1/16W'  | 'IO'       | 'RES CHIP 53.6K 1/16W +-1%(0402)EF'                | 'CHIPR0402'    | ''          | ''            | '20190718'
 '60.4K'      | '0.1%'    | '1/16W'  | '0402LF'  | 'CHIP'   | 'CS36042BB01'(!)        = ''              | ''                 | 'CS36042BB01'           |'R0402'| '(R0402-0201)'                 | '60.4K'   | '0.1%'  | '1/16W'  | 'DISCRETE' | 'RES CHIP 60.4K 1/16W +-0.1%(0402)EF'              | 'CHIPR0402'    | ''          | ''            | '20190718'
 '60.4K'      | '0.1%'    | '1/16W'  | '0402LF'  | 'EMPTY'  | 'CS36042BB01'(!)        = ''              | ''                 | 'CS36042BB01'           |'R0402'| '(R0402-0201)'                 | '60.4K'   | '0.1%'  | '1/16W'  | 'IO'       | 'RES CHIP 60.4K 1/16W +-0.1%(0402)EF'              | 'CHIPR0402'    | ''          | ''            | '20190718'
 '61.9K'      | '1%'      | '1/16W'  | '0402LF'  | 'CHIP'   | 'CS36192FB04'(!)        = 'End of Design' | 'Comp-Approve'     | 'CS36192FB04'           |'R0402'| '(R0402-0201)'                 | '61.9K'   | '1%'    | '1/16W'  | 'DISCRETE' | 'RES CHIP 61.9K 1/16W +-1%(0402)EF'                | 'CHIPR0402'    | ''          | ''            | '20190718'
 '61.9K'      | '1%'      | '1/16W'  | '0402LF'  | 'EMPTY'  | 'CS36192FB04'(!)        = 'End of Design' | 'Comp-Approve'     | 'CS36192FB04'           |'R0402'| '(R0402-0201)'                 | '61.9K'   | '1%'    | '1/16W'  | 'IO'       | 'RES CHIP 61.9K 1/16W +-1%(0402)EF'                | 'CHIPR0402'    | ''          | ''            | '20190718'
 '82K'        | '1%'      | '1/16W'  | '0402LF'  | 'CHIP'   | 'CS38202FB01'(!)        = 'End of Design' | 'Comp-Approve'     | 'CS38202FB01'           |'R0402'| '(R0402-0201)'                 | '82K'     | '1%'    | '1/16W'  | 'DISCRETE' | 'RES CHIP 82K  1/16W +-1% (0402)EF'                | 'CHIPR0402'    | ''          | ''            | '20190718'
 '82K'        | '1%'      | '1/16W'  | '0402LF'  | 'EMPTY'  | 'CS38202FB01'(!)        = 'End of Design' | 'Comp-Approve'     | 'CS38202FB01'           |'R0402'| '(R0402-0201)'                 | '82K'     | '1%'    | '1/16W'  | 'IO'       | 'RES CHIP 82K  1/16W +-1% (0402)EF'                | 'CHIPR0402'    | ''          | ''            | '20190718'
 '140K'       | '1%'      | '1/16W'  | '0402LF'  | 'CHIP'   | 'CS41402FB01'(!)        = 'End of Design' | 'Comp-Approve'     | 'CS41402FB01'           |'R0402'| '(R0402-0201)'                 | '140K'    | '1%'    | '1/16W'  | 'DISCRETE' | 'RES CHIP 140K 1/16W +-1%(0402)EF'                 | 'CHIPR0402'    | ''          | ''            | '20190718'
 '140K'       | '1%'      | '1/16W'  | '0402LF'  | 'EMPTY'  | 'CS41402FB01'(!)        = 'End of Design' | 'Comp-Approve'     | 'CS41402FB01'           |'R0402'| '(R0402-0201)'                 | '140K'    | '1%'    | '1/16W'  | 'IO'       | 'RES CHIP 140K 1/16W +-1%(0402)EF'                 | 'CHIPR0402'    | ''          | ''            | '20190718'
 '200K'       | '5%'      | '1/16W'  | '0402LF'  | 'CHIP'   | 'CS42002JB02'(!)        = 'End of Design' | 'Comp-Approve'     | 'CS42002JB02'           |'R0402'| '(R0402-0201)'                 | '200K'    | '5%'    | '1/16W'  | 'DISCRETE' | 'RES CHIP 200K 1/16W +-5%(0402)EF'                 | 'CHIPR0402'    | ''          | ''            | '20190718'
 '200K'       | '5%'      | '1/16W'  | '0402LF'  | 'EMPTY'  | 'CS42002JB02'(!)        = 'End of Design' | 'Comp-Approve'     | 'CS42002JB02'           |'R0402'| '(R0402-0201)'                 | '200K'    | '5%'    | '1/16W'  | 'IO'       | 'RES CHIP 200K 1/16W +-5%(0402)EF'                 | 'CHIPR0402'    | ''          | ''            | '20190718'
 '22.6K'      | '1%'      | '1/16W'  | '0402LF'  | 'CHIP'   | 'CS32262FB02'(!)        = 'End of Design' | 'Comp-Approve'     | 'CS32262FB02'           |'R0402'| '(R0402-0201)'                 | '22.6K'   | '1%'    | '1/16W'  | 'DISCRETE' | 'RES CHIP 22.6K 1/16W +-1%(0402)EF'                | 'CHIPR0402'    | ''          | ''            | '20190718'
 '22.6K'      | '1%'      | '1/16W'  | '0402LF'  | 'EMPTY'  | 'CS32262FB02'(!)        = 'End of Design' | 'Comp-Approve'     | 'CS32262FB02'           |'R0402'| '(R0402-0201)'                 | '22.6K'   | '1%'    | '1/16W'  | 'IO'       | 'RES CHIP 22.6K 1/16W +-1%(0402)EF'                | 'CHIPR0402'    | ''          | ''            | '20190718'
 '36.5K'      | '1%'      | '1/16W'  | '0402LF'  | 'CHIP'   | 'CS33652FB03'(!)        = 'End of Design' | 'Comp-Approve'     | 'CS33652FB03'           |'R0402'| '(R0402-0201)'                 | '36.5K'   | '1%'    | '1/16W'  | 'DISCRETE' | 'RES CHIP 36.5K 1/16W +-1%(0402)EF'                | 'CHIPR0402'    | ''          | ''            | '20190718'
 '36.5K'      | '1%'      | '1/16W'  | '0402LF'  | 'EMPTY'  | 'CS33652FB03'(!)        = 'End of Design' | 'Comp-Approve'     | 'CS33652FB03'           |'R0402'| '(R0402-0201)'                 | '36.5K'   | '1%'    | '1/16W'  | 'IO'       | 'RES CHIP 36.5K 1/16W +-1%(0402)EF'                | 'CHIPR0402'    | ''          | ''            | '20190718'
 '1'          | '1%'      | '1/2W'   | '1206LF'  | 'CHIP'   | 'CS-1007F201'(!)        = 'End of Design' | 'Comp-Approve'     | 'CS-1007F201'           |'R1206XI'| '(SMR1206AW)'                  | '1'       | '1%'    | '1/2W'   | 'DISCRETE' | 'RES CHIP 1 1/2W +-1%(1206)EF'                     | 'CHIPR1206'    | ''          | ''            | '20190722'
 '1'          | '1%'      | '1/2W'   | '1206LF'  | 'EMPTY'  | 'CS-1007F201'(!)        = 'End of Design' | 'Comp-Approve'     | 'CS-1007F201'           |'R1206XI'| '(SMR1206AW)'                  | '1'       | '1%'    | '1/2W'   | 'IO'       | 'RES CHIP 1 1/2W +-1%(1206)EF'                     | 'CHIPR1206'    | ''          | ''            | '20190722'
 '1'          | '1%'      | '1/4W'   | '1206LF'  | 'CHIP'   | 'CS-1006F203'(!)        = ''              | ''                 | 'CS-1006F203'           |'R1206XF'| '(SMR1206AW)'                  | '1'       | '1%'    | '1/4W'   | 'DISCRETE' | 'RES CHIP 1 1/4W +-1%(1206)EF'                     | 'CHIPR1206'    | ''          | ''            | '20190722'
 '1'          | '1%'      | '1/4W'   | '1206LF'  | 'EMPTY'  | 'CS-1006F203'(!)        = ''              | ''                 | 'CS-1006F203'           |'R1206XF'| '(SMR1206AW)'                  | '1'       | '1%'    | '1/4W'   | 'IO'       | 'RES CHIP 1 1/4W +-1%(1206)EF'                     | 'CHIPR1206'    | ''          | ''            | '20190722'
 '576'        | '1%'      | '1/16W'  | '0402LF'  | 'CHIP'   | 'CS15762FB03'(!)        = 'End of Design' | 'Comp-Approve'     | 'CS15762FB03'           |'R0402'| '(R0402-0201)'                 | '576'     | '1%'    | '1/16W'  | 'DISCRETE' | 'RES CHIP 576 1/16W +-1%(0402)EF'                  | 'CHIPR0402'    | ''          | ''            | '20190729'
 '576'        | '1%'      | '1/16W'  | '0402LF'  | 'EMPTY'  | 'CS15762FB03'(!)        = 'End of Design' | 'Comp-Approve'     | 'CS15762FB03'           |'R0402'| '(R0402-0201)'                 | '576'     | '1%'    | '1/16W'  | 'IO'       | 'RES CHIP 576 1/16W +-1%(0402)EF'                  | 'CHIPR0402'    | ''          | ''            | '20190729'
 '1.37K'      | '1%'      | '1/16W'  | '0402LF'  | 'CHIP'   | 'CS21372FB03'(!)        = 'End of Design' | 'Comp-Approve'     | 'CS21372FB03'           |'R0402'| '(R0402-0201)'                 | '1.37K'   | '1%'    | '1/16W'  | 'DISCRETE' | 'RES CHIP 1.37K 1/16W +-1%(0402)EF'                | 'CHIPR0402'    | ''          | ''            | '20190729'
 '1.37K'      | '1%'      | '1/16W'  | '0402LF'  | 'EMPTY'  | 'CS21372FB03'(!)        = 'End of Design' | 'Comp-Approve'     | 'CS21372FB03'           |'R0402'| '(R0402-0201)'                 | '1.37K'   | '1%'    | '1/16W'  | 'IO'       | 'RES CHIP 1.37K 1/16W +-1%(0402)EF'                | 'CHIPR0402'    | ''          | ''            | '20190729'
 '27'         | '5%'      | '1/16W'  | '0402LF'  | 'CHIP'   | 'CS02702JB02'(!)        = 'End of Design' | 'Comp-Approve'     | 'CS02702JB02'           |'R0402'| '(R0402-0201)'                 | '27'      | '5%'    | '1/16W'  | 'DISCRETE' | 'RES CHIP 27 1/16W +-5%(0402)EF'                   | 'CHIPR0402'    | ''          | ''            | '20190729'
 '27'         | '5%'      | '1/16W'  | '0402LF'  | 'EMPTY'  | 'CS02702JB02'(!)        = 'End of Design' | 'Comp-Approve'     | 'CS02702JB02'           |'R0402'| '(R0402-0201)'                 | '27'      | '5%'    | '1/16W'  | 'IO'       | 'RES CHIP 27 1/16W +-5%(0402)EF'                   | 'CHIPR0402'    | ''          | ''            | '20190729'
 '43.2'       | '1%'      | '1/16W'  | '0402LF'  | 'CHIP'   | 'CS04322FB01'(!)        = 'End of Design' | 'Comp-Approve'     | 'CS04322FB01'           |'R0402'| '(R0402-0201)'                 | '43.2'    | '1%'    | '1/16W'  | 'DISCRETE' | 'RES CHIP 43.2 1/16W +-1%(0402)EF'                 | 'CHIPR0402'    | ''          | ''            | '20190729'
 '43.2'       | '1%'      | '1/16W'  | '0402LF'  | 'EMPTY'  | 'CS04322FB01'(!)        = 'End of Design' | 'Comp-Approve'     | 'CS04322FB01'           |'R0402'| '(R0402-0201)'                 | '43.2'    | '1%'    | '1/16W'  | 'IO'       | 'RES CHIP 43.2 1/16W +-1%(0402)EF'                 | 'CHIPR0402'    | ''          | ''            | '20190729'
 '100'        | '5%'      | '1/16W'  | '0402LF'  | 'CHIP'   | 'CS11002JB06'(!)        = 'End of Design' | 'Comp-Approve'     | 'CS11002JB06'           |'R0402'| '(R0402-0201)'                 | '100'     | '5%'    | '1/16W'  | 'DISCRETE' | 'RES CHIP 100 1/16W +-5%(0402)EF'                  | 'CHIPR0402'    | ''          | ''            | '20190729'
 '100'        | '5%'      | '1/16W'  | '0402LF'  | 'EMPTY'  | 'CS11002JB06'(!)        = 'End of Design' | 'Comp-Approve'     | 'CS11002JB06'           |'R0402'| '(R0402-0201)'                 | '100'     | '5%'    | '1/16W'  | 'IO'       | 'RES CHIP 100 1/16W +-5%(0402)EF'                  | 'CHIPR0402'    | ''          | ''            | '20190729'
 '4.7K'       | '5%'      | '1/16W'  | '0402LF'  | 'CHIP'   | 'CS24702JB10'(!)        = 'End of Design' | 'Comp-Approve'     | 'CS24702JB10'           |'R0402'| '(R0402-0201)'                 | '4.7K'    | '5%'    | '1/16W'  | 'DISCRETE' | 'RES CHIP 4.7K 1/16W +-5%(0402)EF'                 | 'CHIPR0402'    | ''          | ''            | '20190729'
 '4.7K'       | '5%'      | '1/16W'  | '0402LF'  | 'EMPTY'  | 'CS24702JB10'(!)        = 'End of Design' | 'Comp-Approve'     | 'CS24702JB10'           |'R0402'| '(R0402-0201)'                 | '4.7K'    | '5%'    | '1/16W'  | 'IO'       | 'RES CHIP 4.7K 1/16W +-5%(0402)EF'                 | 'CHIPR0402'    | ''          | ''            | '20190729'
 '5.11K'      | '1%'      | '1/16W'  | '0402LF'  | 'CHIP'   | 'CS25112FB04'(!)        = 'End of Design' | 'Comp-Approve'     | 'CS25112FB04'           |'R0402'| '(R0402-0201)'                 | '5.11K'   | '1%'    | '1/16W'  | 'DISCRETE' | 'RES CHIP 5.11K 1/16W +-1%(0402)EF'                | 'CHIPR0402'    | ''          | ''            | '20190726'
 '5.11K'      | '1%'      | '1/16W'  | '0402LF'  | 'EMPTY'  | 'CS25112FB04'(!)        = 'End of Design' | 'Comp-Approve'     | 'CS25112FB04'           |'R0402'| '(R0402-0201)'                 | '5.11K'   | '1%'    | '1/16W'  | 'IO'       | 'RES CHIP 5.11K 1/16W +-1%(0402)EF'                | 'CHIPR0402'    | ''          | ''            | '20190726'
 '82.5K'      | '1%'      | '1/16W'  | '0402LF'  | 'CHIP'   | 'CS38252FB01'(!)        = ''              | ''                 | 'CS38252FB01'           |'R0402'| '(R0402-0201)'                 | '82.5K'   | '1%'    | '1/16W'  | 'DISCRETE' | 'RES CHIP 82.5K 1/16W +-1%(0402)EF'                | 'CHIPR0402'    | ''          | ''            | '20190730'
 '82.5K'      | '1%'      | '1/16W'  | '0402LF'  | 'EMPTY'  | 'CS38252FB01'(!)        = ''              | ''                 | 'CS38252FB01'           |'R0402'| '(R0402-0201)'                 | '82.5K'   | '1%'    | '1/16W'  | 'IO'       | 'RES CHIP 82.5K 1/16W +-1%(0402)EF'                | 'CHIPR0402'    | ''          | ''            | '20190730'
 '17.8K'      | '1%'      | '1/16W'  | '0402LF'  | 'CHIP'   | 'CS31782FB04'(!)        = 'End of Design' | 'Comp-Approve'     | 'CS31782FB04'           |'R0402'| '(R0402-0201)'                 | '17.8K'   | '1%'    | '1/16W'  | 'DISCRETE' | 'RES CHIP 17.8K 1/16W +- 1% (0402)EF'              | 'CHIPR0402'    | ''          | ''            | '20190730'
 '17.8K'      | '1%'      | '1/16W'  | '0402LF'  | 'EMPTY'  | 'CS31782FB04'(!)        = 'End of Design' | 'Comp-Approve'     | 'CS31782FB04'           |'R0402'| '(R0402-0201)'                 | '17.8K'   | '1%'    | '1/16W'  | 'IO'       | 'RES CHIP 17.8K 1/16W +- 1% (0402)EF'              | 'CHIPR0402'    | ''          | ''            | '20190730'
 '953'        | '1%'      | '1/10W'  | '0603LF'  | 'CHIP'   | 'CS19533F901'(!)        = 'End of Design' | 'Comp-Approve'     | 'CS19533F901'           |'R0603_H24'| '(SMR0603AW)'                  | '953'     | '1%'    | '1/10W'  | 'DISCRETE' | 'RES CHIP 953 1/10W +-1%(0603)EF'                  | 'CHIPR0603'    | ''          | ''            | '20190730'
 '953'        | '1%'      | '1/10W'  | '0603LF'  | 'EMPTY'  | 'CS19533F901'(!)        = 'End of Design' | 'Comp-Approve'     | 'CS19533F901'           |'R0603_H24'| '(SMR0603AW)'                  | '953'     | '1%'    | '1/10W'  | 'IO'       | 'RES CHIP 953 1/10W +-1%(0603)EF'                  | 'CHIPR0603'    | ''          | ''            | '20190730'
 '1.6K'       | '1%'      | '1/10W'  | '0603LF'  | 'CHIP'   | 'CS21603F900'(!)        = 'End of Design' | 'Comp-Approve'     | 'CS21603F900'           |'R0603_H24'| '(SMR0603AW)'                  | '1.6K'    | '1%'    | '1/10W'  | 'DISCRETE' | 'RES CHIP 1.6K 1/10W +-1% (0603)EF'                | 'CHIPR0603'    | ''          | ''            | '20190731'
 '1.6K'       | '1%'      | '1/10W'  | '0603LF'  | 'EMPTY'  | 'CS21603F900'(!)        = 'End of Design' | 'Comp-Approve'     | 'CS21603F900'           |'R0603_H24'| '(SMR0603AW)'                  | '1.6K'    | '1%'    | '1/10W'  | 'IO'       | 'RES CHIP 1.6K 1/10W +-1% (0603)EF'                | 'CHIPR0603'    | ''          | ''            | '20190731'
 '681K'       | '1%'      | '1/16W'  | '0402LF'  | 'CHIP'   | 'CS46812FB06'(!)        = ''              | ''                 | 'CS46812FB06'           |'R0402'| '(R0402-0201)'                 | '681K'    | '1%'    | '1/16W'  | 'DISCRETE' | 'RES CHIP 681K 1/16W +-1%(0402)EF'                 | 'CHIPR0402'    | ''          | ''            | '20190731'
 '681K'       | '1%'      | '1/16W'  | '0402LF'  | 'EMPTY'  | 'CS46812FB06'(!)        = ''              | ''                 | 'CS46812FB06'           |'R0402'| '(R0402-0201)'                 | '681K'    | '1%'    | '1/16W'  | 'IO'       | 'RES CHIP 681K 1/16W +-1%(0402)EF'                 | 'CHIPR0402'    | ''          | ''            | '20190731'
 '0.004'      | '1%'      | '1W'     | '1206LF'  | 'CHIP'   | 'CS+0048F201'(!)        = 'End of Design' | 'Comp-Release Qty' | 'CS+0048F201'           |'R1206XD_H36'| '(SMR1206AW)'                  | '0.004'   | '1%'    | '1W'     | 'DISCRETE' | 'RES CHIP 0.004 1W +-1%(1206)EF'                   | 'CHIPR1206'    | ''          | ''            | '20190731'
 '0.004'      | '1%'      | '1W'     | '1206LF'  | 'EMPTY'  | 'CS+0048F201'(!)        = 'End of Design' | 'Comp-Release Qty' | 'CS+0048F201'           |'R1206XD_H36'| '(SMR1206AW)'                  | '0.004'   | '1%'    | '1W'     | 'IO'       | 'RES CHIP 0.004 1W +-1%(1206)EF'                   | 'CHIPR1206'    | ''          | ''            | '20190731'
 '1.5K'       | '0.1%'    | '1/16W'  | '0402LF'  | 'CHIP'   | 'CS21502BB00'(!)        = ''              | ''                 | 'CS21502BB00'           |'R0402'| '(R0402-0201)'                 | '1.5K'    | '0.1%'  | '1/16W'  | 'DISCRETE' | 'RES CHIP 1.5K 1/16W +-0.1% (0402)'                | 'CHIPR0402'    | ''          | ''            | '20190801'
 '1.5K'       | '0.1%'    | '1/16W'  | '0402LF'  | 'EMPTY'  | 'CS21502BB00'(!)        = ''              | ''                 | 'CS21502BB00'           |'R0402'| '(R0402-0201)'                 | '1.5K'    | '0.1%'  | '1/16W'  | 'IO'       | 'RES CHIP 1.5K 1/16W +-0.1% (0402)'                | 'CHIPR0402'    | ''          | ''            | '20190801'
 '56K'        | '0.1%'    | '1/16W'  | '0402LF'  | 'CHIP'   | 'CS35602BB00'(!)        = ''              | ''                 | 'CS35602BB00'           |'R0402'| '(R0402-0201)'                 | '56K'     | '0.1%'  | '1/16W'  | 'DISCRETE' | 'RES CHIP 56K 1/16W +-0.1%(0402)'                  | 'CHIPR0402'    | ''          | ''            | '20190821'
 '56K'        | '0.1%'    | '1/16W'  | '0402LF'  | 'EMPTY'  | 'CS35602BB00'(!)        = ''              | ''                 | 'CS35602BB00'           |'R0402'| '(R0402-0201)'                 | '56K'     | '0.1%'  | '1/16W'  | 'IO'       | 'RES CHIP 56K 1/16W +-0.1%(0402)'                  | 'CHIPR0402'    | ''          | ''            | '20190821'
 '7.87K'      | '1%'      | '1/16W'  | '0402LF'  | 'CHIP'   | 'CS27872FB02'(!)        = 'End of Design' | 'Comp-Approve'     | 'CS27872FB02'           |'R0402'| '(R0402-0201)'                 | '7.87K'   | '1%'    | '1/16W'  | 'DISCRETE' | 'RES CHIP 7.87K 1/16W +-1%(0402)EF'                | 'CHIPR0402'    | ''          | ''            | '20190820'
 '7.87K'      | '1%'      | '1/16W'  | '0402LF'  | 'EMPTY'  | 'CS27872FB02'(!)        = 'End of Design' | 'Comp-Approve'     | 'CS27872FB02'           |'R0402'| '(R0402-0201)'                 | '7.87K'   | '1%'    | '1/16W'  | 'IO'       | 'RES CHIP 7.87K 1/16W +-1%(0402)EF'                | 'CHIPR0402'    | ''          | ''            | '20190820'
 '13.3K'      | '1%'      | '1/16W'  | '0402LF'  | 'CHIP'   | 'CS31332FB02'(!)        = 'End of Design' | 'Comp-Approve'     | 'CS31332FB02'           |'R0402'| '(R0402-0201)'                 | '13.3K'   | '1%'    | '1/16W'  | 'DISCRETE' | 'RES CHIP 13.3K 1/16W +-1%(0402)EF'                | 'CHIPR0402'    | ''          | ''            | '20190820'
 '13.3K'      | '1%'      | '1/16W'  | '0402LF'  | 'EMPTY'  | 'CS31332FB02'(!)        = 'End of Design' | 'Comp-Approve'     | 'CS31332FB02'           |'R0402'| '(R0402-0201)'                 | '13.3K'   | '1%'    | '1/16W'  | 'IO'       | 'RES CHIP 13.3K 1/16W +-1%(0402)EF'                | 'CHIPR0402'    | ''          | ''            | '20190820'
 '1.47K'      | '1%'      | '1/16W'  | '0402LF'  | 'CHIP'   | 'CS21472FB02'(!)        = 'End of Design' | 'Comp-Approve'     | 'CS21472FB02'           |'R0402'| '(R0402-0201)'                 | '1.47K'   | '1%'    | '1/16W'  | 'DISCRETE' | 'RES CHIP 1.47K 1/16W +-1%(0402)EF'                | 'CHIPR0402'    | ''          | ''            | '20190821'
 '1.47K'      | '1%'      | '1/16W'  | '0402LF'  | 'EMPTY'  | 'CS21472FB02'(!)        = 'End of Design' | 'Comp-Approve'     | 'CS21472FB02'           |'R0402'| '(R0402-0201)'                 | '1.47K'   | '1%'    | '1/16W'  | 'IO'       | 'RES CHIP 1.47K 1/16W +-1%(0402)EF'                | 'CHIPR0402'    | ''          | ''            | '20190821'
 '76.8K'      | '1%'      | '1/20W'  | '0201LF'  | 'CHIP'   | 'CS37681FE01'(!)        = ''              | ''                 | 'CS37681FE01'           |'R0201'| '(SMR0201AW)'                  | '76.8K'   | '1%'    | '1/20W'  | 'DISCRETE' | 'RES CHIP 76.8K 1/20W +-1%(0201)YGOSELASN'         | 'CHIPR0201'    | ''          | ''            | '20190821'
 '76.8K'      | '1%'      | '1/20W'  | '0201LF'  | 'EMPTY'  | 'CS37681FE01'(!)        = ''              | ''                 | 'CS37681FE01'           |'R0201'| '(SMR0201AW)'                  | '76.8K'   | '1%'    | '1/20W'  | 'IO'       | 'RES CHIP 76.8K 1/20W +-1%(0201)YGOSELASN'         | 'CHIPR0201'    | ''          | ''            | '20190821'
 '17.4K'      | '1%'      | '1/16W'  | '0402LF'  | 'CHIP'   | 'CS31742FB04'(!)        = 'End of Design' | 'Comp-Approve'     | 'CS31742FB04'           |'R0402'| '(R0402-0201)'                 | '17.4K'   | '1%'    | '1/16W'  | 'DISCRETE' | 'RES CHIP 17.4K 1/16W +-1%(0402)EF'                | 'CHIPR0402'    | ''          | ''            | '20190826'
 '17.4K'      | '1%'      | '1/16W'  | '0402LF'  | 'EMPTY'  | 'CS31742FB04'(!)        = 'End of Design' | 'Comp-Approve'     | 'CS31742FB04'           |'R0402'| '(R0402-0201)'                 | '17.4K'   | '1%'    | '1/16W'  | 'IO'       | 'RES CHIP 17.4K 1/16W +-1%(0402)EF'                | 'CHIPR0402'    | ''          | ''            | '20190826'
 '0.15'       | '1%'      | '1/2W'   | '1206LF'  | 'CHIP'   | 'CS+1507F200'(!)        = ''              | ''                 | 'CS+1507F200'           |'R1206XF'| '(SMR1206AW)'                  | '0.15'    | '1%'    | '1/2W'   | 'DISCRETE' | 'RES CHIP 0.15 1/2W +-1%(1206)'                    | 'CHIPR1206'    | ''          | ''            | '20190829'
 '0.15'       | '1%'      | '1/2W'   | '1206LF'  | 'EMPTY'  | 'CS+1507F200'(!)        = ''              | ''                 | 'CS+1507F200'           |'R1206XF'| '(SMR1206AW)'                  | '0.15'    | '1%'    | '1/2W'   | 'IO'       | 'RES CHIP 0.15 1/2W +-1%(1206)'                    | 'CHIPR1206'    | ''          | ''            | '20190829'
 '680'        | '1%'      | '1/16W'  | '0402LF'  | 'CHIP'   | 'CS16802FB03'(!)        = ''              | ''                 | 'CS16802FB03'           |'R0402'| '(R0402-0201)'                 | '680'     | '1%'    | '1/16W'  | 'DISCRETE' | 'RES CHIP 680 1/16W +-1%(0402)EF'                  | 'CHIPR0402'    | ''          | ''            | '20190829'
 '680'        | '1%'      | '1/16W'  | '0402LF'  | 'EMPTY'  | 'CS16802FB03'(!)        = ''              | ''                 | 'CS16802FB03'           |'R0402'| '(R0402-0201)'                 | '680'     | '1%'    | '1/16W'  | 'IO'       | 'RES CHIP 680 1/16W +-1%(0402)EF'                  | 'CHIPR0402'    | ''          | ''            | '20190829'
 '3.57K'      | '1%'      | '1/16W'  | '0402LF'  | 'CHIP'   | 'CS23572FB05'(!)        = 'End of Design' | 'Comp-Approve'     | 'CS23572FB05'           |'R0402'| '(R0402-0201)'                 | '3.57K'   | '1%'    | '1/16W'  | 'DISCRETE' | 'RES CHIP 3.57K 1/16W +-1%(0402)EF'                | 'CHIPR0402'    | ''          | ''            | '20190829'
 '3.57K'      | '1%'      | '1/16W'  | '0402LF'  | 'EMPTY'  | 'CS23572FB05'(!)        = 'End of Design' | 'Comp-Approve'     | 'CS23572FB05'           |'R0402'| '(R0402-0201)'                 | '3.57K'   | '1%'    | '1/16W'  | 'IO'       | 'RES CHIP 3.57K 1/16W +-1%(0402)EF'                | 'CHIPR0402'    | ''          | ''            | '20190829'
 '76.8K'      | '1%'      | '1/20W'  | '0201LF'  | 'CHIP'   | 'CS37681FE06'(!)        = ''              | ''                 | 'CS37681FE06'           |'R0201'| '(SMR0201AW)'                  | '76.8K'   | '1%'    | '1/20W'  | 'DISCRETE' | 'RES CHIP 76.8K 1/20W +-1%(0201)'                  | 'CHIPR0201'    | ''          | ''            | '20190829'
 '76.8K'      | '1%'      | '1/20W'  | '0201LF'  | 'EMPTY'  | 'CS37681FE06'(!)        = ''              | ''                 | 'CS37681FE06'           |'R0201'| '(SMR0201AW)'                  | '76.8K'   | '1%'    | '1/20W'  | 'IO'       | 'RES CHIP 76.8K 1/20W +-1%(0201)'                  | 'CHIPR0201'    | ''          | ''            | '20190829'
 '0.003'      | '1%'      | '1W'     | '1206LF'  | 'CHIP'   | 'CS+0038F203'(!)        = ''              | ''                 | 'CS+0038F203'           |'R1206XK'| '(SMR1206AW)'                  | '0.003'   | '1%'    | '1W'     | 'DISCRETE' | 'RES CHIP 0.003 1W +-1%(1206)'                     | 'CHIPR1206'    | ''          | ''            | '20190828'
 '0.003'      | '1%'      | '1W'     | '1206LF'  | 'EMPTY'  | 'CS+0038F203'(!)        = ''              | ''                 | 'CS+0038F203'           |'R1206XK'| '(SMR1206AW)'                  | '0.003'   | '1%'    | '1W'     | 'IO'       | 'RES CHIP 0.003 1W +-1%(1206)'                     | 'CHIPR1206'    | ''          | ''            | '20190828'
 '1.1M'       | '1%'      | '1/8W'   | '0805LF'  | 'CHIP'   | 'CS51104FA00'(!)        = ''              | ''                 | 'CS51104FA00'           |'R0805'| '(SMR0805AW)'                  | '1.1M'    | '1%'    | '1/8W'   | 'DISCRETE' | 'RES CHIP 1.1M 1/8W +-1%(0805)'                    | 'CHIPR0805'    | ''          | ''            | '20190826'
 '1.1M'       | '1%'      | '1/8W'   | '0805LF'  | 'EMPTY'  | 'CS51104FA00'(!)        = ''              | ''                 | 'CS51104FA00'           |'R0805'| '(SMR0805AW)'                  | '1.1M'    | '1%'    | '1/8W'   | 'IO'       | 'RES CHIP 1.1M 1/8W +-1%(0805)'                    | 'CHIPR0805'    | ''          | ''            | '20190826'
 '28.7K'      | '1%'      | '1/10W'  | '0603LF'  | 'CHIP'   | 'CS32873F918'(!)        = ''              | ''                 | 'CS32873F918'           |'R0603'| '(SMR0603AW)'                  | '28.7K'   | '1%'    | '1/10W'  | 'DISCRETE' | 'RESISTOR CHIP 28.7K 1/10W+-1%(0603)'              | 'CHIPR0603'    | ''          | ''            | '20190830'
 '28.7K'      | '1%'      | '1/10W'  | '0603LF'  | 'EMPTY'  | 'CS32873F918'(!)        = ''              | ''                 | 'CS32873F918'           |'R0603'| '(SMR0603AW)'                  | '28.7K'   | '1%'    | '1/10W'  | 'IO'       | 'RESISTOR CHIP 28.7K 1/10W+-1%(0603)'              | 'CHIPR0603'    | ''          | ''            | '20190830'
 '20'         | '5%'      | '1/16W'  | '0402LF'  | 'CHIP'   | 'CS02002JB02'(!)        = ''              | ''                 | 'CS02002JB02'           |'R0402'| '(R0402-0201)'                 | '20'      | '5%'    | '1/16W'  | 'DISCRETE' | 'RES CHIP 20 1/16W +-5%(0402)EF'                   | 'CHIPR0402'    | ''          | ''            | '20190904'
 '20'         | '5%'      | '1/16W'  | '0402LF'  | 'EMPTY'  | 'CS02002JB02'(!)        = ''              | ''                 | 'CS02002JB02'           |'R0402'| '(R0402-0201)'                 | '20'      | '5%'    | '1/16W'  | 'IO'       | 'RES CHIP 20 1/16W +-5%(0402)EF'                   | 'CHIPR0402'    | ''          | ''            | '20190904'
 '30.1'       | '1%'      | '1/10W'  | '0603LF'  | 'CHIP'   | 'CS03013F902'(!)        = 'End of Design' | 'Comp-Release Qty' | 'CS03013F902'           |'R0603_H24'| '(SMR0603AW)'                  | '30.1'    | '1%'    | '1/10W'  | 'DISCRETE' | 'RES CHIP 30.1 1/10W +-1%(0603)EF'                 | 'CHIPR0603'    | ''          | ''            | '20190904'
 '30.1'       | '1%'      | '1/10W'  | '0603LF'  | 'EMPTY'  | 'CS03013F902'(!)        = 'End of Design' | 'Comp-Release Qty' | 'CS03013F902'           |'R0603_H24'| '(SMR0603AW)'                  | '30.1'    | '1%'    | '1/10W'  | 'IO'       | 'RES CHIP 30.1 1/10W +-1%(0603)EF'                 | 'CHIPR0603'    | ''          | ''            | '20190904'
 '33'         | '5%'      | '1/16W'  | '0402LF'  | 'CHIP'   | 'CS03302JB10'(!)        = 'End of Design' | 'Comp-Approve'     | 'CS03302JB10'           |'R0402'| '(R0402-0201)'                 | '33'      | '5%'    | '1/16W'  | 'DISCRETE' | 'RES CHIP 33 1/16W +-5%(0402)EF'                   | 'CHIPR0402'    | ''          | ''            | '20190904'
 '33'         | '5%'      | '1/16W'  | '0402LF'  | 'EMPTY'  | 'CS03302JB10'(!)        = 'End of Design' | 'Comp-Approve'     | 'CS03302JB10'           |'R0402'| '(R0402-0201)'                 | '33'      | '5%'    | '1/16W'  | 'IO'       | 'RES CHIP 33 1/16W +-5%(0402)EF'                   | 'CHIPR0402'    | ''          | ''            | '20190904'
 '1'          | '1%'      | '1/10W'  | '0603LF'  | 'CHIP'   | 'CS-1003F900'(!)        = 'End of Design' | 'Comp-Approve'     | 'CS-1003F900'           |'R0603_H24'| '(SMR0603AW)'                  | '1'       | '1%'    | '1/10W'  | 'DISCRETE' | 'RES CHIP 1 1/10W +-1%(0603)EF'                    | 'CHIPR0603'    | ''          | ''            | '20190904'
 '1'          | '1%'      | '1/10W'  | '0603LF'  | 'EMPTY'  | 'CS-1003F900'(!)        = 'End of Design' | 'Comp-Approve'     | 'CS-1003F900'           |'R0603_H24'| '(SMR0603AW)'                  | '1'       | '1%'    | '1/10W'  | 'IO'       | 'RES CHIP 1 1/10W +-1%(0603)EF'                    | 'CHIPR0603'    | ''          | ''            | '20190904'
 '165'        | '1%'      | '1/16W'  | '0402LF'  | 'CHIP'   | 'CS11652FB03'(!)        = 'End of Design' | 'Comp-Approve'     | 'CS11652FB03'           |'R0402'| '(R0402-0201)'                 | '165'     | '1%'    | '1/16W'  | 'DISCRETE' | 'RES CHIP 165 1/16W +-1%(0402)EF'                  | 'CHIPR0402'    | ''          | ''            | '20190904'
 '165'        | '1%'      | '1/16W'  | '0402LF'  | 'EMPTY'  | 'CS11652FB03'(!)        = 'End of Design' | 'Comp-Approve'     | 'CS11652FB03'           |'R0402'| '(R0402-0201)'                 | '165'     | '1%'    | '1/16W'  | 'IO'       | 'RES CHIP 165 1/16W +-1%(0402)EF'                  | 'CHIPR0402'    | ''          | ''            | '20190904'
 '249'        | '1%'      | '1/16W'  | '0402LF'  | 'CHIP'   | 'CS12492FB02'(!)        = 'End of Design' | 'Comp-Approve'     | 'CS12492FB02'           |'R0402'| '(R0402-0201)'                 | '249'     | '1%'    | '1/16W'  | 'DISCRETE' | 'RES CHIP 249 1/16W +-1%(0402)EF'                  | 'CHIPR0402'    | ''          | ''            | '20190904'
 '249'        | '1%'      | '1/16W'  | '0402LF'  | 'EMPTY'  | 'CS12492FB02'(!)        = 'End of Design' | 'Comp-Approve'     | 'CS12492FB02'           |'R0402'| '(R0402-0201)'                 | '249'     | '1%'    | '1/16W'  | 'IO'       | 'RES CHIP 249 1/16W +-1%(0402)EF'                  | 'CHIPR0402'    | ''          | ''            | '20190904'
 '249'        | '0.1%'    | '1/10W'  | '0603LF'  | 'CHIP'   | 'CS12493B901'(!)        = ''              | ''                 | 'CS12493B901'           |'R0603_H24'| '(SMR0603AW)'                  | '249'     | '0.1%'  | '1/10W'  | 'DISCRETE' | 'RES CHIP 249 1/10W +-0.1%(0603)EF'                | 'CHIPR0603'    | ''          | ''            | '20190905'
 '249'        | '0.1%'    | '1/10W'  | '0603LF'  | 'EMPTY'  | 'CS12493B901'(!)        = ''              | ''                 | 'CS12493B901'           |'R0603_H24'| '(SMR0603AW)'                  | '249'     | '0.1%'  | '1/10W'  | 'IO'       | 'RES CHIP 249 1/10W +-0.1%(0603)EF'                | 'CHIPR0603'    | ''          | ''            | '20190905'
 '301'        | '1%'      | '1/16W'  | '0402LF'  | 'CHIP'   | 'CS13012FB02'(!)        = 'End of Design' | 'Comp-Approve'     | 'CS13012FB02'           |'R0402'| '(R0402-0201)'                 | '301'     | '1%'    | '1/16W'  | 'DISCRETE' | 'RES CHIP 301 1/16W +-1%(0402)EF'                  | 'CHIPR0402'    | ''          | ''            | '20190904'
 '301'        | '1%'      | '1/16W'  | '0402LF'  | 'EMPTY'  | 'CS13012FB02'(!)        = 'End of Design' | 'Comp-Approve'     | 'CS13012FB02'           |'R0402'| '(R0402-0201)'                 | '301'     | '1%'    | '1/16W'  | 'IO'       | 'RES CHIP 301 1/16W +-1%(0402)EF'                  | 'CHIPR0402'    | ''          | ''            | '20190904'
 '383'        | '1%'      | '1/16W'  | '0402LF'  | 'CHIP'   | 'CS13832FB03'(!)        = 'End of Design' | 'Comp-Approve'     | 'CS13832FB03'           |'R0402'| '(R0402-0201)'                 | '383'     | '1%'    | '1/16W'  | 'DISCRETE' | 'RES CHIP 383 1/16W +-1%(0402)EF'                  | 'CHIPR0402'    | ''          | ''            | '20190904'
 '383'        | '1%'      | '1/16W'  | '0402LF'  | 'EMPTY'  | 'CS13832FB03'(!)        = 'End of Design' | 'Comp-Approve'     | 'CS13832FB03'           |'R0402'| '(R0402-0201)'                 | '383'     | '1%'    | '1/16W'  | 'IO'       | 'RES CHIP 383 1/16W +-1%(0402)EF'                  | 'CHIPR0402'    | ''          | ''            | '20190904'
 '510'        | '5%'      | '1/16W'  | '0402LF'  | 'CHIP'   | 'CS15102JB04'(!)        = ''              | ''                 | 'CS15102JB04'           |'R0402'| '(R0402-0201)'                 | '510'     | '5%'    | '1/16W'  | 'DISCRETE' | 'RES CHIP 510 1/16W +-5%(0402)EF'                  | 'CHIPR0402'    | ''          | ''            | '20190904'
 '510'        | '5%'      | '1/16W'  | '0402LF'  | 'EMPTY'  | 'CS15102JB04'(!)        = ''              | ''                 | 'CS15102JB04'           |'R0402'| '(R0402-0201)'                 | '510'     | '5%'    | '1/16W'  | 'IO'       | 'RES CHIP 510 1/16W +-5%(0402)EF'                  | 'CHIPR0402'    | ''          | ''            | '20190904'
 '523'        | '1%'      | '1/16W'  | '0402LF'  | 'CHIP'   | 'CS15232FB03'(!)        = ''              | ''                 | 'CS15232FB03'           |'R0402'| '(R0402-0201)'                 | '523'     | '1%'    | '1/16W'  | 'DISCRETE' | 'RES CHIP 523 1/16W +-1%(0402)EF'                  | 'CHIPR0402'    | ''          | ''            | '20190904'
 '523'        | '1%'      | '1/16W'  | '0402LF'  | 'EMPTY'  | 'CS15232FB03'(!)        = ''              | ''                 | 'CS15232FB03'           |'R0402'| '(R0402-0201)'                 | '523'     | '1%'    | '1/16W'  | 'IO'       | 'RES CHIP 523 1/16W +-1%(0402)EF'                  | 'CHIPR0402'    | ''          | ''            | '20190904'
 '560'        | '1%'      | '1/16W'  | '0402LF'  | 'CHIP'   | 'CS15602FB03'(!)        = ''              | ''                 | 'CS15602FB03'           |'R0402'| '(R0402-0201)'                 | '560'     | '1%'    | '1/16W'  | 'DISCRETE' | 'RES CHIP 560 1/16W +-1%(0402)EF'                  | 'CHIPR0402'    | ''          | ''            | '20190904'
 '560'        | '1%'      | '1/16W'  | '0402LF'  | 'EMPTY'  | 'CS15602FB03'(!)        = ''              | ''                 | 'CS15602FB03'           |'R0402'| '(R0402-0201)'                 | '560'     | '1%'    | '1/16W'  | 'IO'       | 'RES CHIP 560 1/16W +-1%(0402)EF'                  | 'CHIPR0402'    | ''          | ''            | '20190904'
 '562'        | '1%'      | '1/16W'  | '0402LF'  | 'CHIP'   | 'CS15622FB01'(!)        = 'End of Design' | 'Comp-Approve'     | 'CS15622FB01'           |'R0402'| '(R0402-0201)'                 | '562'     | '1%'    | '1/16W'  | 'DISCRETE' | 'RES CHIP 562 1/16W +-1% (0402)EF'                 | 'CHIPR0402'    | ''          | ''            | '20190904'
 '562'        | '1%'      | '1/16W'  | '0402LF'  | 'EMPTY'  | 'CS15622FB01'(!)        = 'End of Design' | 'Comp-Approve'     | 'CS15622FB01'           |'R0402'| '(R0402-0201)'                 | '562'     | '1%'    | '1/16W'  | 'IO'       | 'RES CHIP 562 1/16W +-1% (0402)EF'                 | 'CHIPR0402'    | ''          | ''            | '20190904'
 '750'        | '1%'      | '1/20W'  | '0201LF'  | 'CHIP'   | 'CS17501FE11'(!)        = ''              | ''                 | 'CS17501FE11'           |'R0201'| '(SMR0201AW)'                  | '750'     | '1%'    | '1/20W'  | 'DISCRETE' | 'RES CHIP 750 1/20W +-1%(0201)EF'                  | 'CHIPR0201'    | ''          | ''            | '20190904'
 '750'        | '1%'      | '1/20W'  | '0201LF'  | 'EMPTY'  | 'CS17501FE11'(!)        = ''              | ''                 | 'CS17501FE11'           |'R0201'| '(SMR0201AW)'                  | '750'     | '1%'    | '1/20W'  | 'IO'       | 'RES CHIP 750 1/20W +-1%(0201)EF'                  | 'CHIPR0201'    | ''          | ''            | '20190904'
 '887'        | '1%'      | '1/16W'  | '0402LF'  | 'CHIP'   | 'CS18872FB02'(!)        = 'End of Design' | 'Comp-Approve'     | 'CS18872FB02'           |'R0402'| '(R0402-0201)'                 | '887'     | '1%'    | '1/16W'  | 'DISCRETE' | 'RES CHIP 887 1/16W +-1%(0402)EF'                  | 'CHIPR0402'    | ''          | ''            | '20190905'
 '887'        | '1%'      | '1/16W'  | '0402LF'  | 'EMPTY'  | 'CS18872FB02'(!)        = 'End of Design' | 'Comp-Approve'     | 'CS18872FB02'           |'R0402'| '(R0402-0201)'                 | '887'     | '1%'    | '1/16W'  | 'IO'       | 'RES CHIP 887 1/16W +-1%(0402)EF'                  | 'CHIPR0402'    | ''          | ''            | '20190905'
 '1.18K'      | '1%'      | '1/16W'  | '0402LF'  | 'CHIP'   | 'CS21182FB01'(!)        = 'End of Design' | 'Comp-Approve'     | 'CS21182FB01'           |'R0402'| '(R0402-0201)'                 | '1.18K'   | '1%'    | '1/16W'  | 'DISCRETE' | 'RES CHIP 1.18K 1/16W +-1%(0402)EF'                | 'CHIPR0402'    | ''          | ''            | '20190905'
 '1.18K'      | '1%'      | '1/16W'  | '0402LF'  | 'EMPTY'  | 'CS21182FB01'(!)        = 'End of Design' | 'Comp-Approve'     | 'CS21182FB01'           |'R0402'| '(R0402-0201)'                 | '1.18K'   | '1%'    | '1/16W'  | 'IO'       | 'RES CHIP 1.18K 1/16W +-1%(0402)EF'                | 'CHIPR0402'    | ''          | ''            | '20190905'
 '1.2K'       | '1%'      | '1/16W'  | '0402LF'  | 'CHIP'   | 'CS21202FB00'(!)        = 'End of Design' | 'Comp-Approve'     | 'CS21202FB00'           |'R0402'| '(R0402-0201)'                 | '1.2K'    | '1%'    | '1/16W'  | 'DISCRETE' | 'RES CHIP 1.2K 1/16W+-1%(0402)EF'                  | 'CHIPR0402'    | ''          | ''            | '20190905'
 '1.2K'       | '1%'      | '1/16W'  | '0402LF'  | 'EMPTY'  | 'CS21202FB00'(!)        = 'End of Design' | 'Comp-Approve'     | 'CS21202FB00'           |'R0402'| '(R0402-0201)'                 | '1.2K'    | '1%'    | '1/16W'  | 'IO'       | 'RES CHIP 1.2K 1/16W+-1%(0402)EF'                  | 'CHIPR0402'    | ''          | ''            | '20190905'
 '2.67K'      | '1%'      | '1/16W'  | '0402LF'  | 'CHIP'   | 'CS22672FB03'(!)        = 'End of Design' | 'Comp-Approve'     | 'CS22672FB03'           |'R0402'| '(R0402-0201)'                 | '2.67K'   | '1%'    | '1/16W'  | 'DISCRETE' | 'RES CHIP 2.67K 1/16W +-1%(0402)EF'                | 'CHIPR0402'    | ''          | ''            | '20190905'
 '2.67K'      | '1%'      | '1/16W'  | '0402LF'  | 'EMPTY'  | 'CS22672FB03'(!)        = 'End of Design' | 'Comp-Approve'     | 'CS22672FB03'           |'R0402'| '(R0402-0201)'                 | '2.67K'   | '1%'    | '1/16W'  | 'IO'       | 'RES CHIP 2.67K 1/16W +-1%(0402)EF'                | 'CHIPR0402'    | ''          | ''            | '20190905'
 '4.22K'      | '1%'      | '1/16W'  | '0402LF'  | 'CHIP'   | 'CS24222FB01'(!)        = 'End of Design' | 'Comp-Approve'     | 'CS24222FB01'           |'R0402'| '(R0402-0201)'                 | '4.22K'   | '1%'    | '1/16W'  | 'DISCRETE' | 'RES CHIP 4.22K 1/16W +-1%(0402)EF'                | 'CHIPR0402'    | ''          | ''            | '20190906'
 '4.22K'      | '1%'      | '1/16W'  | '0402LF'  | 'EMPTY'  | 'CS24222FB01'(!)        = 'End of Design' | 'Comp-Approve'     | 'CS24222FB01'           |'R0402'| '(R0402-0201)'                 | '4.22K'   | '1%'    | '1/16W'  | 'IO'       | 'RES CHIP 4.22K 1/16W +-1%(0402)EF'                | 'CHIPR0402'    | ''          | ''            | '20190906'
 '5.36K'      | '1%'      | '1/16W'  | '0402LF'  | 'CHIP'   | 'CS25362FB02'(!)        = 'End of Design' | 'Comp-Approve'     | 'CS25362FB02'           |'R0402'| '(R0402-0201)'                 | '5.36K'   | '1%'    | '1/16W'  | 'DISCRETE' | 'RES CHIP 5.36K 1/16W +-1%(0402)EF'                | 'CHIPR0402'    | ''          | ''            | '20190906'
 '5.36K'      | '1%'      | '1/16W'  | '0402LF'  | 'EMPTY'  | 'CS25362FB02'(!)        = 'End of Design' | 'Comp-Approve'     | 'CS25362FB02'           |'R0402'| '(R0402-0201)'                 | '5.36K'   | '1%'    | '1/16W'  | 'IO'       | 'RES CHIP 5.36K 1/16W +-1%(0402)EF'                | 'CHIPR0402'    | ''          | ''            | '20190906'
 '6.98K'      | '1%'      | '1/16W'  | '0402LF'  | 'CHIP'   | 'CS26982FB08'(!)        = ''              | ''                 | 'CS26982FB08'           |'R0402'| '(R0402-0201)'                 | '6.98K'   | '1%'    | '1/16W'  | 'DISCRETE' | 'RES CHIP 6.98K 1/16W +-1%(0402)EF'                | 'CHIPR0402'    | ''          | ''            | '20190906'
 '6.98K'      | '1%'      | '1/16W'  | '0402LF'  | 'EMPTY'  | 'CS26982FB08'(!)        = ''              | ''                 | 'CS26982FB08'           |'R0402'| '(R0402-0201)'                 | '6.98K'   | '1%'    | '1/16W'  | 'IO'       | 'RES CHIP 6.98K 1/16W +-1%(0402)EF'                | 'CHIPR0402'    | ''          | ''            | '20190906'
 '10.7K'      | '1%'      | '1/16W'  | '0402LF'  | 'CHIP'   | 'CS31072FB05'(!)        = 'End of Design' | 'Comp-Approve'     | 'CS31072FB05'           |'R0402'| '(R0402-0201)'                 | '10.7K'   | '1%'    | '1/16W'  | 'DISCRETE' | 'RES CHIP 10.7K 1/16W +-1%(0402)EF'                | 'CHIPR0402'    | ''          | ''            | '20190906'
 '10.7K'      | '1%'      | '1/16W'  | '0402LF'  | 'EMPTY'  | 'CS31072FB05'(!)        = 'End of Design' | 'Comp-Approve'     | 'CS31072FB05'           |'R0402'| '(R0402-0201)'                 | '10.7K'   | '1%'    | '1/16W'  | 'IO'       | 'RES CHIP 10.7K 1/16W +-1%(0402)EF'                | 'CHIPR0402'    | ''          | ''            | '20190906'
 '26.7K'      | '1%'      | '1/16W'  | '0402LF'  | 'CHIP'   | 'CS32672FB03'(!)        = 'End of Design' | 'Comp-Approve'     | 'CS32672FB03'           |'R0402'| '(R0402-0201)'                 | '26.7K'   | '1%'    | '1/16W'  | 'DISCRETE' | 'RES CHIP 26.7K 1/16W +-1%(0402)EF'                | 'CHIPR0402'    | ''          | ''            | '20190906'
 '26.7K'      | '1%'      | '1/16W'  | '0402LF'  | 'EMPTY'  | 'CS32672FB03'(!)        = 'End of Design' | 'Comp-Approve'     | 'CS32672FB03'           |'R0402'| '(R0402-0201)'                 | '26.7K'   | '1%'    | '1/16W'  | 'IO'       | 'RES CHIP 26.7K 1/16W +-1%(0402)EF'                | 'CHIPR0402'    | ''          | ''            | '20190906'
 '27K'        | '1%'      | '1/16W'  | '0402LF'  | 'CHIP'   | 'CS32702FB03'(!)        = 'End of Design' | 'Comp-Approve'     | 'CS32702FB03'           |'R0402'| '(R0402-0201)'                 | '27K'     | '1%'    | '1/16W'  | 'DISCRETE' | 'RES CHIP 27K 1/16W +-1%(0402)EF'                  | 'CHIPR0402'    | ''          | ''            | '20190906'
 '27K'        | '1%'      | '1/16W'  | '0402LF'  | 'EMPTY'  | 'CS32702FB03'(!)        = 'End of Design' | 'Comp-Approve'     | 'CS32702FB03'           |'R0402'| '(R0402-0201)'                 | '27K'     | '1%'    | '1/16W'  | 'IO'       | 'RES CHIP 27K 1/16W +-1%(0402)EF'                  | 'CHIPR0402'    | ''          | ''            | '20190906'
 '57.6K'      | '1%'      | '1/16W'  | '0402LF'  | 'CHIP'   | 'CS35762FB02'(!)        = ''              | ''                 | 'CS35762FB02'           |'R0402'| '(R0402-0201)'                 | '57.6K'   | '1%'    | '1/16W'  | 'DISCRETE' | 'RES CHIP 57.6K 1/16W +-1%(0402)EF'                | 'CHIPR0402'    | ''          | ''            | '20190906'
 '57.6K'      | '1%'      | '1/16W'  | '0402LF'  | 'EMPTY'  | 'CS35762FB02'(!)        = ''              | ''                 | 'CS35762FB02'           |'R0402'| '(R0402-0201)'                 | '57.6K'   | '1%'    | '1/16W'  | 'IO'       | 'RES CHIP 57.6K 1/16W +-1%(0402)EF'                | 'CHIPR0402'    | ''          | ''            | '20190906'
 '68K'        | '1%'      | '1/16W'  | '0402LF'  | 'CHIP'   | 'CS36802FB04'(!)        = 'End of Design' | 'Comp-Approve'     | 'CS36802FB04'           |'R0402'| '(R0402-0201)'                 | '68K'     | '1%'    | '1/16W'  | 'DISCRETE' | 'RES CHIP 68K 1/16W +-1%(0402)EF'                  | 'CHIPR0402'    | ''          | ''            | '20190906'
 '68K'        | '1%'      | '1/16W'  | '0402LF'  | 'EMPTY'  | 'CS36802FB04'(!)        = 'End of Design' | 'Comp-Approve'     | 'CS36802FB04'           |'R0402'| '(R0402-0201)'                 | '68K'     | '1%'    | '1/16W'  | 'IO'       | 'RES CHIP 68K 1/16W +-1%(0402)EF'                  | 'CHIPR0402'    | ''          | ''            | '20190906'
 '4.02'       | '1%'      | '1/16W'  | '0402LF'  | 'CHIP'   | 'CS-4022FB01'(!)        = 'End of Design' | 'Comp-Approve'     | 'CS-4022FB01'           |'R0402'| '(R0402-0201)'                 | '4.02'    | '1%'    | '1/16W'  | 'DISCRETE' | 'RES CHIP 4.02 1/16W +-1%(0402)EF'                 | 'CHIPR0402'    | ''          | ''            | '20190906'
 '4.02'       | '1%'      | '1/16W'  | '0402LF'  | 'EMPTY'  | 'CS-4022FB01'(!)        = 'End of Design' | 'Comp-Approve'     | 'CS-4022FB01'           |'R0402'| '(R0402-0201)'                 | '4.02'    | '1%'    | '1/16W'  | 'IO'       | 'RES CHIP 4.02 1/16W +-1%(0402)EF'                 | 'CHIPR0402'    | ''          | ''            | '20190906'
 '143K'       | '1%'      | '1/16W'  | '0402LF'  | 'CHIP'   | 'CS41432FB04'(!)        = ''              | ''                 | 'CS41432FB04'           |'R0402'| '(R0402-0201)'                 | '143K'    | '1%'    | '1/16W'  | 'DISCRETE' | 'RES CHIP 143K 1/16W +-1%(0402)EF'                 | 'CHIPR0402'    | ''          | ''            | '20190906'
 '143K'       | '1%'      | '1/16W'  | '0402LF'  | 'EMPTY'  | 'CS41432FB04'(!)        = ''              | ''                 | 'CS41432FB04'           |'R0402'| '(R0402-0201)'                 | '143K'    | '1%'    | '1/16W'  | 'IO'       | 'RES CHIP 143K 1/16W +-1%(0402)EF'                 | 'CHIPR0402'    | ''          | ''            | '20190906'
 '165K'       | '1%'      | '1/16W'  | '0402LF'  | 'CHIP'   | 'CS41652FB03'(!)        = 'End of Design' | 'Comp-Approve'     | 'CS41652FB03'           |'R0402'| '(R0402-0201)'                 | '165K'    | '1%'    | '1/16W'  | 'DISCRETE' | 'RES CHIP 165K 1/16W +-1%(0402)EF'                 | 'CHIPR0402'    | ''          | ''            | '20190906'
 '165K'       | '1%'      | '1/16W'  | '0402LF'  | 'EMPTY'  | 'CS41652FB03'(!)        = 'End of Design' | 'Comp-Approve'     | 'CS41652FB03'           |'R0402'| '(R0402-0201)'                 | '165K'    | '1%'    | '1/16W'  | 'IO'       | 'RES CHIP 165K 1/16W +-1%(0402)EF'                 | 'CHIPR0402'    | ''          | ''            | '20190906'
 '255K'       | '1%'      | '1/16W'  | '0402LF'  | 'CHIP'   | 'CS42552FB02'(!)        = 'End of Design' | 'Comp-Approve'     | 'CS42552FB02'           |'R0402'| '(R0402-0201)'                 | '255K'    | '1%'    | '1/16W'  | 'DISCRETE' | 'RES CHIP 255K 1/16W +-1%(0402)EF'                 | 'CHIPR0402'    | ''          | ''            | '20190906'
 '255K'       | '1%'      | '1/16W'  | '0402LF'  | 'EMPTY'  | 'CS42552FB02'(!)        = 'End of Design' | 'Comp-Approve'     | 'CS42552FB02'           |'R0402'| '(R0402-0201)'                 | '255K'    | '1%'    | '1/16W'  | 'IO'       | 'RES CHIP 255K 1/16W +-1%(0402)EF'                 | 'CHIPR0402'    | ''          | ''            | '20190906'
 '470K'       | '1%'      | '1/16W'  | '0402LF'  | 'CHIP'   | 'CS44702FB02'(!)        = 'End of Design' | 'Comp-Approve'     | 'CS44702FB02'           |'R0402'| '(R0402-0201)'                 | '470K'    | '1%'    | '1/16W'  | 'DISCRETE' | 'RES CHIP 470K 1/16W +-1%(0402)EF'                 | 'CHIPR0402'    | ''          | ''            | '20190906'
 '470K'       | '1%'      | '1/16W'  | '0402LF'  | 'EMPTY'  | 'CS44702FB02'(!)        = 'End of Design' | 'Comp-Approve'     | 'CS44702FB02'           |'R0402'| '(R0402-0201)'                 | '470K'    | '1%'    | '1/16W'  | 'IO'       | 'RES CHIP 470K 1/16W +-1%(0402)EF'                 | 'CHIPR0402'    | ''          | ''            | '20190906'
 '866K'       | '1%'      | '1/16W'  | '0402LF'  | 'CHIP'   | 'CS48662FB02'(!)        = ''              | ''                 | 'CS48662FB02'           |'R0402'| '(R0402-0201)'                 | '866K'    | '1%'    | '1/16W'  | 'DISCRETE' | 'RES CHIP 866K 1/16W +-1%(0402)EF'                 | 'CHIPR0402'    | ''          | ''            | '20190906'
 '866K'       | '1%'      | '1/16W'  | '0402LF'  | 'EMPTY'  | 'CS48662FB02'(!)        = ''              | ''                 | 'CS48662FB02'           |'R0402'| '(R0402-0201)'                 | '866K'    | '1%'    | '1/16W'  | 'IO'       | 'RES CHIP 866K 1/16W +-1%(0402)EF'                 | 'CHIPR0402'    | ''          | ''            | '20190906'
 '5.11'       | '1%'      | '1/16W'  | '0402LF'  | 'CHIP'   | 'CS-5112FB02'(!)        = 'End of Design' | 'Comp-Approve'     | 'CS-5112FB02'           |'R0402'| '(R0402-0201)'                 | '5.11'    | '1%'    | '1/16W'  | 'DISCRETE' | 'RES CHIP 5.11 1/16W +-1%(0402)EF'                 | 'CHIPR0402'    | ''          | ''            | '20190906'
 '5.11'       | '1%'      | '1/16W'  | '0402LF'  | 'EMPTY'  | 'CS-5112FB02'(!)        = 'End of Design' | 'Comp-Approve'     | 'CS-5112FB02'           |'R0402'| '(R0402-0201)'                 | '5.11'    | '1%'    | '1/16W'  | 'IO'       | 'RES CHIP 5.11 1/16W +-1%(0402)EF'                 | 'CHIPR0402'    | ''          | ''            | '20190906'
 '10M'        | '1%'      | '1/16W'  | '0402LF'  | 'CHIP'   | 'CS61002FB02'(!)        = ''              | ''                 | 'CS61002FB02'           |'R0402'| '(R0402-0201)'                 | '10M'     | '1%'    | '1/16W'  | 'DISCRETE' | 'RES CHIP 10M 1/16W +-1%(0402)EF'                  | 'CHIPR0402'    | ''          | ''            | '20190906'
 '10M'        | '1%'      | '1/16W'  | '0402LF'  | 'EMPTY'  | 'CS61002FB02'(!)        = ''              | ''                 | 'CS61002FB02'           |'R0402'| '(R0402-0201)'                 | '10M'     | '1%'    | '1/16W'  | 'IO'       | 'RES CHIP 10M 1/16W +-1%(0402)EF'                  | 'CHIPR0402'    | ''          | ''            | '20190906'
 '2.8M'       | '1%'      | '1/8W'   | '0805LF'  | 'CHIP'   | 'CS52804FA00'(!)        = ''              | ''                 | 'CS52804FA00'           |'R0805'| '(SMR0805AW)'                  | '2.8M'    | '1%'    | '1/8W'   | 'DISCRETE' | 'RES CHIP 2.8M 1/8W +-1%(0805)'                    | 'CHIPR0805'    | ''          | ''            | '20191001'
 '2.8M'       | '1%'      | '1/8W'   | '0805LF'  | 'EMPTY'  | 'CS52804FA00'(!)        = ''              | ''                 | 'CS52804FA00'           |'R0805'| '(SMR0805AW)'                  | '2.8M'    | '1%'    | '1/8W'   | 'IO'       | 'RES CHIP 2.8M 1/8W +-1%(0805)'                    | 'CHIPR0805'    | ''          | ''            | '20191001'
 '12K'        | '1%'      | '1/10W'  | '0603LF'  | 'CHIP'   | 'CS31203F911'(!)        = ''              | ''                 | 'CS31203F911'           |'R0603'| '(SMR0603AW)'                  | '12K'     | '1%'    | '1/10W'  | 'DISCRETE' | 'RESISTOR CHIP 12K 1/10W+-1%(0603)'                | 'CHIPR0603'    | ''          | ''            | '20190925'
 '12K'        | '1%'      | '1/10W'  | '0603LF'  | 'EMPTY'  | 'CS31203F911'(!)        = ''              | ''                 | 'CS31203F911'           |'R0603'| '(SMR0603AW)'                  | '12K'     | '1%'    | '1/10W'  | 'IO'       | 'RESISTOR CHIP 12K 1/10W+-1%(0603)'                | 'CHIPR0603'    | ''          | ''            | '20190925'
 '26.1K'      | '0.1%'    | '1/10W'  | '0603LF'  | 'CHIP'   | 'CS32613B900'(!)        = 'End of Design' | 'Comp-Approve'     | 'CS32613B900'           |'R0603'| '(SMR0603AW)'                  | '26.1K'   | '0.1%'  | '1/10W'  | 'DISCRETE' | 'RES CHIP 26.1K 1/10W +-0.1%(0603)'                | 'CHIPR0603'    | ''          | ''            | '20190927'
 '26.1K'      | '0.1%'    | '1/10W'  | '0603LF'  | 'EMPTY'  | 'CS32613B900'(!)        = 'End of Design' | 'Comp-Approve'     | 'CS32613B900'           |'R0603'| '(SMR0603AW)'                  | '26.1K'   | '0.1%'  | '1/10W'  | 'IO'       | 'RES CHIP 26.1K 1/10W +-0.1%(0603)'                | 'CHIPR0603'    | ''          | ''            | '20190927'
 '10.2K'      | '0.1%'    | '1/16W'  | '0402LF'  | 'CHIP'   | 'CS31022BB01'(!)        = ''              | ''                 | 'CS31022BB01'           |'R0402'| '(R0402-0201)'                 | '10.2K'   | '0.1%'  | '1/16W'  | 'DISCRETE' | 'RES CHIP 10.2K 1/16W +-0.1%(0402)'                | 'CHIPR0402'    | ''          | ''            | '20190927'
 '10.2K'      | '0.1%'    | '1/16W'  | '0402LF'  | 'EMPTY'  | 'CS31022BB01'(!)        = ''              | ''                 | 'CS31022BB01'           |'R0402'| '(R0402-0201)'                 | '10.2K'   | '0.1%'  | '1/16W'  | 'IO'       | 'RES CHIP 10.2K 1/16W +-0.1%(0402)'                | 'CHIPR0402'    | ''          | ''            | '20190927'
 '10K'        | '1%'      | '1/20W'  | '0201LF'  | 'CHIP'   | 'CS31001FE17'(!)        = ''              | ''                 | 'CS31001FE17'           |'R0201'| '(SMR0201AW)'                  | '10K'     | '1%'    | '1/20W'  | 'DISCRETE' | 'RES CHIP 10K 1/20W +-1%(0201)EF'                  | 'CHIPR0201'    | ''          | ''            | '20191004'
 '10K'        | '1%'      | '1/20W'  | '0201LF'  | 'EMPTY'  | 'CS31001FE17'(!)        = ''              | ''                 | 'CS31001FE17'           |'R0201'| '(SMR0201AW)'                  | '10K'     | '1%'    | '1/20W'  | 'IO'       | 'RES CHIP 10K 1/20W +-1%(0201)EF'                  | 'CHIPR0201'    | ''          | ''            | '20191004'
 '32.4'       | '1%'      | '1/16W'  | '0402LF'  | 'CHIP'   | 'CS03242FB00'(!)        = ''              | ''                 | 'CS03242FB00'           |'R0402'| '(R0402-0201)'                 | '32.4'    | '1%'    | '1/16W'  | 'DISCRETE' | 'RES CHIP 32.4 1/16W +-1%(0402)'                   | 'CHIPR0402'    | ''          | ''            | '20191004'
 '32.4'       | '1%'      | '1/16W'  | '0402LF'  | 'EMPTY'  | 'CS03242FB00'(!)        = ''              | ''                 | 'CS03242FB00'           |'R0402'| '(R0402-0201)'                 | '32.4'    | '1%'    | '1/16W'  | 'IO'       | 'RES CHIP 32.4 1/16W +-1%(0402)'                   | 'CHIPR0402'    | ''          | ''            | '20191004'
 '1.74M'      | '1%'      | '1/8W'   | '0805LF'  | 'CHIP'   | 'CS51744FA00'(!)        = ''              | ''                 | 'CS51744FA00'           |'R0805'| '(SMR0805AW)'                  | '1.74M'   | '1%'    | '1/8W'   | 'DISCRETE' | 'RES CHIP 1.74M 1/8W +-1%(0805)'                   | 'CHIPR0805'    | ''          | ''            | '20191008'
 '1.74M'      | '1%'      | '1/8W'   | '0805LF'  | 'EMPTY'  | 'CS51744FA00'(!)        = ''              | ''                 | 'CS51744FA00'           |'R0805'| '(SMR0805AW)'                  | '1.74M'   | '1%'    | '1/8W'   | 'IO'       | 'RES CHIP 1.74M 1/8W +-1%(0805)'                   | 'CHIPR0805'    | ''          | ''            | '20191008'
 '4.7K'       | '5%'      | '1/20W'  | '0201LF'  | 'CHIP'   | 'CS24701JE04'(!)        = 'End of Design' | 'Comp-Approve'     | 'CS24701JE04'           |'R0201'| '(SMR0201AW)'                  | '4.7K'    | '5%'    | '1/20W'  | 'DISCRETE' | 'RES CHIP 4.7K 1/20W +-5%(0201)EF'                 | 'CHIPR0201'    | ''          | ''            | '20191008'
 '4.7K'       | '5%'      | '1/20W'  | '0201LF'  | 'EMPTY'  | 'CS24701JE04'(!)        = 'End of Design' | 'Comp-Approve'     | 'CS24701JE04'           |'R0201'| '(SMR0201AW)'                  | '4.7K'    | '5%'    | '1/20W'  | 'IO'       | 'RES CHIP 4.7K 1/20W +-5%(0201)EF'                 | 'CHIPR0201'    | ''          | ''            | '20191008'
 '3.6K'       | '1%'      | '1/20W'  | '0201LF'  | 'CHIP'   | 'CS23601FE00'(!)        = ''              | ''                 | 'CS23601FE00'           |'R0201'| '(SMR0201AW)'                  | '3.6K'    | '1%'    | '1/20W'  | 'DISCRETE' | 'RES CHIP 3.6K 1/20W +-1% (0201)'                  | 'CHIPR0201'    | ''          | ''            | '20191008'
 '3.6K'       | '1%'      | '1/20W'  | '0201LF'  | 'EMPTY'  | 'CS23601FE00'(!)        = ''              | ''                 | 'CS23601FE00'           |'R0201'| '(SMR0201AW)'                  | '3.6K'    | '1%'    | '1/20W'  | 'IO'       | 'RES CHIP 3.6K 1/20W +-1% (0201)'                  | 'CHIPR0201'    | ''          | ''            | '20191008'
 '348'        | '1%'      | '1/10W'  | '0603LF'  | 'CHIP'   | 'CS13483F917'(!)        = ''              | ''                 | 'CS13483F917'           |'R0603_H24'| '(SMR0603AW)'                  | '348'     | '1%'    | '1/10W'  | 'DISCRETE' | 'RES CHIP 348 1/10W +-1%(0603)'                    | 'CHIPR0603'    | ''          | ''            | '20191008'
 '348'        | '1%'      | '1/10W'  | '0603LF'  | 'EMPTY'  | 'CS13483F917'(!)        = ''              | ''                 | 'CS13483F917'           |'R0603_H24'| '(SMR0603AW)'                  | '348'     | '1%'    | '1/10W'  | 'IO'       | 'RES CHIP 348 1/10W +-1%(0603)'                    | 'CHIPR0603'    | ''          | ''            | '20191008'
 '10.2'       | '0.1%'    | '1/16W'  | '0402LF'  | 'CHIP'   | 'CS01022BB00'(!)        = ''              | ''                 | 'CS01022BB00'           |'R0402'| '(R0402-0201)'                 | '10.2'    | '0.1%'  | '1/16W'  | 'DISCRETE' | 'RES CHIP 10.2 1/16W +-0.1%(0402)'                 | 'CHIPR0402'    | ''          | ''            | '20191021'
 '10.2'       | '0.1%'    | '1/16W'  | '0402LF'  | 'EMPTY'  | 'CS01022BB00'(!)        = ''              | ''                 | 'CS01022BB00'           |'R0402'| '(R0402-0201)'                 | '10.2'    | '0.1%'  | '1/16W'  | 'IO'       | 'RES CHIP 10.2 1/16W +-0.1%(0402)'                 | 'CHIPR0402'    | ''          | ''            | '20191021'
 '6.8K'       | '1%'      | '1/20W'  | '0201LF'  | 'CHIP'   | 'CS26801FE00'(!)        = ''              | ''                 | 'CS26801FE00'           |'R0201'| '(SMR0201AW)'                  | '6.8K'    | '1%'    | '1/20W'  | 'DISCRETE' | 'RES CHIP 6.8K(1/20W,+-1%,0201)'                   | 'CHIPR0201'    | ''          | ''            | '20191022'
 '6.8K'       | '1%'      | '1/20W'  | '0201LF'  | 'EMPTY'  | 'CS26801FE00'(!)        = ''              | ''                 | 'CS26801FE00'           |'R0201'| '(SMR0201AW)'                  | '6.8K'    | '1%'    | '1/20W'  | 'IO'       | 'RES CHIP 6.8K(1/20W,+-1%,0201)'                   | 'CHIPR0201'    | ''          | ''            | '20191022'
 '4.7'        | '1%'      | '1/16W'  | '0402LF'  | 'CHIP'   | 'CS-4702FB19'(!)        = 'End of Design' | 'Comp-Approve'     | 'CS-4702FB19'           |'R0402'| '(R0402-0201)'                 | '4.7'     | '1%'    | '1/16W'  | 'DISCRETE' | 'RES CHIP 4.7 1/16W +-1%(0402)'                    | 'CHIPR0402'    | ''          | ''            | '20191025'
 '4.7'        | '1%'      | '1/16W'  | '0402LF'  | 'EMPTY'  | 'CS-4702FB19'(!)        = 'End of Design' | 'Comp-Approve'     | 'CS-4702FB19'           |'R0402'| '(R0402-0201)'                 | '4.7'     | '1%'    | '1/16W'  | 'IO'       | 'RES CHIP 4.7 1/16W +-1%(0402)'                    | 'CHIPR0402'    | ''          | ''            | '20191025'
 '10.2'       | '1%'      | '1/16W'  | '0402LF'  | 'CHIP'   | 'CS01022FB00'(!)        = ''              | ''                 | 'CS01022FB00'           |'R0402'| '(R0402-0201)'                 | '10.2'    | '1%'    | '1/16W'  | 'DISCRETE' | 'RES CHIP 10.2 1/16W +-1%(0402)HF'                 | 'CHIPR0402'    | ''          | ''            | '20191029'
 '10.2'       | '1%'      | '1/16W'  | '0402LF'  | 'EMPTY'  | 'CS01022FB00'(!)        = ''              | ''                 | 'CS01022FB00'           |'R0402'| '(R0402-0201)'                 | '10.2'    | '1%'    | '1/16W'  | 'IO'       | 'RES CHIP 10.2 1/16W +-1%(0402)HF'                 | 'CHIPR0402'    | ''          | ''            | '20191029'
 '0.03'       | '1%'      | '1/2W'   | '1206LF'  | 'CHIP'   | 'CS+0307F200'(!)        = ''              | ''                 | 'CS+0307F200'           |'R1206'| '(SMR1206AW)'                  | '0.03'    | '1%'    | '1/2W'   | 'DISCRETE' | 'RES CHIP 0.03 1/2W +-1%(1206)'                    | 'CHIPR1206'    | ''          | ''            | '20191030'
 '0.03'       | '1%'      | '1/2W'   | '1206LF'  | 'EMPTY'  | 'CS+0307F200'(!)        = ''              | ''                 | 'CS+0307F200'           |'R1206'| '(SMR1206AW)'                  | '0.03'    | '1%'    | '1/2W'   | 'IO'       | 'RES CHIP 0.03 1/2W +-1%(1206)'                    | 'CHIPR1206'    | ''          | ''            | '20191030'
 '332K'       | '1%'      | '1/16W'  | '0402LF'  | 'CHIP'   | 'CS43322FB03'(!)        = 'End of Design' | 'Comp-Approve'     | 'CS43322FB03'           |'R0402'| '(R0402-0201)'                 | '332K'    | '1%'    | '1/16W'  | 'DISCRETE' | 'RES CHIP 332K 1/16W +-1%(0402)EF'                 | 'CHIPR0402'    | ''          | ''            | '20191101'
 '332K'       | '1%'      | '1/16W'  | '0402LF'  | 'EMPTY'  | 'CS43322FB03'(!)        = 'End of Design' | 'Comp-Approve'     | 'CS43322FB03'           |'R0402'| '(R0402-0201)'                 | '332K'    | '1%'    | '1/16W'  | 'IO'       | 'RES CHIP 332K 1/16W +-1%(0402)EF'                 | 'CHIPR0402'    | ''          | ''            | '20191101'
 '40.2K'      | '1%'      | '1/16W'  | '0402LF'  | 'CHIP'   | 'CS34022FB04'(!)        = 'End of Design' | 'Comp-Approve'     | 'CS34022FB04'           |'R0402'| '(R0402-0201)'                 | '40.2K'   | '1%'    | '1/16W'  | 'DISCRETE' | 'RES CHIP 40.2K 1/16W +-1%(0402)EF'                | 'CHIPR0402'    | ''          | ''            | '20191101'
 '40.2K'      | '1%'      | '1/16W'  | '0402LF'  | 'EMPTY'  | 'CS34022FB04'(!)        = 'End of Design' | 'Comp-Approve'     | 'CS34022FB04'           |'R0402'| '(R0402-0201)'                 | '40.2K'   | '1%'    | '1/16W'  | 'IO'       | 'RES CHIP 40.2K 1/16W +-1%(0402)EF'                | 'CHIPR0402'    | ''          | ''            | '20191101'
 '118K'       | '1%'      | '1/16W'  | '0402LF'  | 'CHIP'   | 'CS41182FB05'(!)        = ''              | ''                 | 'CS41182FB05'           |'R0402'| '(R0402-0201)'                 | '118K'    | '1%'    | '1/16W'  | 'DISCRETE' | 'RES CHIP 118K 1/16W +-1%(0402)EF'                 | 'CHIPR0402'    | ''          | ''            | '20191101'
 '118K'       | '1%'      | '1/16W'  | '0402LF'  | 'EMPTY'  | 'CS41182FB05'(!)        = ''              | ''                 | 'CS41182FB05'           |'R0402'| '(R0402-0201)'                 | '118K'    | '1%'    | '1/16W'  | 'IO'       | 'RES CHIP 118K 1/16W +-1%(0402)EF'                 | 'CHIPR0402'    | ''          | ''            | '20191101'
 '160K'       | '1%'      | '1/16W'  | '0402LF'  | 'CHIP'   | 'CS41602FB05'(!)        = ''              | ''                 | 'CS41602FB05'           |'R0402'| '(R0402-0201)'                 | '160K'    | '1%'    | '1/16W'  | 'DISCRETE' | 'RES CHIP 160K 1/16W+-1%(0402)EF'                  | 'CHIPR0402'    | ''          | ''            | '20191113'
 '160K'       | '1%'      | '1/16W'  | '0402LF'  | 'EMPTY'  | 'CS41602FB05'(!)        = ''              | ''                 | 'CS41602FB05'           |'R0402'| '(R0402-0201)'                 | '160K'    | '1%'    | '1/16W'  | 'IO'       | 'RES CHIP 160K 1/16W+-1%(0402)EF'                  | 'CHIPR0402'    | ''          | ''            | '20191113'
 '33.2K'      | '1%'      | '1/20W'  | '0201LF'  | 'CHIP'   | 'CS33321FE00'(!)        = ''              | ''                 | 'CS33321FE00'           |'R0201'| '(SMR0201AW)'                  | '33.2K'   | '1%'    | '1/20W'  | 'DISCRETE' | 'RES CHIP 33.2K 1/20W +-1%(0201)'                  | 'CHIPR0201'    | ''          | ''            | '20191122'
 '33.2K'      | '1%'      | '1/20W'  | '0201LF'  | 'EMPTY'  | 'CS33321FE00'(!)        = ''              | ''                 | 'CS33321FE00'           |'R0201'| '(SMR0201AW)'                  | '33.2K'   | '1%'    | '1/20W'  | 'IO'       | 'RES CHIP 33.2K 1/20W +-1%(0201)'                  | 'CHIPR0201'    | ''          | ''            | '20191122'
 '115K'       | '1%'      | '1/20W'  | '0201LF'  | 'CHIP'   | 'CS41151FE00'(!)        = ''              | ''                 | 'CS41151FE00'           |'R0201'| '(SMR0201AW)'                  | '115K'    | '1%'    | '1/20W'  | 'DISCRETE' | 'RES CHIP 115K 1/20W +-1% (0201)'                  | 'CHIPR0201'    | ''          | ''            | '20191122'
 '115K'       | '1%'      | '1/20W'  | '0201LF'  | 'EMPTY'  | 'CS41151FE00'(!)        = ''              | ''                 | 'CS41151FE00'           |'R0201'| '(SMR0201AW)'                  | '115K'    | '1%'    | '1/20W'  | 'IO'       | 'RES CHIP 115K 1/20W +-1% (0201)'                  | 'CHIPR0201'    | ''          | ''            | '20191122'
 '806'        | '1%'      | '1/10W'  | '0603LF'  | 'CHIP'   | 'CS18063F901'(!)        = ''              | ''                 | 'CS18063F901'           |'R0603_H24'| '(SMR0603AW)'                  | '806'     | '1%'    | '1/10W'  | 'DISCRETE' | 'RES CHIP 806 1/10W +-1%(0603)EF'                  | 'CHIPR0603'    | ''          | ''            | '20191203'
 '806'        | '1%'      | '1/10W'  | '0603LF'  | 'EMPTY'  | 'CS18063F901'(!)        = ''              | ''                 | 'CS18063F901'           |'R0603_H24'| '(SMR0603AW)'                  | '806'     | '1%'    | '1/10W'  | 'IO'       | 'RES CHIP 806 1/10W +-1%(0603)EF'                  | 'CHIPR0603'    | ''          | ''            | '20191203'
 '0.0006'     | '1%'      | '4W'     | '2725LF'  | 'CHIP'   | 'CS0000FFT03'(!)        = 'End of Design' | 'Comp-Approve'     | 'CS0000FFT03'           |'R2725'| '(SMR2725AW)'                  | '0.0006'  | '1%'    | '4W'     | 'DISCRETE' | 'RES CHIP 0.0006 4W +-1%(2725)H0.991'              | 'CHIPR2725'    | ''          | ''            | '20191204'
 '0.0006'     | '1%'      | '4W'     | '2725LF'  | 'EMPTY'  | 'CS0000FFT03'(!)        = 'End of Design' | 'Comp-Approve'     | 'CS0000FFT03'           |'R2725'| '(SMR2725AW)'                  | '0.0006'  | '1%'    | '4W'     | 'IO'       | 'RES CHIP 0.0006 4W +-1%(2725)H0.991'              | 'CHIPR2725'    | ''          | ''            | '20191204'
 '2.61K'      | '0.1%'    | '1/16W'  | '0402LF'  | 'CHIP'   | 'CS22612BB00'(!)        = ''              | ''                 | 'CS22612BB00'           |'R0402'| '(R0402-0201)'                 | '2.61K'   | '0.1%'  | '1/16W'  | 'DISCRETE' | 'RES CHIP 2.61K 1/16W +-0.1%(0402)'                | 'CHIPR0402'    | ''          | ''            | '20191204'
 '2.61K'      | '0.1%'    | '1/16W'  | '0402LF'  | 'EMPTY'  | 'CS22612BB00'(!)        = ''              | ''                 | 'CS22612BB00'           |'R0402'| '(R0402-0201)'                 | '2.61K'   | '0.1%'  | '1/16W'  | 'IO'       | 'RES CHIP 2.61K 1/16W +-0.1%(0402)'                | 'CHIPR0402'    | ''          | ''            | '20191204'
 '76.8K'      | '0.1%'    | '1/20W'  | '0201LF'  | 'CHIP'   | 'CS37681BE01'(!)        = ''              | ''                 | 'CS37681BE01'           |'R0201'| '(SMR0201AW)'                  | '76.8K'   | '0.1%'  | '1/20W'  | 'DISCRETE' | 'RES CHIP 76.8K 1/20W +-0.1%(0201)'                | 'CHIPR0201'    | ''          | ''            | '20191204'
 '76.8K'      | '0.1%'    | '1/20W'  | '0201LF'  | 'EMPTY'  | 'CS37681BE01'(!)        = ''              | ''                 | 'CS37681BE01'           |'R0201'| '(SMR0201AW)'                  | '76.8K'   | '0.1%'  | '1/20W'  | 'IO'       | 'RES CHIP 76.8K 1/20W +-0.1%(0201)'                | 'CHIPR0201'    | ''          | ''            | '20191204'
 '8.06K'      | '1%'      | '1/20W'  | '0201LF'  | 'CHIP'   | 'CS28061FE00'(!)        = ''              | ''                 | 'CS28061FE00'           |'R0201'| '(SMR0201AW)'                  | '8.06K'   | '1%'    | '1/20W'  | 'DISCRETE' | 'RES CHIP 8.06K 1/20W +-1%(0201)'                  | 'CHIPR0201'    | ''          | ''            | '20191204'
 '8.06K'      | '1%'      | '1/20W'  | '0201LF'  | 'EMPTY'  | 'CS28061FE00'(!)        = ''              | ''                 | 'CS28061FE00'           |'R0201'| '(SMR0201AW)'                  | '8.06K'   | '1%'    | '1/20W'  | 'IO'       | 'RES CHIP 8.06K 1/20W +-1%(0201)'                  | 'CHIPR0201'    | ''          | ''            | '20191204'
 '931K'       | '1%'      | '1/16W'  | '0402LF'  | 'CHIP'   | 'CS49312FB00'(!)        = ''              | ''                 | 'CS49312FB00'           |'R0402'| '(R0402-0201)'                 | '931K'    | '1%'    | '1/16W'  | 'DISCRETE' | 'RES CHIP 931K 1/16W +-1%(0402)'                   | 'CHIPR0402'    | ''          | ''            | '20191216'
 '931K'       | '1%'      | '1/16W'  | '0402LF'  | 'EMPTY'  | 'CS49312FB00'(!)        = ''              | ''                 | 'CS49312FB00'           |'R0402'| '(R0402-0201)'                 | '931K'    | '1%'    | '1/16W'  | 'IO'       | 'RES CHIP 931K 1/16W +-1%(0402)'                   | 'CHIPR0402'    | ''          | ''            | '20191216'
 '0'          | '5%'      | '1/8W'   | '0805LF'  | 'CHIP'   | 'CS00004JA05'(!)        = 'End of Design' | 'Comp-Approve'     | 'CS00004JA05'           |'R0805'| '(SMR0805AW)'                  | '0'       | '5%'    | '1/8W'   | 'DISCRETE' | 'RES CHIP 0 1/8W +-5% (0805)EF'                    | 'CHIPR0805'    | ''          | ''            | '20191218'
 '0'          | '5%'      | '1/8W'   | '0805LF'  | 'EMPTY'  | 'CS00004JA05'(!)        = 'End of Design' | 'Comp-Approve'     | 'CS00004JA05'           |'R0805'| '(SMR0805AW)'                  | '0'       | '5%'    | '1/8W'   | 'IO'       | 'RES CHIP 0 1/8W +-5% (0805)EF'                    | 'CHIPR0805'    | ''          | ''            | '20191218'
 '0.0004'     | '1%'      | '4W'     | '2725LF'  | 'CHIP'   | 'CS0000FFT08'(!)        = 'End of Design' | 'Comp-Release Qty' | 'CS0000FFT08'           |'R2725'| '(SMR2725AW)'                  | '0.0004'  | '1%'    | '4W'     | 'DISCRETE' | 'RES CHIP 0.0004 4W +-1%(2725)'                    | 'CHIPR2725'    | ''          | ''            | '20191227'
 '0.0004'     | '1%'      | '4W'     | '2725LF'  | 'EMPTY'  | 'CS0000FFT08'(!)        = 'End of Design' | 'Comp-Release Qty' | 'CS0000FFT08'           |'R2725'| '(SMR2725AW)'                  | '0.0004'  | '1%'    | '4W'     | 'IO'       | 'RES CHIP 0.0004 4W +-1%(2725)'                    | 'CHIPR2725'    | ''          | ''            | '20191227'
 '0'          | ''        | '1W'     | '2512LF'  | 'CHIP'   | 'CS00008TR01'(!)        = ''              | ''                 | 'CS00008TR01'           |'R2512XU'| '(SMR2512AW)'                  | '0'       | ''      | '1W'     | 'DISCRETE' | 'RES CHIP 0 1W(2512)EF'                            | 'CHIPR2512'    | ''          | ''            | '20191227'
 '0'          | ''        | '1W'     | '2512LF'  | 'EMPTY'  | 'CS00008TR01'(!)        = ''              | ''                 | 'CS00008TR01'           |'R2512XU'| '(SMR2512AW)'                  | '0'       | ''      | '1W'     | 'IO'       | 'RES CHIP 0 1W(2512)EF'                            | 'CHIPR2512'    | ''          | ''            | '20191227'
 '750'        | '1%'      | '1/16W'  | '0402LF'  | 'CHIP'   | 'CS17502FB03'(!)        = 'End of Design' | 'Comp-Approve'     | 'CS17502FB03'           |'R0402'| '(R0402-0201)'                 | '750'     | '1%'    | '1/16W'  | 'DISCRETE' | 'RES CHIP 750 1/16W +-1%(0402)EF'                  | 'CHIPR0402'    | ''          | ''            | '20191227'
 '750'        | '1%'      | '1/16W'  | '0402LF'  | 'EMPTY'  | 'CS17502FB03'(!)        = 'End of Design' | 'Comp-Approve'     | 'CS17502FB03'           |'R0402'| '(R0402-0201)'                 | '750'     | '1%'    | '1/16W'  | 'IO'       | 'RES CHIP 750 1/16W +-1%(0402)EF'                  | 'CHIPR0402'    | ''          | ''            | '20191227'
 '2.32K'      | '1%'      | '1/16W'  | '0402LF'  | 'CHIP'   | 'CS22322FB03'(!)        = 'End of Design' | 'Comp-Approve'     | 'CS22322FB03'           |'R0402'| '(R0402-0201)'                 | '2.32K'   | '1%'    | '1/16W'  | 'DISCRETE' | 'RES CHIP 2.32K 1/16W +-1%(0402)EF'                | 'CHIPR0402'    | ''          | ''            | '20191227'
 '2.32K'      | '1%'      | '1/16W'  | '0402LF'  | 'EMPTY'  | 'CS22322FB03'(!)        = 'End of Design' | 'Comp-Approve'     | 'CS22322FB03'           |'R0402'| '(R0402-0201)'                 | '2.32K'   | '1%'    | '1/16W'  | 'IO'       | 'RES CHIP 2.32K 1/16W +-1%(0402)EF'                | 'CHIPR0402'    | ''          | ''            | '20191227'
 '7.32K'      | '1%'      | '1/16W'  | '0402LF'  | 'CHIP'   | 'CS27322FB02'(!)        = 'End of Design' | 'Comp-Approve'     | 'CS27322FB02'           |'R0402'| '(R0402-0201)'                 | '7.32K'   | '1%'    | '1/16W'  | 'DISCRETE' | 'RES CHIP 7.32K 1/16W +-1%(0402)EF'                | 'CHIPR0402'    | ''          | ''            | '20191227'
 '7.32K'      | '1%'      | '1/16W'  | '0402LF'  | 'EMPTY'  | 'CS27322FB02'(!)        = 'End of Design' | 'Comp-Approve'     | 'CS27322FB02'           |'R0402'| '(R0402-0201)'                 | '7.32K'   | '1%'    | '1/16W'  | 'IO'       | 'RES CHIP 7.32K 1/16W +-1%(0402)EF'                | 'CHIPR0402'    | ''          | ''            | '20191227'
 '7.68K'      | '1%'      | '1/16W'  | '0402LF'  | 'CHIP'   | 'CS27682FB04'(!)        = 'End of Design' | 'Comp-Approve'     | 'CS27682FB04'           |'R0402'| '(R0402-0201)'                 | '7.68K'   | '1%'    | '1/16W'  | 'DISCRETE' | 'RES CHIP 7.68K 1/16W +-1%(0402)EF'                | 'CHIPR0402'    | ''          | ''            | '20191227'
 '7.68K'      | '1%'      | '1/16W'  | '0402LF'  | 'EMPTY'  | 'CS27682FB04'(!)        = 'End of Design' | 'Comp-Approve'     | 'CS27682FB04'           |'R0402'| '(R0402-0201)'                 | '7.68K'   | '1%'    | '1/16W'  | 'IO'       | 'RES CHIP 7.68K 1/16W +-1%(0402)EF'                | 'CHIPR0402'    | ''          | ''            | '20191227'
 '15K'        | '1%'      | '1/16W'  | '0402LF'  | 'CHIP'   | 'CS31502FB05'(!)        = 'End of Design' | 'Comp-Approve'     | 'CS31502FB05'           |'R0402'| '(R0402-0201)'                 | '15K'     | '1%'    | '1/16W'  | 'DISCRETE' | 'RES CHIP 15K 1/16W +-1%(0402)EF'                  | 'CHIPR0402'    | ''          | ''            | '20191227'
 '15K'        | '1%'      | '1/16W'  | '0402LF'  | 'EMPTY'  | 'CS31502FB05'(!)        = 'End of Design' | 'Comp-Approve'     | 'CS31502FB05'           |'R0402'| '(R0402-0201)'                 | '15K'     | '1%'    | '1/16W'  | 'IO'       | 'RES CHIP 15K 1/16W +-1%(0402)EF'                  | 'CHIPR0402'    | ''          | ''            | '20191227'
 '634K'       | '1%'      | '1/16W'  | '0402LF'  | 'CHIP'   | 'CS46342FB04'(!)        = 'End of Design' | 'Comp-Approve'     | 'CS46342FB04'           |'R0402'| '(R0402-0201)'                 | '634K'    | '1%'    | '1/16W'  | 'DISCRETE' | 'RES CHIP 634K 1/16W +-1%(0402)'                   | 'CHIPR0402'    | ''          | ''            | '20200108'
 '634K'       | '1%'      | '1/16W'  | '0402LF'  | 'EMPTY'  | 'CS46342FB04'(!)        = 'End of Design' | 'Comp-Approve'     | 'CS46342FB04'           |'R0402'| '(R0402-0201)'                 | '634K'    | '1%'    | '1/16W'  | 'IO'       | 'RES CHIP 634K 1/16W +-1%(0402)'                   | 'CHIPR0402'    | ''          | ''            | '20200108'
 '825K'       | '1%'      | '1/16W'  | '0402LF'  | 'CHIP'   | 'CS48252FB01'(!)        = ''              | ''                 | 'CS48252FB01'           |'R0402'| '(R0402-0201)'                 | '825K'    | '1%'    | '1/16W'  | 'DISCRETE' | 'RES CHIP 825K 1/16W +-1%(0402)'                   | 'CHIPR0402'    | ''          | ''            | '20200108'
 '825K'       | '1%'      | '1/16W'  | '0402LF'  | 'EMPTY'  | 'CS48252FB01'(!)        = ''              | ''                 | 'CS48252FB01'           |'R0402'| '(R0402-0201)'                 | '825K'    | '1%'    | '1/16W'  | 'IO'       | 'RES CHIP 825K 1/16W +-1%(0402)'                   | 'CHIPR0402'    | ''          | ''            | '20200108'
 '715K'       | '1%'      | '1/16W'  | '0402LF'  | 'CHIP'   | 'CS47152FB00'(!)        = ''              | ''                 | 'CS47152FB00'           |'R0402'| '(R0402-0201)'                 | '715K'    | '1%'    | '1/16W'  | 'DISCRETE' | 'RES CHIP 715K 1/16W +-1% (0402)'                  | 'CHIPR0402'    | ''          | ''            | '20200114'
 '715K'       | '1%'      | '1/16W'  | '0402LF'  | 'EMPTY'  | 'CS47152FB00'(!)        = ''              | ''                 | 'CS47152FB00'           |'R0402'| '(R0402-0201)'                 | '715K'    | '1%'    | '1/16W'  | 'IO'       | 'RES CHIP 715K 1/16W +-1% (0402)'                  | 'CHIPR0402'    | ''          | ''            | '20200114'
 '2.7K'       | '5%'      | '1/8W'   | '0805LF'  | 'CHIP'   | 'CS22704JA36'(!)        = ''              | ''                 | 'CS22704JA36'           |'R0805'| '(SMR0805AW)'                  | '2.7K'    | '5%'    | '1/8W'   | 'DISCRETE' | 'RESISTOR CHIP 2.7K  1/8W  +-5%(0805)'             | 'CHIPR0805'    | ''          | ''            | '20200113'
 '2.7K'       | '5%'      | '1/8W'   | '0805LF'  | 'EMPTY'  | 'CS22704JA36'(!)        = ''              | ''                 | 'CS22704JA36'           |'R0805'| '(SMR0805AW)'                  | '2.7K'    | '5%'    | '1/8W'   | 'IO'       | 'RESISTOR CHIP 2.7K  1/8W  +-5%(0805)'             | 'CHIPR0805'    | ''          | ''            | '20200113'
 '19.6K'      | '1%'      | '1/16W'  | '0402LF'  | 'CHIP'   | 'CS31962FB07'(!)        = ''              | ''                 | 'CS31962FB07'           |'R0402'| '(R0402-0201)'                 | '19.6K'   | '1%'    | '1/16W'  | 'DISCRETE' | 'RES CHIP 19.6K 1/16W +-1%(0402)EF'                | 'CHIPR0402'    | ''          | ''            | '20200114'
 '19.6K'      | '1%'      | '1/16W'  | '0402LF'  | 'EMPTY'  | 'CS31962FB07'(!)        = ''              | ''                 | 'CS31962FB07'           |'R0402'| '(R0402-0201)'                 | '19.6K'   | '1%'    | '1/16W'  | 'IO'       | 'RES CHIP 19.6K 1/16W +-1%(0402)EF'                | 'CHIPR0402'    | ''          | ''            | '20200114'
 '255'        | '1%'      | '1/10W'  | '0603LF'  | 'CHIP'   | 'CS12553F914'(!)        = ''              | ''                 | 'CS12553F914'           |'R0603'| '(SMR0603AW)'                  | '255'     | '1%'    | '1/10W'  | 'DISCRETE' | 'RESISTOR CHIP 255,1/10W,+-1%(0603)'               | 'CHIPR0603'    | ''          | ''            | '20200122'
 '255'        | '1%'      | '1/10W'  | '0603LF'  | 'EMPTY'  | 'CS12553F914'(!)        = ''              | ''                 | 'CS12553F914'           |'R0603'| '(SMR0603AW)'                  | '255'     | '1%'    | '1/10W'  | 'IO'       | 'RESISTOR CHIP 255,1/10W,+-1%(0603)'               | 'CHIPR0603'    | ''          | ''            | '20200122'
 '33'         | '5%'      | '1/8W'   | '0805LF'  | 'CHIP'   | 'CS03304JA14'(!)        = ''              | ''                 | 'CS03304JA14'           |'R0805'| '(SMR0805AW)'                  | '33'      | '5%'    | '1/8W'   | 'DISCRETE' | 'RES CHIP 33 1/8W +-5% (0805)'                     | 'CHIPR0805'    | ''          | ''            | '20200203'
 '33'         | '5%'      | '1/8W'   | '0805LF'  | 'EMPTY'  | 'CS03304JA14'(!)        = ''              | ''                 | 'CS03304JA14'           |'R0805'| '(SMR0805AW)'                  | '33'      | '5%'    | '1/8W'   | 'IO'       | 'RES CHIP 33 1/8W +-5% (0805)'                     | 'CHIPR0805'    | ''          | ''            | '20200203'
 '120K'       | '1%'      | '1/16W'  | '0402LF'  | 'CHIP'   | 'CS41202FB05'(!)        = ''              | ''                 | 'CS41202FB05'           |'R0402'| '(R0402-0201)'                 | '120K'    | '1%'    | '1/16W'  | 'DISCRETE' | 'RES CHIP 120K 1/16W +-1%(0402)EF'                 | 'CHIPR0402'    | ''          | ''            | '20200225'
 '120K'       | '1%'      | '1/16W'  | '0402LF'  | 'EMPTY'  | 'CS41202FB05'(!)        = ''              | ''                 | 'CS41202FB05'           |'R0402'| '(R0402-0201)'                 | '120K'    | '1%'    | '1/16W'  | 'IO'       | 'RES CHIP 120K 1/16W +-1%(0402)EF'                 | 'CHIPR0402'    | ''          | ''            | '20200225'
 '0.0003'     | '1%'      | '8W'     | '2512LF'  | 'CHIP'   | 'CS0000LFR00'(!)        = ''              | ''                 | 'CS0000LFR00'           |'R2512XV'| '(SMR2512AW)'                  | '0.0003'  | '1%'    | '8W'     | 'DISCRETE' | 'RES CHIP 0.0003 8W +-1% (2512)KOA'                | 'CHIPR2512'    | ''          | ''            | '20200227'
 '0.0003'     | '1%'      | '8W'     | '2512LF'  | 'EMPTY'  | 'CS0000LFR00'(!)        = ''              | ''                 | 'CS0000LFR00'           |'R2512XV'| '(SMR2512AW)'                  | '0.0003'  | '1%'    | '8W'     | 'IO'       | 'RES CHIP 0.0003 8W +-1% (2512)KOA'                | 'CHIPR2512'    | ''          | ''            | '20200227'
 '56.2K'      | '1%'      | '1/16W'  | '0402LF'  | 'CHIP'   | 'CS35622FB07'(!)        = 'End of Design' | 'Comp-Approve'     | 'CS35622FB07'           |'R0402'| '(R0402-0201)'                 | '56.2K'   | '1%'    | '1/16W'  | 'DISCRETE' | 'RES CHIP 56.2K 1/16W +-1%(0402)EF'                | 'CHIPR0402'    | ''          | ''            | '20200227'
 '56.2K'      | '1%'      | '1/16W'  | '0402LF'  | 'EMPTY'  | 'CS35622FB07'(!)        = 'End of Design' | 'Comp-Approve'     | 'CS35622FB07'           |'R0402'| '(R0402-0201)'                 | '56.2K'   | '1%'    | '1/16W'  | 'IO'       | 'RES CHIP 56.2K 1/16W +-1%(0402)EF'                | 'CHIPR0402'    | ''          | ''            | '20200227'
 '46.4K'      | '1%'      | '1/16W'  | '0402LF'  | 'CHIP'   | 'CS34642FB02'(!)        = ''              | ''                 | 'CS34642FB02'           |'R0402'| '(R0402-0201)'                 | '46.4K'   | '1%'    | '1/16W'  | 'DISCRETE' | 'RES CHIP 46.4K 1/16W +-1%(0402)EF'                | 'CHIPR0402'    | ''          | ''            | '20200227'
 '46.4K'      | '1%'      | '1/16W'  | '0402LF'  | 'EMPTY'  | 'CS34642FB02'(!)        = ''              | ''                 | 'CS34642FB02'           |'R0402'| '(R0402-0201)'                 | '46.4K'   | '1%'    | '1/16W'  | 'IO'       | 'RES CHIP 46.4K 1/16W +-1%(0402)EF'                | 'CHIPR0402'    | ''          | ''            | '20200227'
 '21.5K'      | '1%'      | '1/16W'  | '0402LF'  | 'CHIP'   | 'CS32152FB04'(!)        = ''              | ''                 | 'CS32152FB04'           |'R0402'| '(R0402-0201)'                 | '21.5K'   | '1%'    | '1/16W'  | 'DISCRETE' | 'RES CHIP 21.5K 1/16W +-1%(0402)EF'                | 'CHIPR0402'    | ''          | ''            | '20200302'
 '21.5K'      | '1%'      | '1/16W'  | '0402LF'  | 'EMPTY'  | 'CS32152FB04'(!)        = ''              | ''                 | 'CS32152FB04'           |'R0402'| '(R0402-0201)'                 | '21.5K'   | '1%'    | '1/16W'  | 'IO'       | 'RES CHIP 21.5K 1/16W +-1%(0402)EF'                | 'CHIPR0402'    | ''          | ''            | '20200302'
 '270K'       | '1%'      | '1/16W'  | '0402LF'  | 'CHIP'   | 'CS42702FB01'(!)        = ''              | ''                 | 'CS42702FB01'           |'R0402'| '(R0402-0201)'                 | '270K'    | '1%'    | '1/16W'  | 'DISCRETE' | 'RES CHIP 270K 1/16W +-1%(0402)EF'                 | 'CHIPR0402'    | ''          | ''            | '20200304'
 '270K'       | '1%'      | '1/16W'  | '0402LF'  | 'EMPTY'  | 'CS42702FB01'(!)        = ''              | ''                 | 'CS42702FB01'           |'R0402'| '(R0402-0201)'                 | '270K'    | '1%'    | '1/16W'  | 'IO'       | 'RES CHIP 270K 1/16W +-1%(0402)EF'                 | 'CHIPR0402'    | ''          | ''            | '20200304'
 '0.22'       | '1%'      | '1/2W'   | '1206LF'  | 'CHIP'   | 'CS+2207F202'(!)        = ''              | ''                 | 'CS+2207F202'           |'R1206XJ'| '(SMR1206AW)'                  | '0.22'    | '1%'    | '1/2W'   | 'DISCRETE' | 'RES CHIP 0.22 1/2W +-1%(1206)'                    | 'CHIPR1206'    | ''          | ''            | '20200304'
 '0.22'       | '1%'      | '1/2W'   | '1206LF'  | 'EMPTY'  | 'CS+2207F202'(!)        = ''              | ''                 | 'CS+2207F202'           |'R1206XJ'| '(SMR1206AW)'                  | '0.22'    | '1%'    | '1/2W'   | 'IO'       | 'RES CHIP 0.22 1/2W +-1%(1206)'                    | 'CHIPR1206'    | ''          | ''            | '20200304'
 '4.75'       | '1%'      | '1/16W'  | '0402LF'  | 'CHIP'   | 'CS-4752FB01'(!)        = 'End of Design' | 'Comp-Approve'     | 'CS-4752FB01'           |'R0402'| '(R0402-0201)'                 | '4.75'    | '1%'    | '1/16W'  | 'DISCRETE' | 'RES CHIP 4.75 1/16W +-1%(0402)EF'                 | 'CHIPR0402'    | ''          | ''            | '20200312'
 '4.75'       | '1%'      | '1/16W'  | '0402LF'  | 'EMPTY'  | 'CS-4752FB01'(!)        = 'End of Design' | 'Comp-Approve'     | 'CS-4752FB01'           |'R0402'| '(R0402-0201)'                 | '4.75'    | '1%'    | '1/16W'  | 'IO'       | 'RES CHIP 4.75 1/16W +-1%(0402)EF'                 | 'CHIPR0402'    | ''          | ''            | '20200312'
 '1.3M'       | '1%'      | '1/16W'  | '0402LF'  | 'CHIP'   | 'CS51302FB00'(!)        = ''              | ''                 | 'CS51302FB00'           |'R0402'| '(R0402-0201)'                 | '1.3M'    | '1%'    | '1/16W'  | 'DISCRETE' | 'RES CHIP 1.3M 1/16W +-1%(0402)'                   | 'CHIPR0402'    | ''          | ''            | '20200313'
 '1.3M'       | '1%'      | '1/16W'  | '0402LF'  | 'EMPTY'  | 'CS51302FB00'(!)        = ''              | ''                 | 'CS51302FB00'           |'R0402'| '(R0402-0201)'                 | '1.3M'    | '1%'    | '1/16W'  | 'IO'       | 'RES CHIP 1.3M 1/16W +-1%(0402)'                   | 'CHIPR0402'    | ''          | ''            | '20200313'
 '1.43M'      | '1%'      | '1/16W'  | '0402LF'  | 'CHIP'   | 'CS51432FB10'(!)        = ''              | ''                 | 'CS51432FB10'           |'R0402'| '(R0402-0201)'                 | '1.43M'   | '1%'    | '1/16W'  | 'DISCRETE' | 'RES CHIP 1.43M 1/16W+-1%(0402)'                   | 'CHIPR0402'    | ''          | ''            | '20200313'
 '1.43M'      | '1%'      | '1/16W'  | '0402LF'  | 'EMPTY'  | 'CS51432FB10'(!)        = ''              | ''                 | 'CS51432FB10'           |'R0402'| '(R0402-0201)'                 | '1.43M'   | '1%'    | '1/16W'  | 'IO'       | 'RES CHIP 1.43M 1/16W+-1%(0402)'                   | 'CHIPR0402'    | ''          | ''            | '20200313'
 '976'        | '0.1%'    | '1/16W'  | '0402LF'  | 'CHIP'   | 'CS19762BB00'(!)        = ''              | ''                 | 'CS19762BB00'           |'R0402'| '(R0402-0201)'                 | '976'     | '0.1%'  | '1/16W'  | 'DISCRETE' | 'RES CHIP 976 1/16W  +-0.1%(0402)'                 | 'CHIPR0402'    | ''          | ''            | '20170829'
 '976'        | '0.1%'    | '1/16W'  | '0402LF'  | 'EMPTY'  | 'CS19762BB00'(!)        = ''              | ''                 | 'CS19762BB00'           |'R0402'| '(R0402-0201)'                 | '976'     | '0.1%'  | '1/16W'  | 'IO'       | 'RES CHIP 976 1/16W  +-0.1%(0402)'                 | 'CHIPR0402'    | ''          | ''            | '20170829'
 '3.3'        | '1%'      | '1/16W'  | '0402LF'  | 'CHIP'   | 'CS-3302FB00'(!)        = 'End of Design' | 'Comp-Approve'     | 'CS-3302FB00'           |'R0402'| '(R0402-0201)'                 | '3.3'     | '1%'    | '1/16W'  | 'DISCRETE' | 'RES CHIP 3.3 1/16W +-1% (0402)'                   | 'CHIPR0402'    | ''          | ''            | '20200319'
 '3.3'        | '1%'      | '1/16W'  | '0402LF'  | 'EMPTY'  | 'CS-3302FB00'(!)        = 'End of Design' | 'Comp-Approve'     | 'CS-3302FB00'           |'R0402'| '(R0402-0201)'                 | '3.3'     | '1%'    | '1/16W'  | 'IO'       | 'RES CHIP 3.3 1/16W +-1% (0402)'                   | 'CHIPR0402'    | ''          | ''            | '20200319'
 '100'        | '1%'      | '1/4W'   | '1206LF'  | 'CHIP'   | 'CS11006F216'(!)        = ''              | ''                 | 'CS11006F216'           |'R1206XM'| '(SMR1206AW)'                  | '100'     | '1%'    | '1/4W'   | 'DISCRETE' | 'RES CHIP 100 1/4W +-1%(1206)'                     | 'CHIPR1206'    | ''          | ''            | '20200323'
 '100'        | '1%'      | '1/4W'   | '1206LF'  | 'EMPTY'  | 'CS11006F216'(!)        = ''              | ''                 | 'CS11006F216'           |'R1206XM'| '(SMR1206AW)'                  | '100'     | '1%'    | '1/4W'   | 'IO'       | 'RES CHIP 100 1/4W +-1%(1206)'                     | 'CHIPR1206'    | ''          | ''            | '20200323'
 '5.76K'      | '1%'      | '1/16W'  | '0402LF'  | 'CHIP'   | 'CS25762FB04'(!)        = 'End of Design' | 'Comp-Approve'     | 'CS25762FB04'           |'R0402'| '(R0402-0201)'                 | '5.76K'   | '1%'    | '1/16W'  | 'DISCRETE' | 'RES CHIP 5.76K 1/16W +-1%(0402)EF'                | 'CHIPR0402'    | ''          | ''            | '20200320'
 '5.76K'      | '1%'      | '1/16W'  | '0402LF'  | 'EMPTY'  | 'CS25762FB04'(!)        = 'End of Design' | 'Comp-Approve'     | 'CS25762FB04'           |'R0402'| '(R0402-0201)'                 | '5.76K'   | '1%'    | '1/16W'  | 'IO'       | 'RES CHIP 5.76K 1/16W +-1%(0402)EF'                | 'CHIPR0402'    | ''          | ''            | '20200320'
 '4.7K'       | '1%'      | '1/20W'  | '0201LF'  | 'CHIP'   | 'CS24701FE00'(!)        = ''              | ''                 | 'CS24701FE00'           |'R0201'| '(SMR0201AW)'                  | '4.7K'    | '1%'    | '1/20W'  | 'DISCRETE' | 'RES CHIP 4.7K 1/20W +-1%(0201)'                   | 'CHIPR0201'    | ''          | ''            | '20200326'
 '4.7K'       | '1%'      | '1/20W'  | '0201LF'  | 'EMPTY'  | 'CS24701FE00'(!)        = ''              | ''                 | 'CS24701FE00'           |'R0201'| '(SMR0201AW)'                  | '4.7K'    | '1%'    | '1/20W'  | 'IO'       | 'RES CHIP 4.7K 1/20W +-1%(0201)'                   | 'CHIPR0201'    | ''          | ''            | '20200326'
 '30K'        | '1%'      | '1/20W'  | '0201LF'  | 'CHIP'   | 'CS33001FE00'(!)        = 'End of Design' | 'Comp-Approve'     | 'CS33001FE00'           |'R0201'| '(SMR0201AW)'                  | '30K'     | '1%'    | '1/20W'  | 'DISCRETE' | 'RES CHIP 30K 1/20W +-1% (0201)'                   | 'CHIPR0201'    | ''          | ''            | '20200326'
 '30K'        | '1%'      | '1/20W'  | '0201LF'  | 'EMPTY'  | 'CS33001FE00'(!)        = 'End of Design' | 'Comp-Approve'     | 'CS33001FE00'           |'R0201'| '(SMR0201AW)'                  | '30K'     | '1%'    | '1/20W'  | 'IO'       | 'RES CHIP 30K 1/20W +-1% (0201)'                   | 'CHIPR0201'    | ''          | ''            | '20200326'
 '162'        | '1%'      | '1/16W'  | '0402LF'  | 'CHIP'   | 'CS11622FB09'(!)        = ''              | ''                 | 'CS11622FB09'           |'R0402'| '(R0402-0201)'                 | '162'     | '1%'    | '1/16W'  | 'DISCRETE' | 'RES CHIP 162 1/16W +-1% (0402)YGO'                | 'CHIPR0402'    | ''          | ''            | '20200324'
 '162'        | '1%'      | '1/16W'  | '0402LF'  | 'EMPTY'  | 'CS11622FB09'(!)        = ''              | ''                 | 'CS11622FB09'           |'R0402'| '(R0402-0201)'                 | '162'     | '1%'    | '1/16W'  | 'IO'       | 'RES CHIP 162 1/16W +-1% (0402)YGO'                | 'CHIPR0402'    | ''          | ''            | '20200324'
 '681'        | '1%'      | '1/16W'  | '0402LF'  | 'CHIP'   | 'CS16812FB07'(!)        = ''              | ''                 | 'CS16812FB07'           |'R0402'| '(R0402-0201)'                 | '681'     | '1%'    | '1/16W'  | 'DISCRETE' | 'RES CHIP 681 1/16W +-1% (0402)YGO'                | 'CHIPR0402'    | ''          | ''            | '20200325'
 '681'        | '1%'      | '1/16W'  | '0402LF'  | 'EMPTY'  | 'CS16812FB07'(!)        = ''              | ''                 | 'CS16812FB07'           |'R0402'| '(R0402-0201)'                 | '681'     | '1%'    | '1/16W'  | 'IO'       | 'RES CHIP 681 1/16W +-1% (0402)YGO'                | 'CHIPR0402'    | ''          | ''            | '20200325'
 '2.8K'       | '1%'      | '1/16W'  | '0402LF'  | 'CHIP'   | 'CS22802FB07'(!)        = ''              | ''                 | 'CS22802FB07'           |'R0402'| '(R0402-0201)'                 | '2.8K'    | '1%'    | '1/16W'  | 'DISCRETE' | 'RES CHIP 2.8K 1/16W +-1%(0402)YGO'                | 'CHIPR0402'    | ''          | ''            | '20200325'
 '2.8K'       | '1%'      | '1/16W'  | '0402LF'  | 'EMPTY'  | 'CS22802FB07'(!)        = ''              | ''                 | 'CS22802FB07'           |'R0402'| '(R0402-0201)'                 | '2.8K'    | '1%'    | '1/16W'  | 'IO'       | 'RES CHIP 2.8K 1/16W +-1%(0402)YGO'                | 'CHIPR0402'    | ''          | ''            | '20200325'
 '3.3'        | '1%'      | '1/2W'   | '1206LF'  | 'CHIP'   | 'CS-3307F200'(!)        = ''              | ''                 | 'CS-3307F200'           |'R1206XN'| '(SMR1206AW)'                  | '3.3'     | '1%'    | '1/2W'   | 'DISCRETE' | 'RES CHIP 3.3 1/2W+-1%(1206)SR'                    | 'CHIPR1206'    | ''          | ''            | '20200330'
 '3.3'        | '1%'      | '1/2W'   | '1206LF'  | 'EMPTY'  | 'CS-3307F200'(!)        = ''              | ''                 | 'CS-3307F200'           |'R1206XN'| '(SMR1206AW)'                  | '3.3'     | '1%'    | '1/2W'   | 'IO'       | 'RES CHIP 3.3 1/2W+-1%(1206)SR'                    | 'CHIPR1206'    | ''          | ''            | '20200330'
 '475K'       | '1%'      | '1/10W'  | '0603LF'  | 'CHIP'   | 'CS44753F912'(!)        = ''              | ''                 | 'CS44753F912'           |'R0603'| '(SMR0603AW)'                  | '475K'    | '1%'    | '1/10W'  | 'DISCRETE' | 'RES CHIP 475K 1/10W +-1%(0603)'                   | 'CHIPR0603'    | ''          | ''            | '20200401'
 '475K'       | '1%'      | '1/10W'  | '0603LF'  | 'EMPTY'  | 'CS44753F912'(!)        = ''              | ''                 | 'CS44753F912'           |'R0603'| '(SMR0603AW)'                  | '475K'    | '1%'    | '1/10W'  | 'IO'       | 'RES CHIP 475K 1/10W +-1%(0603)'                   | 'CHIPR0603'    | ''          | ''            | '20200401'
 '124'        | '1%'      | '1/16W'  | '0402LF'  | 'CHIP'   | 'CS11242FB10'(!)        = 'End of Design' | 'Comp-Approve'     | 'CS11242FB10'           |'R0402'| '(R0402-0201)'                 | '124'     | '1%'    | '1/16W'  | 'DISCRETE' | 'RES CHIP 124 1/16W +-1%(0402)'                    | 'CHIPR0402'    | ''          | ''            | '20200409'
 '124'        | '1%'      | '1/16W'  | '0402LF'  | 'EMPTY'  | 'CS11242FB10'(!)        = 'End of Design' | 'Comp-Approve'     | 'CS11242FB10'           |'R0402'| '(R0402-0201)'                 | '124'     | '1%'    | '1/16W'  | 'IO'       | 'RES CHIP 124 1/16W +-1%(0402)'                    | 'CHIPR0402'    | ''          | ''            | '20200409'
 '3.3'        | '1%'      | '1/4W'   | '0603LF'  | 'CHIP'   | 'CS-3306F900'(!)        = ''              | ''                 | 'CS-3306F900'           |'R0603'| '(SMR0603AW)'                  | '3.3'     | '1%'    | '1/4W'   | 'DISCRETE' | 'RES CHIP 3.3 1/4W+-1%(0603)SR'                    | 'CHIPR0603'    | ''          | ''            | '20200414'
 '3.3'        | '1%'      | '1/4W'   | '0603LF'  | 'EMPTY'  | 'CS-3306F900'(!)        = ''              | ''                 | 'CS-3306F900'           |'R0603'| '(SMR0603AW)'                  | '3.3'     | '1%'    | '1/4W'   | 'IO'       | 'RES CHIP 3.3 1/4W+-1%(0603)SR'                    | 'CHIPR0603'    | ''          | ''            | '20200414'
 '330'        | '5%'      | '1/2W'   | '1206LF'  | 'CHIP'   | 'CS13307J200'(!)        = ''              | ''                 | 'CS13307J200'           |'R1206XN'| '(SMR1206AW)'                  | '330'     | '5%'    | '1/2W'   | 'DISCRETE' | 'RES CHIP 330 1/2W+-5%(1206)SR'                    | 'CHIPR1206'    | ''          | ''            | '20200424'
 '330'        | '5%'      | '1/2W'   | '1206LF'  | 'EMPTY'  | 'CS13307J200'(!)        = ''              | ''                 | 'CS13307J200'           |'R1206XN'| '(SMR1206AW)'                  | '330'     | '5%'    | '1/2W'   | 'IO'       | 'RES CHIP 330 1/2W+-5%(1206)SR'                    | 'CHIPR1206'    | ''          | ''            | '20200424'
 '3.3'        | '5%'      | '1/5W'   | '0603LF'  | 'CHIP'   | 'CS-330GJ900'(!)        = ''              | ''                 | 'CS-330GJ900'           |'R0603'| '(SMR0603AW)'                  | '3.3'     | '5%'    | '1/5W'   | 'DISCRETE' | 'RES CHIP 3.3 1/5W+-5%(0603)SR'                    | 'CHIPR0603'    | ''          | ''            | '20200429'
 '3.3'        | '5%'      | '1/5W'   | '0603LF'  | 'EMPTY'  | 'CS-330GJ900'(!)        = ''              | ''                 | 'CS-330GJ900'           |'R0603'| '(SMR0603AW)'                  | '3.3'     | '5%'    | '1/5W'   | 'IO'       | 'RES CHIP 3.3 1/5W+-5%(0603)SR'                    | 'CHIPR0603'    | ''          | ''            | '20200429'
 '1.5'        | '5%'      | '1/4W'   | '0603LF'  | 'CHIP'   | 'CS-1506J900'(!)        = ''              | ''                 | 'CS-1506J900'           |'R0603'| '(SMR0603AW)'                  | '1.5'     | '5%'    | '1/4W'   | 'DISCRETE' | 'RES CHIP 1.5 1/4W+-5%(0603)SR'                    | 'CHIPR0603'    | ''          | ''            | '20200505'
 '1.5'        | '5%'      | '1/4W'   | '0603LF'  | 'EMPTY'  | 'CS-1506J900'(!)        = ''              | ''                 | 'CS-1506J900'           |'R0603'| '(SMR0603AW)'                  | '1.5'     | '5%'    | '1/4W'   | 'IO'       | 'RES CHIP 1.5 1/4W+-5%(0603)SR'                    | 'CHIPR0603'    | ''          | ''            | '20200505'
 '3.65K'      | '1%'      | '1/16W'  | '0402LF'  | 'CHIP'   | 'CS23652FB03'(!)        = ''              | ''                 | 'CS23652FB03'           |'R0402'| '(R0402-0201)'                 | '3.65K'   | '1%'    | '1/16W'  | 'DISCRETE' | 'RES CHIP 3.65K 1/16W +-1%(0402)EF'                | 'CHIPR0402'    | ''          | ''            | '20200508'
 '3.65K'      | '1%'      | '1/16W'  | '0402LF'  | 'EMPTY'  | 'CS23652FB03'(!)        = ''              | ''                 | 'CS23652FB03'           |'R0402'| '(R0402-0201)'                 | '3.65K'   | '1%'    | '1/16W'  | 'IO'       | 'RES CHIP 3.65K 1/16W +-1%(0402)EF'                | 'CHIPR0402'    | ''          | ''            | '20200508'
 '0.01'       | '1%'      | '1W'     | '1206LF'  | 'CHIP'   | 'CS+0108F207'(!)        = ''              | ''                 | 'CS+0108F207'           |'R1206XO'| '(SMR1206AW)'                  | '0.01'    | '1%'    | '1W'     | 'DISCRETE' | 'RES CHIP 0.01 1W +-1%(1206)EF'                    | 'CHIPR1206'    | ''          | ''            | '20191224'
 '0.01'       | '1%'      | '1W'     | '1206LF'  | 'EMPTY'  | 'CS+0108F207'(!)        = ''              | ''                 | 'CS+0108F207'           |'R1206XO'| '(SMR1206AW)'                  | '0.01'    | '1%'    | '1W'     | 'IO'       | 'RES CHIP 0.01 1W +-1%(1206)EF'                    | 'CHIPR1206'    | ''          | ''            | '20191224'
 '1.58M'      | '1%'      | '1/8W'   | '0805LF'  | 'CHIP'   | 'CS51584FA00'(!)        = ''              | ''                 | 'CS51584FA00'           |'R0805'| '(SMR0805AW)'                  | '1.58M'   | '1%'    | '1/8W'   | 'DISCRETE' | 'RES CHIP 1.58M 1/8W +-1%(0805)'                   | 'CHIPR0805'    | ''          | ''            | '20200514'
 '1.58M'      | '1%'      | '1/8W'   | '0805LF'  | 'EMPTY'  | 'CS51584FA00'(!)        = ''              | ''                 | 'CS51584FA00'           |'R0805'| '(SMR0805AW)'                  | '1.58M'   | '1%'    | '1/8W'   | 'IO'       | 'RES CHIP 1.58M 1/8W +-1%(0805)'                   | 'CHIPR0805'    | ''          | ''            | '20200514'
 '1.5K'       | '1%'      | '1/4W'   | '1206LF'  | 'CHIP'   | 'CS21506F200'(!)        = ''              | ''                 | 'CS21506F200'           |'R1206XM'| '(SMR1206AW)'                  | '1.5K'    | '1%'    | '1/4W'   | 'DISCRETE' | 'RES CHIP 1.5K 1/4W +-1%(1206)'                    | 'CHIPR1206'    | ''          | ''            | '20200518'
 '1.5K'       | '1%'      | '1/4W'   | '1206LF'  | 'EMPTY'  | 'CS21506F200'(!)        = ''              | ''                 | 'CS21506F200'           |'R1206XM'| '(SMR1206AW)'                  | '1.5K'    | '1%'    | '1/4W'   | 'IO'       | 'RES CHIP 1.5K 1/4W +-1%(1206)'                    | 'CHIPR1206'    | ''          | ''            | '20200518'
 '0.001'      | '1%'      | '3W'     | '2512LF'  | 'CHIP'   | 'CS+001DFR07'(!)        = ''              | ''                 | 'CS+001DFR07'           |'R2512XW'| '(SMR2512AW)'                  | '0.001'   | '1%'    | '3W'     | 'DISCRETE' | 'RES CHIP 0.001 3W +-1%(2512)YGO AEC'              | 'CHIPR2512'    | ''          | ''            | '20200527'
 '0.001'      | '1%'      | '3W'     | '2512LF'  | 'EMPTY'  | 'CS+001DFR07'(!)        = ''              | ''                 | 'CS+001DFR07'           |'R2512XW'| '(SMR2512AW)'                  | '0.001'   | '1%'    | '3W'     | 'IO'       | 'RES CHIP 0.001 3W +-1%(2512)YGO AEC'              | 'CHIPR2512'    | ''          | ''            | '20200527'
 '45.3K'      | '1%'      | '1/16W'  | '0402LF'  | 'CHIP'   | 'CS34532FB08'(!)        = ''              | ''                 | 'CS34532FB08'           |'R0402'| '(R0402-0201)'                 | '45.3K'   | '1%'    | '1/16W'  | 'DISCRETE' | 'RES CHIP 45.3K 1/16W +-1%(0402)EF'                | 'CHIPR0402'    | ''          | ''            | '20200602'
 '45.3K'      | '1%'      | '1/16W'  | '0402LF'  | 'EMPTY'  | 'CS34532FB08'(!)        = ''              | ''                 | 'CS34532FB08'           |'R0402'| '(R0402-0201)'                 | '45.3K'   | '1%'    | '1/16W'  | 'IO'       | 'RES CHIP 45.3K 1/16W +-1%(0402)EF'                | 'CHIPR0402'    | ''          | ''            | '20200602'
 '107K'       | '1%'      | '1/16W'  | '0402LF'  | 'CHIP'   | 'CS41072FB05'(!)        = ''              | ''                 | 'CS41072FB05'           |'R0402'| '(R0402-0201)'                 | '107K'    | '1%'    | '1/16W'  | 'DISCRETE' | 'RES CHIP 107K 1/16W +-1%(0402)EF'                 | 'CHIPR0402'    | ''          | ''            | '20200602'
 '107K'       | '1%'      | '1/16W'  | '0402LF'  | 'EMPTY'  | 'CS41072FB05'(!)        = ''              | ''                 | 'CS41072FB05'           |'R0402'| '(R0402-0201)'                 | '107K'    | '1%'    | '1/16W'  | 'IO'       | 'RES CHIP 107K 1/16W +-1%(0402)EF'                 | 'CHIPR0402'    | ''          | ''            | '20200602'
 '91K'        | '1%'      | '1/16W'  | '0402LF'  | 'CHIP'   | 'CS39102FB06'(!)        = ''              | ''                 | 'CS39102FB06'           |'R0402'| '(R0402-0201)'                 | '91K'     | '1%'    | '1/16W'  | 'DISCRETE' | 'RES CHIP 91K 1/16W +-1%(0402)EF'                  | 'CHIPR0402'    | ''          | ''            | '20200602'
 '91K'        | '1%'      | '1/16W'  | '0402LF'  | 'EMPTY'  | 'CS39102FB06'(!)        = ''              | ''                 | 'CS39102FB06'           |'R0402'| '(R0402-0201)'                 | '91K'     | '1%'    | '1/16W'  | 'IO'       | 'RES CHIP 91K 1/16W +-1%(0402)EF'                  | 'CHIPR0402'    | ''          | ''            | '20200602'
 '20.5K'      | '1%'      | '1/16W'  | '0402LF'  | 'CHIP'   | 'CS32052FB02'(!)        = 'End of Design' | 'Comp-Approve'     | 'CS32052FB02'           |'R0402'| '(R0402-0201)'                 | '20.5K'   | '1%'    | '1/16W'  | 'DISCRETE' | 'RES CHIP 20.5K 1/16W +-1%(0402)EF'                | 'CHIPR0402'    | ''          | ''            | '20200602'
 '20.5K'      | '1%'      | '1/16W'  | '0402LF'  | 'EMPTY'  | 'CS32052FB02'(!)        = 'End of Design' | 'Comp-Approve'     | 'CS32052FB02'           |'R0402'| '(R0402-0201)'                 | '20.5K'   | '1%'    | '1/16W'  | 'IO'       | 'RES CHIP 20.5K 1/16W +-1%(0402)EF'                | 'CHIPR0402'    | ''          | ''            | '20200602'
 '0.0003'     | '1%'      | '4W'     | '2725LF'  | 'CHIP'   | 'CS0000FFT10'(!)        = 'End of Design' | 'Comp-Approve'     | 'CS0000FFT10'           |'R2725XA'| '(SMR2725AW)'                  | '0.0003'  | '1%'    | '4W'     | 'DISCRETE' | 'RES CHIP 0.0003 4W +-1%(2725)ERO'                 | 'CHIPR2725'    | ''          | ''            | '20200609'
 '0.0003'     | '1%'      | '4W'     | '2725LF'  | 'EMPTY'  | 'CS0000FFT10'(!)        = 'End of Design' | 'Comp-Approve'     | 'CS0000FFT10'           |'R2725XA'| '(SMR2725AW)'                  | '0.0003'  | '1%'    | '4W'     | 'IO'       | 'RES CHIP 0.0003 4W +-1%(2725)ERO'                 | 'CHIPR2725'    | ''          | ''            | '20200609'
 '0.0003'     | '1%'      | '4W'     | '2725LF'  | 'CHIP'   | 'CS0000FFT09'(!)        = ''              | ''                 | 'CS0000FFT09'           |'R2725'| '(SMR2725AW)'                  | '0.0003'  | '1%'    | '4W'     | 'DISCRETE' | 'RES CHIP 0.0003 4W +-1%(2725)RLC'                 | 'CHIPR2725'    | ''          | ''            | '20200609'
 '0.0003'     | '1%'      | '4W'     | '2725LF'  | 'EMPTY'  | 'CS0000FFT09'(!)        = ''              | ''                 | 'CS0000FFT09'           |'R2725'| '(SMR2725AW)'                  | '0.0003'  | '1%'    | '4W'     | 'IO'       | 'RES CHIP 0.0003 4W +-1%(2725)RLC'                 | 'CHIPR2725'    | ''          | ''            | '20200609'
 '4.64K'      | '1%'      | '1/16W'  | '0402LF'  | 'CHIP'   | 'CS24642FB01'(!)        = 'End of Design' | 'Comp-Approve'     | 'CS24642FB01'           |'R0402'| '(R0402-0201)'                 | '4.64K'   | '1%'    | '1/16W'  | 'DISCRETE' | 'RES CHIP 4.64K 1/16W +-1%(0402)EF'                | 'CHIPR0402'    | ''          | ''            | '20200609'
 '4.64K'      | '1%'      | '1/16W'  | '0402LF'  | 'EMPTY'  | 'CS24642FB01'(!)        = 'End of Design' | 'Comp-Approve'     | 'CS24642FB01'           |'R0402'| '(R0402-0201)'                 | '4.64K'   | '1%'    | '1/16W'  | 'IO'       | 'RES CHIP 4.64K 1/16W +-1%(0402)EF'                | 'CHIPR0402'    | ''          | ''            | '20200609'
 '7.15K'      | '1%'      | '1/16W'  | '0402LF'  | 'CHIP'   | 'CS27152FB03'(!)        = 'End of Design' | 'Comp-Approve'     | 'CS27152FB03'           |'R0402'| '(R0402-0201)'                 | '7.15K'   | '1%'    | '1/16W'  | 'DISCRETE' | 'RES CHIP 7.15K 1/16W +-1%(0402)EF'                | 'CHIPR0402'    | ''          | ''            | '20200609'
 '7.15K'      | '1%'      | '1/16W'  | '0402LF'  | 'EMPTY'  | 'CS27152FB03'(!)        = 'End of Design' | 'Comp-Approve'     | 'CS27152FB03'           |'R0402'| '(R0402-0201)'                 | '7.15K'   | '1%'    | '1/16W'  | 'IO'       | 'RES CHIP 7.15K 1/16W +-1%(0402)EF'                | 'CHIPR0402'    | ''          | ''            | '20200609'
 '100'        | '5%'      | '1/10W'  | '0603LF'  | 'CHIP'   | 'CS11003J903'(!)        = ''              | ''                 | 'CS11003J903'           |'R0603_H24'| '(SMR0603AW)'                  | '100'     | '5%'    | '1/10W'  | 'DISCRETE' | 'RES CHIP 100 1/10W +-5%(0603)EF'                  | 'CHIPR0603'    | ''          | ''            | '20200609'
 '100'        | '5%'      | '1/10W'  | '0603LF'  | 'EMPTY'  | 'CS11003J903'(!)        = ''              | ''                 | 'CS11003J903'           |'R0603_H24'| '(SMR0603AW)'                  | '100'     | '5%'    | '1/10W'  | 'IO'       | 'RES CHIP 100 1/10W +-5%(0603)EF'                  | 'CHIPR0603'    | ''          | ''            | '20200609'
 '6.49K'      | '1%'      | '1/16W'  | '0402LF'  | 'CHIP'   | 'CS26492FB06'(!)        = 'End of Design' | 'Comp-Approve'     | 'CS26492FB06'           |'R0402'| '(R0402-0201)'                 | '6.49K'   | '1%'    | '1/16W'  | 'DISCRETE' | 'RES CHIP 6.49K 1/16W +-1%(0402)EF'                | 'CHIPR0402'    | ''          | ''            | '20200611'
 '6.49K'      | '1%'      | '1/16W'  | '0402LF'  | 'EMPTY'  | 'CS26492FB06'(!)        = 'End of Design' | 'Comp-Approve'     | 'CS26492FB06'           |'R0402'| '(R0402-0201)'                 | '6.49K'   | '1%'    | '1/16W'  | 'IO'       | 'RES CHIP 6.49K 1/16W +-1%(0402)EF'                | 'CHIPR0402'    | ''          | ''            | '20200611'
 '16.9K'      | '1%'      | '1/16W'  | '0402LF'  | 'CHIP'   | 'CS31692FB03'(!)        = 'End of Design' | 'Comp-Approve'     | 'CS31692FB03'           |'R0402'| '(R0402-0201)'                 | '16.9K'   | '1%'    | '1/16W'  | 'DISCRETE' | 'RES CHIP 16.9K 1/16W +-1%(0402)EF'                | 'CHIPR0402'    | ''          | ''            | '20200615'
 '16.9K'      | '1%'      | '1/16W'  | '0402LF'  | 'EMPTY'  | 'CS31692FB03'(!)        = 'End of Design' | 'Comp-Approve'     | 'CS31692FB03'           |'R0402'| '(R0402-0201)'                 | '16.9K'   | '1%'    | '1/16W'  | 'IO'       | 'RES CHIP 16.9K 1/16W +-1%(0402)EF'                | 'CHIPR0402'    | ''          | ''            | '20200615'
 '5.1'        | '1%'      | '1/16W'  | '0402LF'  | 'CHIP'   | 'CS-5102FB00'(!)        = 'End of Design' | 'Comp-Approve'     | 'CS-5102FB00'           |'R0402'| '(R0402-0201)'                 | '5.1'     | '1%'    | '1/16W'  | 'DISCRETE' | 'RES CHIP 5.1 1/16W +-1%(0402)'                    | 'CHIPR0402'    | ''          | ''            | '20200707'
 '5.1'        | '1%'      | '1/16W'  | '0402LF'  | 'EMPTY'  | 'CS-5102FB00'(!)        = 'End of Design' | 'Comp-Approve'     | 'CS-5102FB00'           |'R0402'| '(R0402-0201)'                 | '5.1'     | '1%'    | '1/16W'  | 'IO'       | 'RES CHIP 5.1 1/16W +-1%(0402)'                    | 'CHIPR0402'    | ''          | ''            | '20200707'
 '1'          | '1%'      | '1/4W'   | '0603LF'  | 'CHIP'   | 'CS-1006F900'(!)        = ''              | ''                 | 'CS-1006F900'           |'R0603'| '(SMR0603AW)'                  | '1'       | '1%'    | '1/4W'   | 'DISCRETE' | 'RES CHIP 1 1/4W+-1%(0603)SR'                      | 'CHIPR0603'    | ''          | ''            | '20200707'
 '1'          | '1%'      | '1/4W'   | '0603LF'  | 'EMPTY'  | 'CS-1006F900'(!)        = ''              | ''                 | 'CS-1006F900'           |'R0603'| '(SMR0603AW)'                  | '1'       | '1%'    | '1/4W'   | 'IO'       | 'RES CHIP 1 1/4W+-1%(0603)SR'                      | 'CHIPR0603'    | ''          | ''            | '20200707'
 '820'        | '1%'      | '1/16W'  | '0402LF'  | 'CHIP'   | 'CS18202FB00'(!)        = 'End of Design' | 'Comp-Approve'     | 'CS18202FB00'           |'R0402'| '(R0402-0201)'                 | '820'     | '1%'    | '1/16W'  | 'DISCRETE' | 'RES CHIP 820 1/16W +-1%(0402)'                    | 'CHIPR0402'    | ''          | ''            | '20200715'
 '820'        | '1%'      | '1/16W'  | '0402LF'  | 'EMPTY'  | 'CS18202FB00'(!)        = 'End of Design' | 'Comp-Approve'     | 'CS18202FB00'           |'R0402'| '(R0402-0201)'                 | '820'     | '1%'    | '1/16W'  | 'IO'       | 'RES CHIP 820 1/16W +-1%(0402)'                    | 'CHIPR0402'    | ''          | ''            | '20200715'
 '1'          | '5%'      | '1/2W'   | '1206LF'  | 'CHIP'   | 'CS-1007J200'(!)        = ''              | ''                 | 'CS-1007J200'           |'R1206XN'| '(SMR1206AW)'                  | '1'       | '5%'    | '1/2W'   | 'DISCRETE' | 'RES CHIP 1 1/2W+-5%(1206)SR'                      | 'CHIPR1206'    | ''          | ''            | '20200715'
 '1'          | '5%'      | '1/2W'   | '1206LF'  | 'EMPTY'  | 'CS-1007J200'(!)        = ''              | ''                 | 'CS-1007J200'           |'R1206XN'| '(SMR1206AW)'                  | '1'       | '5%'    | '1/2W'   | 'IO'       | 'RES CHIP 1 1/2W+-5%(1206)SR'                      | 'CHIPR1206'    | ''          | ''            | '20200715'
 '34.8K'      | '1%'      | '1/16W'  | '0402LF'  | 'CHIP'   | 'CS33482FB04'(!)        = ''              | ''                 | 'CS33482FB04'           |'R0402'| '(R0402-0201)'                 | '34.8K'   | '1%'    | '1/16W'  | 'DISCRETE' | 'RES CHIP 34.8K 1/16W +-1%(0402)EF'                | 'CHIPR0402'    | ''          | ''            | '20200728'
 '34.8K'      | '1%'      | '1/16W'  | '0402LF'  | 'EMPTY'  | 'CS33482FB04'(!)        = ''              | ''                 | 'CS33482FB04'           |'R0402'| '(R0402-0201)'                 | '34.8K'   | '1%'    | '1/16W'  | 'IO'       | 'RES CHIP 34.8K 1/16W +-1%(0402)EF'                | 'CHIPR0402'    | ''          | ''            | '20200728'
 '0.68'       | '1%'      | '1/10W'  | '0603LF'  | 'CHIP'   | 'CS+6803F900'(!)        = ''              | ''                 | 'CS+6803F900'           |'R0603_H24'| '(SMR0603AW)'                  | '0.68'    | '1%'    | '1/10W'  | 'DISCRETE' | 'RES CHIP 0.68 1/10W+-1%(0603)EF'                  | 'CHIPR0603'    | ''          | ''            | '20200803'
 '0.68'       | '1%'      | '1/10W'  | '0603LF'  | 'EMPTY'  | 'CS+6803F900'(!)        = ''              | ''                 | 'CS+6803F900'           |'R0603_H24'| '(SMR0603AW)'                  | '0.68'    | '1%'    | '1/10W'  | 'IO'       | 'RES CHIP 0.68 1/10W+-1%(0603)EF'                  | 'CHIPR0603'    | ''          | ''            | '20200803'
 '24K'        | '1%'      | '1/10W'  | '0603LF'  | 'CHIP'   | 'CS32403F911'(!)        = 'End of Design' | 'Comp-Approve'     | 'CS32403F911'           |'R0603'| '(SMR0603AW)'                  | '24K'     | '1%'    | '1/10W'  | 'DISCRETE' | 'RES CHIP 24K 1/10W +-1%(0603)'                    | 'CHIPR0603'    | ''          | ''            | '20200810'
 '24K'        | '1%'      | '1/10W'  | '0603LF'  | 'EMPTY'  | 'CS32403F911'(!)        = 'End of Design' | 'Comp-Approve'     | 'CS32403F911'           |'R0603'| '(SMR0603AW)'                  | '24K'     | '1%'    | '1/10W'  | 'IO'       | 'RES CHIP 24K 1/10W +-1%(0603)'                    | 'CHIPR0603'    | ''          | ''            | '20200810'
 '1.1K'       | '1%'      | '1/16W'  | '0402LF'  | 'CHIP'   | 'CS21102FB04'(!)        = 'End of Design' | 'Comp-Approve'     | 'CS21102FB04'           |'R0402'| '(R0402-0201)'                 | '1.1K'    | '1%'    | '1/16W'  | 'DISCRETE' | 'RES CHIP 1.1K 1/16W +-1% (0402)EF'                | 'CHIPR0402'    | ''          | ''            | '20200810'
 '1.1K'       | '1%'      | '1/16W'  | '0402LF'  | 'EMPTY'  | 'CS21102FB04'(!)        = 'End of Design' | 'Comp-Approve'     | 'CS21102FB04'           |'R0402'| '(R0402-0201)'                 | '1.1K'    | '1%'    | '1/16W'  | 'IO'       | 'RES CHIP 1.1K 1/16W +-1% (0402)EF'                | 'CHIPR0402'    | ''          | ''            | '20200810'
 '49.9'       | '1%'      | '1/4W'   | '1206LF'  | 'CHIP'   | 'CS04996F200'(!)        = ''              | ''                 | 'CS04996F200'           |'R1206XJ'| '(SMR1206AW)'                  | '49.9'    | '1%'    | '1/4W'   | 'DISCRETE' | 'RES CHIP 49.9 1/4W+-1%(1206)'                     | 'CHIPR1206'    | ''          | ''            | '20200811'
 '49.9'       | '1%'      | '1/4W'   | '1206LF'  | 'EMPTY'  | 'CS04996F200'(!)        = ''              | ''                 | 'CS04996F200'           |'R1206XJ'| '(SMR1206AW)'                  | '49.9'    | '1%'    | '1/4W'   | 'IO'       | 'RES CHIP 49.9 1/4W+-1%(1206)'                     | 'CHIPR1206'    | ''          | ''            | '20200811'
 '330'        | '1%'      | '1/8W'   | '0805LF'  | 'CHIP'   | 'CS13304FA00'(!)        = ''              | ''                 | 'CS13304FA00'           |'R0805_H26'| '(SMR0805AW)'                  | '330'     | '1%'    | '1/8W'   | 'DISCRETE' | 'RES CHIP 330 1/8W +-1%(0805)'                     | 'CHIPR0805'    | ''          | ''            | '20200811'
 '330'        | '1%'      | '1/8W'   | '0805LF'  | 'EMPTY'  | 'CS13304FA00'(!)        = ''              | ''                 | 'CS13304FA00'           |'R0805_H26'| '(SMR0805AW)'                  | '330'     | '1%'    | '1/8W'   | 'IO'       | 'RES CHIP 330 1/8W +-1%(0805)'                     | 'CHIPR0805'    | ''          | ''            | '20200811'
 '68K'        | '1%'      | '1/10W'  | '0603LF'  | 'CHIP'   | 'CS36803F917'(!)        = 'End of Design' | 'Comp-Approve'     | 'CS36803F917'           |'R0603'| '(SMR0603AW)'                  | '68K'     | '1%'    | '1/10W'  | 'DISCRETE' | 'RES CHIP 68K 1/10W +-1%(0603)'                    | 'CHIPR0603'    | ''          | ''            | '20200811'
 '68K'        | '1%'      | '1/10W'  | '0603LF'  | 'EMPTY'  | 'CS36803F917'(!)        = 'End of Design' | 'Comp-Approve'     | 'CS36803F917'           |'R0603'| '(SMR0603AW)'                  | '68K'     | '1%'    | '1/10W'  | 'IO'       | 'RES CHIP 68K 1/10W +-1%(0603)'                    | 'CHIPR0603'    | ''          | ''            | '20200811'
 '240K'       | '1%'      | '1/10W'  | '0603LF'  | 'CHIP'   | 'CS42403F913'(!)        = 'End of Design' | 'Comp-Approve'     | 'CS42403F913'           |'R0603'| '(SMR0603AW)'                  | '240K'    | '1%'    | '1/10W'  | 'DISCRETE' | 'RESISTOR CHIP 240K 1/10W,+-1%(0603)'              | 'CHIPR0603'    | ''          | ''            | '20200811'
 '240K'       | '1%'      | '1/10W'  | '0603LF'  | 'EMPTY'  | 'CS42403F913'(!)        = 'End of Design' | 'Comp-Approve'     | 'CS42403F913'           |'R0603'| '(SMR0603AW)'                  | '240K'    | '1%'    | '1/10W'  | 'IO'       | 'RESISTOR CHIP 240K 1/10W,+-1%(0603)'              | 'CHIPR0603'    | ''          | ''            | '20200811'
 '604'        | '1%'      | '1/4W'   | '1206LF'  | 'CHIP'   | 'CS16046F200'(!)        = ''              | ''                 | 'CS16046F200'           |'R1206XF'| '(SMR1206AW)'                  | '604'     | '1%'    | '1/4W'   | 'DISCRETE' | 'RES CHIP 604 1/4W +-1%(1206)'                     | 'CHIPR1206'    | ''          | ''            | '20200812'
 '604'        | '1%'      | '1/4W'   | '1206LF'  | 'EMPTY'  | 'CS16046F200'(!)        = ''              | ''                 | 'CS16046F200'           |'R1206XF'| '(SMR1206AW)'                  | '604'     | '1%'    | '1/4W'   | 'IO'       | 'RES CHIP 604 1/4W +-1%(1206)'                     | 'CHIPR1206'    | ''          | ''            | '20200812'
 '0.0005'     | '1%'      | '3W'     | '2512LF'  | 'CHIP'   | 'CS0000DFR02'(!)        = 'End of Design' | 'Comp-Approve'     | 'CS0000DFR02'           |'R2512XG'| '(SMR2512AW)'                  | '0.0005'  | '1%'    | '3W'     | 'DISCRETE' | 'RES CHIP 0.0005 3W +-1%(2512)EF'                  | 'CHIPR2512'    | ''          | ''            | '20200826'
 '0.0005'     | '1%'      | '3W'     | '2512LF'  | 'EMPTY'  | 'CS0000DFR02'(!)        = 'End of Design' | 'Comp-Approve'     | 'CS0000DFR02'           |'R2512XG'| '(SMR2512AW)'                  | '0.0005'  | '1%'    | '3W'     | 'IO'       | 'RES CHIP 0.0005 3W +-1%(2512)EF'                  | 'CHIPR2512'    | ''          | ''            | '20200826'
 '0.1'        | '1%'      | '1/8W'   | '0805LF'  | 'CHIP'   | 'CS+1004FA01'(!)        = ''              | ''                 | 'CS+1004FA01'           |'R0805'| '(SMR0805AW)'                  | '0.1'     | '1%'    | '1/8W'   | 'DISCRETE' | 'RES CHIP 0.1 1/8W +-1%(0805)'                     | 'CHIPR0805'    | ''          | ''            | '20200909'
 '0.1'        | '1%'      | '1/8W'   | '0805LF'  | 'EMPTY'  | 'CS+1004FA01'(!)        = ''              | ''                 | 'CS+1004FA01'           |'R0805'| '(SMR0805AW)'                  | '0.1'     | '1%'    | '1/8W'   | 'IO'       | 'RES CHIP 0.1 1/8W +-1%(0805)'                     | 'CHIPR0805'    | ''          | ''            | '20200909'
 '100'        | '5%'      | '1/2W'   | '1206LF'  | 'CHIP'   | 'CS11007J200'(!)        = ''              | ''                 | 'CS11007J200'           |'R1206XN'| '(SMR1206AW)'                  | '100'     | '5%'    | '1/2W'   | 'DISCRETE' | 'RES CHIP 100 1/2W+-5%(1206)SR'                    | 'CHIPR1206'    | ''          | ''            | '20200909'
 '100'        | '5%'      | '1/2W'   | '1206LF'  | 'EMPTY'  | 'CS11007J200'(!)        = ''              | ''                 | 'CS11007J200'           |'R1206XN'| '(SMR1206AW)'                  | '100'     | '5%'    | '1/2W'   | 'IO'       | 'RES CHIP 100 1/2W+-5%(1206)SR'                    | 'CHIPR1206'    | ''          | ''            | '20200909'
 '10'         | '0.1%'    | '1/16W'  | '0402LF'  | 'CHIP'   | 'CS01002BB00'(!)        = ''              | ''                 | 'CS01002BB00'           |'R0402'| '(R0402-0201)'                 | '10'      | '0.1%'  | '1/16W'  | 'DISCRETE' | 'RES CHIP 10 1/16W +-0.1%(0402)'                   | 'CHIPR0402'    | ''          | ''            | '20200915'
 '10'         | '0.1%'    | '1/16W'  | '0402LF'  | 'EMPTY'  | 'CS01002BB00'(!)        = ''              | ''                 | 'CS01002BB00'           |'R0402'| '(R0402-0201)'                 | '10'      | '0.1%'  | '1/16W'  | 'IO'       | 'RES CHIP 10 1/16W +-0.1%(0402)'                   | 'CHIPR0402'    | ''          | ''            | '20200915'
 '56K'        | '0.5%'    | '1/16W'  | '0402LF'  | 'CHIP'   | 'CS35602DB00'(!)        = ''              | ''                 | 'CS35602DB00'           |'R0402'| '(R0402-0201)'                 | '56K'     | '0.5%'  | '1/16W'  | 'DISCRETE' | 'RES CHIP 56K 1/16W +-0.5%(0402)'                  | 'CHIPR0402'    | ''          | ''            | '20200915'
 '56K'        | '0.5%'    | '1/16W'  | '0402LF'  | 'EMPTY'  | 'CS35602DB00'(!)        = ''              | ''                 | 'CS35602DB00'           |'R0402'| '(R0402-0201)'                 | '56K'     | '0.5%'  | '1/16W'  | 'IO'       | 'RES CHIP 56K 1/16W +-0.5%(0402)'                  | 'CHIPR0402'    | ''          | ''            | '20200915'
 '2.4K'       | '5%'      | '1/16W'  | '0402LF'  | 'CHIP'   | 'CS22402JB15'(!)        = 'End of Design' | 'Comp-Approve'     | 'CS22402JB15'           |'R0402'| '(R0402-0201)'                 | '2.4K'    | '5%'    | '1/16W'  | 'DISCRETE' | 'RES CHIP 2.4K 1/16W+-5%(0402)'                    | 'CHIPR0402'    | ''          | ''            | '20200917'
 '2.4K'       | '5%'      | '1/16W'  | '0402LF'  | 'EMPTY'  | 'CS22402JB15'(!)        = 'End of Design' | 'Comp-Approve'     | 'CS22402JB15'           |'R0402'| '(R0402-0201)'                 | '2.4K'    | '5%'    | '1/16W'  | 'IO'       | 'RES CHIP 2.4K 1/16W+-5%(0402)'                    | 'CHIPR0402'    | ''          | ''            | '20200917'
 '0.0005'     | '1%'      | '3W'     | '2512LF'  | 'CHIP'   | 'CS0000DFR17'(!)        = ''              | ''                 | 'CS0000DFR17'           |'R2512XX'| '(SMR2512AW)'                  | '0.0005'  | '1%'    | '3W'     | 'DISCRETE' | 'RES CHIP 0.0005 3W +-1%(2512)ERO'                 | 'CHIPR2512'    | ''          | ''            | '20200917'
 '0.0005'     | '1%'      | '3W'     | '2512LF'  | 'EMPTY'  | 'CS0000DFR17'(!)        = ''              | ''                 | 'CS0000DFR17'           |'R2512XX'| '(SMR2512AW)'                  | '0.0005'  | '1%'    | '3W'     | 'IO'       | 'RES CHIP 0.0005 3W +-1%(2512)ERO'                 | 'CHIPR2512'    | ''          | ''            | '20200917'
 '100'        | '5%'      | '1/4W'   | '0805LF'  | 'CHIP'   | 'CS11006JA00'(!)        = ''              | ''                 | 'CS11006JA00'           |'R0805_H26'| '(SMR0805AW)'                  | '100'     | '5%'    | '1/4W'   | 'DISCRETE' | 'RES CHIP 100 1/4W+-5%(0805)SR'                    | 'CHIPR0805'    | ''          | ''            | '20200921'
 '100'        | '5%'      | '1/4W'   | '0805LF'  | 'EMPTY'  | 'CS11006JA00'(!)        = ''              | ''                 | 'CS11006JA00'           |'R0805_H26'| '(SMR0805AW)'                  | '100'     | '5%'    | '1/4W'   | 'IO'       | 'RES CHIP 100 1/4W+-5%(0805)SR'                    | 'CHIPR0805'    | ''          | ''            | '20200921'
 '14.3K'      | '0.1%'    | '1/16W'  | '0402LF'  | 'CHIP'   | 'CS31432BB00'(!)        = ''              | ''                 | 'CS31432BB00'           |'R0402'| '(R0402-0201)'                 | '14.3K'   | '0.1%'  | '1/16W'  | 'DISCRETE' | 'RES CHIP 14.3K 1/16W +-0.1%(0402)'                | 'CHIPR0402'    | ''          | ''            | '20200930'
 '14.3K'      | '0.1%'    | '1/16W'  | '0402LF'  | 'EMPTY'  | 'CS31432BB00'(!)        = ''              | ''                 | 'CS31432BB00'           |'R0402'| '(R0402-0201)'                 | '14.3K'   | '0.1%'  | '1/16W'  | 'IO'       | 'RES CHIP 14.3K 1/16W +-0.1%(0402)'                | 'CHIPR0402'    | ''          | ''            | '20200930'
 '35.7K'      | '0.1%'    | '1/16W'  | '0402LF'  | 'CHIP'   | 'CS33572BB00'(!)        = ''              | ''                 | 'CS33572BB00'           |'R0402'| '(R0402-0201)'                 | '35.7K'   | '0.1%'  | '1/16W'  | 'DISCRETE' | 'RES CHIP 35.7K 1/16W  +-0.1%(0402)'               | 'CHIPR0402'    | ''          | ''            | '20201005'
 '35.7K'      | '0.1%'    | '1/16W'  | '0402LF'  | 'EMPTY'  | 'CS33572BB00'(!)        = ''              | ''                 | 'CS33572BB00'           |'R0402'| '(R0402-0201)'                 | '35.7K'   | '0.1%'  | '1/16W'  | 'IO'       | 'RES CHIP 35.7K 1/16W  +-0.1%(0402)'               | 'CHIPR0402'    | ''          | ''            | '20201005'
 '332K'       | '1%'      | '1/4W'   | '1206LF'  | 'CHIP'   | 'CS43326F200'(!)        = ''              | ''                 | 'CS43326F200'           |'R1206XI'| '(SMR1206AW)'                  | '332K'    | '1%'    | '1/4W'   | 'DISCRETE' | 'RES CHIP 332K 1/4W +-1%(1206)'                    | 'CHIPR1206'    | ''          | ''            | '20201006'
 '332K'       | '1%'      | '1/4W'   | '1206LF'  | 'EMPTY'  | 'CS43326F200'(!)        = ''              | ''                 | 'CS43326F200'           |'R1206XI'| '(SMR1206AW)'                  | '332K'    | '1%'    | '1/4W'   | 'IO'       | 'RES CHIP 332K 1/4W +-1%(1206)'                    | 'CHIPR1206'    | ''          | ''            | '20201006'
 '30.1K'      | '0.1%'    | '1/16W'  | '0402LF'  | 'CHIP'   | 'CS33012BB00'(!)        = 'End of Design' | 'Comp-Approve'     | 'CS33012BB00'           |'R0402'| '(R0402-0201)'                 | '30.1K'   | '0.1%'  | '1/16W'  | 'DISCRETE' | 'RES CHIP 30.1K 1/16W +-0.1% (0402)'               | 'CHIPR0402'    | ''          | ''            | '20201008'
 '30.1K'      | '0.1%'    | '1/16W'  | '0402LF'  | 'EMPTY'  | 'CS33012BB00'(!)        = 'End of Design' | 'Comp-Approve'     | 'CS33012BB00'           |'R0402'| '(R0402-0201)'                 | '30.1K'   | '0.1%'  | '1/16W'  | 'IO'       | 'RES CHIP 30.1K 1/16W +-0.1% (0402)'               | 'CHIPR0402'    | ''          | ''            | '20201008'
 '3.32K'      | '0.1%'    | '1/16W'  | '0402LF'  | 'CHIP'   | 'CS23322BB08'(!)        = 'End of Design' | 'Comp-Approve'     | 'CS23322BB08'           |'R0402'| '(R0402-0201)'                 | '3.32K'   | '0.1%'  | '1/16W'  | 'DISCRETE' | 'RES CHIP 3.32K 1/16W +-0.1% (0402)'               | 'CHIPR0402'    | ''          | ''            | '20201008'
 '3.32K'      | '0.1%'    | '1/16W'  | '0402LF'  | 'EMPTY'  | 'CS23322BB08'(!)        = 'End of Design' | 'Comp-Approve'     | 'CS23322BB08'           |'R0402'| '(R0402-0201)'                 | '3.32K'   | '0.1%'  | '1/16W'  | 'IO'       | 'RES CHIP 3.32K 1/16W +-0.1% (0402)'               | 'CHIPR0402'    | ''          | ''            | '20201008'
 '34.8K'      | '0.1%'    | '1/16W'  | '0402LF'  | 'CHIP'   | 'CS33482BB01'(!)        = ''              | ''                 | 'CS33482BB01'           |'R0402'| '(R0402-0201)'                 | '34.8K'   | '0.1%'  | '1/16W'  | 'DISCRETE' | 'RES CHIP 34.8K 1/16W +-0.1%(0402)'                | 'CHIPR0402'    | ''          | ''            | '20201110'
 '34.8K'      | '0.1%'    | '1/16W'  | '0402LF'  | 'EMPTY'  | 'CS33482BB01'(!)        = ''              | ''                 | 'CS33482BB01'           |'R0402'| '(R0402-0201)'                 | '34.8K'   | '0.1%'  | '1/16W'  | 'IO'       | 'RES CHIP 34.8K 1/16W +-0.1%(0402)'                | 'CHIPR0402'    | ''          | ''            | '20201110'
 '3.57K'      | '0.1%'    | '1/16W'  | '0402LF'  | 'CHIP'   | 'CS23572BB05'(!)        = ''              | ''                 | 'CS23572BB05'           |'R0402'| '(R0402-0201)'                 | '3.57K'   | '0.1%'  | '1/16W'  | 'DISCRETE' | 'RES CHIP 3.57K 1/16W +-0.1%(0402)'                | 'CHIPR0402'    | ''          | ''            | '20201110'
 '3.57K'      | '0.1%'    | '1/16W'  | '0402LF'  | 'EMPTY'  | 'CS23572BB05'(!)        = ''              | ''                 | 'CS23572BB05'           |'R0402'| '(R0402-0201)'                 | '3.57K'   | '0.1%'  | '1/16W'  | 'IO'       | 'RES CHIP 3.57K 1/16W +-0.1%(0402)'                | 'CHIPR0402'    | ''          | ''            | '20201110'
 '182'        | '1%'      | '1/16W'  | '0402LF'  | 'CHIP'   | 'CS11822FB02'(!)        = ''              | ''                 | 'CS11822FB02'           |'R0402'| '(R0402-0201)'                 | '182'     | '1%'    | '1/16W'  | 'DISCRETE' | 'RES CHIP 182 1/16W +-1%(0402)EF'                  | 'CHIPR0402'    | ''          | ''            | '20201112'
 '182'        | '1%'      | '1/16W'  | '0402LF'  | 'EMPTY'  | 'CS11822FB02'(!)        = ''              | ''                 | 'CS11822FB02'           |'R0402'| '(R0402-0201)'                 | '182'     | '1%'    | '1/16W'  | 'IO'       | 'RES CHIP 182 1/16W +-1%(0402)EF'                  | 'CHIPR0402'    | ''          | ''            | '20201112'
 '8.06K'      | '1%'      | '1/16W'  | '0402LF'  | 'CHIP'   | 'CS28062FB03'(!)        = 'End of Design' | 'Comp-Approve'     | 'CS28062FB03'           |'R0402'| '(R0402-0201)'                 | '8.06K'   | '1%'    | '1/16W'  | 'DISCRETE' | 'RES CHIP 8.06K 1/16W +-1%(0402)EF'                | 'CHIPR0402'    | ''          | ''            | '20201118'
 '8.06K'      | '1%'      | '1/16W'  | '0402LF'  | 'EMPTY'  | 'CS28062FB03'(!)        = 'End of Design' | 'Comp-Approve'     | 'CS28062FB03'           |'R0402'| '(R0402-0201)'                 | '8.06K'   | '1%'    | '1/16W'  | 'IO'       | 'RES CHIP 8.06K 1/16W +-1%(0402)EF'                | 'CHIPR0402'    | ''          | ''            | '20201118'
 '162'        | '1%'      | '1/16W'  | '0402LF'  | 'CHIP'   | 'CS11622FB15'(!)        = 'End of Design' | 'Comp-Approve'     | 'CS11622FB15'           |'R0402'| '(R0402-0201)'                 | '162'     | '1%'    | '1/16W'  | 'DISCRETE' | 'RES CHIP 162 1/16W +-1%(0402)'                    | 'CHIPR0402'    | ''          | ''            | '20201120'
 '162'        | '1%'      | '1/16W'  | '0402LF'  | 'EMPTY'  | 'CS11622FB15'(!)        = 'End of Design' | 'Comp-Approve'     | 'CS11622FB15'           |'R0402'| '(R0402-0201)'                 | '162'     | '1%'    | '1/16W'  | 'IO'       | 'RES CHIP 162 1/16W +-1%(0402)'                    | 'CHIPR0402'    | ''          | ''            | '20201120'
 '8.2'        | '1%'      | '1/16W'  | '0402LF'  | 'CHIP'   | 'CS-8202FB00'(!)        = ''              | ''                 | 'CS-8202FB00'           |'R0402'| '(R0402-0201)'                 | '8.2'     | '1%'    | '1/16W'  | 'DISCRETE' | 'RES CHIP 8.2 1/16W +-1%(0402)'                    | 'CHIPR0402'    | ''          | ''            | '20201123'
 '8.2'        | '1%'      | '1/16W'  | '0402LF'  | 'EMPTY'  | 'CS-8202FB00'(!)        = ''              | ''                 | 'CS-8202FB00'           |'R0402'| '(R0402-0201)'                 | '8.2'     | '1%'    | '1/16W'  | 'IO'       | 'RES CHIP 8.2 1/16W +-1%(0402)'                    | 'CHIPR0402'    | ''          | ''            | '20201123'
 '0.2'        | '1%'      | '1/10W'  | '0603LF'  | 'CHIP'   | 'CS+2003F900'(!)        = ''              | ''                 | 'CS+2003F900'           |'R0603_H24'| '(SMR0603AW)'                  | '0.2'     | '1%'    | '1/10W'  | 'DISCRETE' | 'RES CHIP 0.2 1/10W +-1%(0603)EF'                  | 'CHIPR0603'    | ''          | ''            | '20201201'
 '0.2'        | '1%'      | '1/10W'  | '0603LF'  | 'EMPTY'  | 'CS+2003F900'(!)        = ''              | ''                 | 'CS+2003F900'           |'R0603_H24'| '(SMR0603AW)'                  | '0.2'     | '1%'    | '1/10W'  | 'IO'       | 'RES CHIP 0.2 1/10W +-1%(0603)EF'                  | 'CHIPR0603'    | ''          | ''            | '20201201'
 '9.1K'       | '1%'      | '1/16W'  | '0402LF'  | 'CHIP'   | 'CS29102FB00'(!)        = ''              | ''                 | 'CS29102FB00'           |'R0402'| '(R0402-0201)'                 | '9.1K'    | '1%'    | '1/16W'  | 'DISCRETE' | 'RES CHIP 9.1K 1/16W +-1%(0402)EF'                 | 'CHIPR0402'    | ''          | ''            | '20201207'
 '9.1K'       | '1%'      | '1/16W'  | '0402LF'  | 'EMPTY'  | 'CS29102FB00'(!)        = ''              | ''                 | 'CS29102FB00'           |'R0402'| '(R0402-0201)'                 | '9.1K'    | '1%'    | '1/16W'  | 'IO'       | 'RES CHIP 9.1K 1/16W +-1%(0402)EF'                 | 'CHIPR0402'    | ''          | ''            | '20201207'
 '3.3K'       | '5%'      | '1/16W'  | '0402LF'  | 'CHIP'   | 'CS23302JB04'(!)        = 'End of Design' | 'Comp-Approve'     | 'CS23302JB04'           |'R0402'| '(R0402-0201)'                 | '3.3K'    | '5%'    | '1/16W'  | 'DISCRETE' | 'RES CHIP 3.3K 1/16W +-5%(0402)EF'                 | 'CHIPR0402'    | ''          | ''            | '20201208'
 '3.3K'       | '5%'      | '1/16W'  | '0402LF'  | 'EMPTY'  | 'CS23302JB04'(!)        = 'End of Design' | 'Comp-Approve'     | 'CS23302JB04'           |'R0402'| '(R0402-0201)'                 | '3.3K'    | '5%'    | '1/16W'  | 'IO'       | 'RES CHIP 3.3K 1/16W +-5%(0402)EF'                 | 'CHIPR0402'    | ''          | ''            | '20201208'
 '0.15'       | '1%'      | '1W'     | '1206LF'  | 'CHIP'   | 'CS+1508F201'(!)        = ''              | ''                 | 'CS+1508F201'           |'R1206XP'| '(SMR1206AW)'                  | '0.15'    | '1%'    | '1W'     | 'DISCRETE' | 'RES CHIP 0.15 1W +-1%(1206)'                      | 'CHIPR1206'    | ''          | ''            | '20201209'
 '0.15'       | '1%'      | '1W'     | '1206LF'  | 'EMPTY'  | 'CS+1508F201'(!)        = ''              | ''                 | 'CS+1508F201'           |'R1206XP'| '(SMR1206AW)'                  | '0.15'    | '1%'    | '1W'     | 'IO'       | 'RES CHIP 0.15 1W +-1%(1206)'                      | 'CHIPR1206'    | ''          | ''            | '20201209'
 '6.34K'      | '0.1%'    | '1/16W'  | '0402LF'  | 'CHIP'   | 'CS26342BB00'(!)        = ''              | ''                 | 'CS26342BB00'           |'R0402'| '(R0402-0201)'                 | '6.34K'   | '0.1%'  | '1/16W'  | 'DISCRETE' | 'RES CHIP 6.34K 1/16W +-0.1%(0402)'                | 'CHIPR0402'    | ''          | ''            | '20201224'
 '6.34K'      | '0.1%'    | '1/16W'  | '0402LF'  | 'EMPTY'  | 'CS26342BB00'(!)        = ''              | ''                 | 'CS26342BB00'           |'R0402'| '(R0402-0201)'                 | '6.34K'   | '0.1%'  | '1/16W'  | 'IO'       | 'RES CHIP 6.34K 1/16W +-0.1%(0402)'                | 'CHIPR0402'    | ''          | ''            | '20201224'
 '9.09K'      | '0.1%'    | '1/16W'  | '0402LF'  | 'CHIP'   | 'CS29092BB01'(!)        = ''              | ''                 | 'CS29092BB01'           |'R0402'| '(R0402-0201)'                 | '9.09K'   | '0.1%'  | '1/16W'  | 'DISCRETE' | 'RES CHIP 9.09K 1/16W +-0.1%(0402)'                | 'CHIPR0402'    | ''          | ''            | '20201224'
 '9.09K'      | '0.1%'    | '1/16W'  | '0402LF'  | 'EMPTY'  | 'CS29092BB01'(!)        = ''              | ''                 | 'CS29092BB01'           |'R0402'| '(R0402-0201)'                 | '9.09K'   | '0.1%'  | '1/16W'  | 'IO'       | 'RES CHIP 9.09K 1/16W +-0.1%(0402)'                | 'CHIPR0402'    | ''          | ''            | '20201224'
 '2.21K'      | '0.1%'    | '1/16W'  | '0402LF'  | 'CHIP'   | 'CS22212BB01'(!)        = 'End of Design' | 'Comp-Approve'     | 'CS22212BB01'           |'R0402'| '(R0402-0201)'                 | '2.21K'   | '0.1%'  | '1/16W'  | 'DISCRETE' | 'RES CHIP 2.21K 1/16W +-0.1%(0402)'                | 'CHIPR0402'    | ''          | ''            | '20201225'
 '2.21K'      | '0.1%'    | '1/16W'  | '0402LF'  | 'EMPTY'  | 'CS22212BB01'(!)        = 'End of Design' | 'Comp-Approve'     | 'CS22212BB01'           |'R0402'| '(R0402-0201)'                 | '2.21K'   | '0.1%'  | '1/16W'  | 'IO'       | 'RES CHIP 2.21K 1/16W +-0.1%(0402)'                | 'CHIPR0402'    | ''          | ''            | '20201225'
 '4.32K'      | '0.1%'    | '1/16W'  | '0402LF'  | 'CHIP'   | 'CS24322BB01'(!)        = ''              | ''                 | 'CS24322BB01'           |'R0402'| '(R0402-0201)'                 | '4.32K'   | '0.1%'  | '1/16W'  | 'DISCRETE' | 'RES CHIP 4.32K 1/16W +-0.1%(0402)'                | 'CHIPR0402'    | ''          | ''            | '20201225'
 '4.32K'      | '0.1%'    | '1/16W'  | '0402LF'  | 'EMPTY'  | 'CS24322BB01'(!)        = ''              | ''                 | 'CS24322BB01'           |'R0402'| '(R0402-0201)'                 | '4.32K'   | '0.1%'  | '1/16W'  | 'IO'       | 'RES CHIP 4.32K 1/16W +-0.1%(0402)'                | 'CHIPR0402'    | ''          | ''            | '20201225'
 '16.5K'      | '0.1%'    | '1/16W'  | '0402LF'  | 'CHIP'   | 'CS31652BB00'(!)        = ''              | ''                 | 'CS31652BB00'           |'R0402'| '(R0402-0201)'                 | '16.5K'   | '0.1%'  | '1/16W'  | 'DISCRETE' | 'RES CHIP 16.5K 1/16W +-0.1%(0402)'                | 'CHIPR0402'    | ''          | ''            | '20201225'
 '16.5K'      | '0.1%'    | '1/16W'  | '0402LF'  | 'EMPTY'  | 'CS31652BB00'(!)        = ''              | ''                 | 'CS31652BB00'           |'R0402'| '(R0402-0201)'                 | '16.5K'   | '0.1%'  | '1/16W'  | 'IO'       | 'RES CHIP 16.5K 1/16W +-0.1%(0402)'                | 'CHIPR0402'    | ''          | ''            | '20201225'
 '4.12K'      | '0.1%'    | '1/16W'  | '0402LF'  | 'CHIP'   | 'CS24122BB01'(!)        = ''              | ''                 | 'CS24122BB01'           |'R0402'| '(R0402-0201)'                 | '4.12K'   | '0.1%'  | '1/16W'  | 'DISCRETE' | 'RES CHIP 4.12K 1/16W  +-0.1%(0402)'               | 'CHIPR0402'    | ''          | ''            | '20201225'
 '4.12K'      | '0.1%'    | '1/16W'  | '0402LF'  | 'EMPTY'  | 'CS24122BB01'(!)        = ''              | ''                 | 'CS24122BB01'           |'R0402'| '(R0402-0201)'                 | '4.12K'   | '0.1%'  | '1/16W'  | 'IO'       | 'RES CHIP 4.12K 1/16W  +-0.1%(0402)'               | 'CHIPR0402'    | ''          | ''            | '20201225'
 '2.2'        | '1%'      | '1/2W'   | '1206LF'  | 'CHIP'   | 'CS-2207F200'(!)        = ''              | ''                 | 'CS-2207F200'           |'R1206XF'| '(SMR1206AW)'                  | '2.2'     | '1%'    | '1/2W'   | 'DISCRETE' | 'RES CHIP 2.2 1/2W +-1%(1206)'                     | 'CHIPR1206'    | ''          | ''            | '20210105'
 '2.2'        | '1%'      | '1/2W'   | '1206LF'  | 'EMPTY'  | 'CS-2207F200'(!)        = ''              | ''                 | 'CS-2207F200'           |'R1206XF'| '(SMR1206AW)'                  | '2.2'     | '1%'    | '1/2W'   | 'IO'       | 'RES CHIP 2.2 1/2W +-1%(1206)'                     | 'CHIPR1206'    | ''          | ''            | '20210105'
 '200'        | '1%'      | '1/8W'   | '0402LF'  | 'CHIP'   | 'CS12004FB00'(!)        = ''              | ''                 | 'CS12004FB00'           |'R0402'| '(R0402-0201)'                 | '200'     | '1%'    | '1/8W'   | 'DISCRETE' | 'RES CHIP 200 1/8W +-1%(0402)SR'                   | 'CHIPR0402'    | ''          | ''            | '20210112'
 '200'        | '1%'      | '1/8W'   | '0402LF'  | 'EMPTY'  | 'CS12004FB00'(!)        = ''              | ''                 | 'CS12004FB00'           |'R0402'| '(R0402-0201)'                 | '200'     | '1%'    | '1/8W'   | 'IO'       | 'RES CHIP 200 1/8W +-1%(0402)SR'                   | 'CHIPR0402'    | ''          | ''            | '20210112'
 '47K'        | '0.1%'    | '1/16W'  | '0402LF'  | 'CHIP'   | 'CS34702BB03'(!)        = ''              | ''                 | 'CS34702BB03'           |'R0402'| '(R0402-0201)'                 | '47K'     | '0.1%'  | '1/16W'  | 'DISCRETE' | 'RES CHIP 47K 1/16W +-0.1%(0402)YGO'               | 'CHIPR0402'    | ''          | ''            | '20210120'
 '47K'        | '0.1%'    | '1/16W'  | '0402LF'  | 'EMPTY'  | 'CS34702BB03'(!)        = ''              | ''                 | 'CS34702BB03'           |'R0402'| '(R0402-0201)'                 | '47K'     | '0.1%'  | '1/16W'  | 'IO'       | 'RES CHIP 47K 1/16W +-0.1%(0402)YGO'               | 'CHIPR0402'    | ''          | ''            | '20210120'
 '15K'        | '0.1%'    | '1/16W'  | '0402LF'  | 'CHIP'   | 'CS31502BB01'(!)        = ''              | ''                 | 'CS31502BB01'           |'R0402'| '(R0402-0201)'                 | '15K'     | '0.1%'  | '1/16W'  | 'DISCRETE' | 'RES CHIP 15K 1/16W +-0.1%(0402)'                  | 'CHIPR0402'    | ''          | ''            | '20210120'
 '15K'        | '0.1%'    | '1/16W'  | '0402LF'  | 'EMPTY'  | 'CS31502BB01'(!)        = ''              | ''                 | 'CS31502BB01'           |'R0402'| '(R0402-0201)'                 | '15K'     | '0.1%'  | '1/16W'  | 'IO'       | 'RES CHIP 15K 1/16W +-0.1%(0402)'                  | 'CHIPR0402'    | ''          | ''            | '20210120'
 '26.1K'      | '0.1%'    | '1/16W'  | '0402LF'  | 'CHIP'   | 'CS32612BB01'(!)        = ''              | ''                 | 'CS32612BB01'           |'R0402'| '(R0402-0201)'                 | '26.1K'   | '0.1%'  | '1/16W'  | 'DISCRETE' | 'RES CHIP 26.1K 1/16W +-0.1%(0402)'                | 'CHIPR0402'    | ''          | ''            | '20210121'
 '26.1K'      | '0.1%'    | '1/16W'  | '0402LF'  | 'EMPTY'  | 'CS32612BB01'(!)        = ''              | ''                 | 'CS32612BB01'           |'R0402'| '(R0402-0201)'                 | '26.1K'   | '0.1%'  | '1/16W'  | 'IO'       | 'RES CHIP 26.1K 1/16W +-0.1%(0402)'                | 'CHIPR0402'    | ''          | ''            | '20210121'
 '86.6K'      | '0.1%'    | '1/16W'  | '0402LF'  | 'CHIP'   | 'CS38662BB00'(!)        = ''              | ''                 | 'CS38662BB00'           |'R0402'| '(R0402-0201)'                 | '86.6K'   | '0.1%'  | '1/16W'  | 'DISCRETE' | 'RES CHIP 86.6K 1/16W +-0.1%(0402)'                | 'CHIPR0402'    | ''          | ''            | '20210121'
 '86.6K'      | '0.1%'    | '1/16W'  | '0402LF'  | 'EMPTY'  | 'CS38662BB00'(!)        = ''              | ''                 | 'CS38662BB00'           |'R0402'| '(R0402-0201)'                 | '86.6K'   | '0.1%'  | '1/16W'  | 'IO'       | 'RES CHIP 86.6K 1/16W +-0.1%(0402)'                | 'CHIPR0402'    | ''          | ''            | '20210121'
 '7.32K'      | '0.1%'    | '1/16W'  | '0402LF'  | 'CHIP'   | 'CS27322BB08'(!)        = ''              | ''                 | 'CS27322BB08'           |'R0402'| '(R0402-0201)'                 | '7.32K'   | '0.1%'  | '1/16W'  | 'DISCRETE' | 'RES CHIP 7.32K 1/16W +-0.1% (0402)'               | 'CHIPR0402'    | ''          | ''            | '20210121'
 '7.32K'      | '0.1%'    | '1/16W'  | '0402LF'  | 'EMPTY'  | 'CS27322BB08'(!)        = ''              | ''                 | 'CS27322BB08'           |'R0402'| '(R0402-0201)'                 | '7.32K'   | '0.1%'  | '1/16W'  | 'IO'       | 'RES CHIP 7.32K 1/16W +-0.1% (0402)'               | 'CHIPR0402'    | ''          | ''            | '20210121'
 '31.6K'      | '0.1%'    | '1/16W'  | '0402LF'  | 'CHIP'   | 'CS33162BB03'(!)        = ''              | ''                 | 'CS33162BB03'           |'R0402'| '(R0402-0201)'                 | '31.6K'   | '0.1%'  | '1/16W'  | 'DISCRETE' | 'RES CHIP 31.6K 1/16W +-0.1%(0402)'                | 'CHIPR0402'    | ''          | ''            | '20210122'
 '31.6K'      | '0.1%'    | '1/16W'  | '0402LF'  | 'EMPTY'  | 'CS33162BB03'(!)        = ''              | ''                 | 'CS33162BB03'           |'R0402'| '(R0402-0201)'                 | '31.6K'   | '0.1%'  | '1/16W'  | 'IO'       | 'RES CHIP 31.6K 1/16W +-0.1%(0402)'                | 'CHIPR0402'    | ''          | ''            | '20210122'
 '36K'        | '0.1%'    | '1/16W'  | '0402LF'  | 'CHIP'   | 'CS33602BB00'(!)        = 'End of Design' | 'Comp-Release Qty' | 'CS33602BB00'           |'R0402'| '(R0402-0201)'                 | '36K'     | '0.1%'  | '1/16W'  | 'DISCRETE' | 'RES CHIP 36K 1/16W +-0.1%(0402)'                  | 'CHIPR0402'    | ''          | ''            | '20210122'
 '36K'        | '0.1%'    | '1/16W'  | '0402LF'  | 'EMPTY'  | 'CS33602BB00'(!)        = 'End of Design' | 'Comp-Release Qty' | 'CS33602BB00'           |'R0402'| '(R0402-0201)'                 | '36K'     | '0.1%'  | '1/16W'  | 'IO'       | 'RES CHIP 36K 1/16W +-0.1%(0402)'                  | 'CHIPR0402'    | ''          | ''            | '20210122'
 '1.15K'      | '0.1%'    | '1/16W'  | '0402LF'  | 'CHIP'   | 'CS21152BB00'(!)        = ''              | ''                 | 'CS21152BB00'           |'R0402'| '(R0402-0201)'                 | '1.15K'   | '0.1%'  | '1/16W'  | 'DISCRETE' | 'RES CHIP 1.15K 1/16W +-0.1%(0402)'                | 'CHIPR0402'    | ''          | ''            | '20210302'
 '1.15K'      | '0.1%'    | '1/16W'  | '0402LF'  | 'EMPTY'  | 'CS21152BB00'(!)        = ''              | ''                 | 'CS21152BB00'           |'R0402'| '(R0402-0201)'                 | '1.15K'   | '0.1%'  | '1/16W'  | 'IO'       | 'RES CHIP 1.15K 1/16W +-0.1%(0402)'                | 'CHIPR0402'    | ''          | ''            | '20210302'
 '1.02K'      | '0.1%'    | '1/16W'  | '0402LF'  | 'CHIP'   | 'CS21022BB00'(!)        = ''              | ''                 | 'CS21022BB00'           |'R0402'| '(R0402-0201)'                 | '1.02K'   | '0.1%'  | '1/16W'  | 'DISCRETE' | 'RES CHIP 1.02K 1/16W +-0.1%(0402)'                | 'CHIPR0402'    | ''          | ''            | '20210303'
 '1.02K'      | '0.1%'    | '1/16W'  | '0402LF'  | 'EMPTY'  | 'CS21022BB00'(!)        = ''              | ''                 | 'CS21022BB00'           |'R0402'| '(R0402-0201)'                 | '1.02K'   | '0.1%'  | '1/16W'  | 'IO'       | 'RES CHIP 1.02K 1/16W +-0.1%(0402)'                | 'CHIPR0402'    | ''          | ''            | '20210303'
 '16.2K'      | '0.1%'    | '1/16W'  | '0402LF'  | 'CHIP'   | 'CS31622BB00'(!)        = ''              | ''                 | 'CS31622BB00'           |'R0402'| '(R0402-0201)'                 | '16.2K'   | '0.1%'  | '1/16W'  | 'DISCRETE' | 'RES CHIP 16.2K 1/16W 0.1% (0402)'                 | 'CHIPR0402'    | ''          | ''            | '20210309'
 '16.2K'      | '0.1%'    | '1/16W'  | '0402LF'  | 'EMPTY'  | 'CS31622BB00'(!)        = ''              | ''                 | 'CS31622BB00'           |'R0402'| '(R0402-0201)'                 | '16.2K'   | '0.1%'  | '1/16W'  | 'IO'       | 'RES CHIP 16.2K 1/16W 0.1% (0402)'                 | 'CHIPR0402'    | ''          | ''            | '20210309'
 '5.76K'      | '0.1%'    | '1/16W'  | '0402LF'  | 'CHIP'   | 'CS25762BB00'(!)        = 'End of Design' | 'Comp-Approve'     | 'CS25762BB00'           |'R0402'| '(R0402-0201)'                 | '5.76K'   | '0.1%'  | '1/16W'  | 'DISCRETE' | 'RES CHIP 5.76K 1/16W +-0.1%(0402)'                | 'CHIPR0402'    | ''          | ''            | '20210310'
 '5.76K'      | '0.1%'    | '1/16W'  | '0402LF'  | 'EMPTY'  | 'CS25762BB00'(!)        = 'End of Design' | 'Comp-Approve'     | 'CS25762BB00'           |'R0402'| '(R0402-0201)'                 | '5.76K'   | '0.1%'  | '1/16W'  | 'IO'       | 'RES CHIP 5.76K 1/16W +-0.1%(0402)'                | 'CHIPR0402'    | ''          | ''            | '20210310'
 '1'          | '1%'      | '1/4W'   | '0603LF'  | 'CHIP'   | 'CS-1006F903'(!)        = ''              | ''                 | 'CS-1006F903'           |'R0603'| '(SMR0603AW)'                  | '1'       | '1%'    | '1/4W'   | 'DISCRETE' | 'RES CHIP 1 1/4W+-1%(0603)SR RLC'                  | 'CHIPR0603'    | ''          | ''            | '20210318'
 '1'          | '1%'      | '1/4W'   | '0603LF'  | 'EMPTY'  | 'CS-1006F903'(!)        = ''              | ''                 | 'CS-1006F903'           |'R0603'| '(SMR0603AW)'                  | '1'       | '1%'    | '1/4W'   | 'IO'       | 'RES CHIP 1 1/4W+-1%(0603)SR RLC'                  | 'CHIPR0603'    | ''          | ''            | '20210318'
 '3.3'        | '1%'      | '1/4W'   | '0603LF'  | 'CHIP'   | 'CS-3306F903'(!)        = ''              | ''                 | 'CS-3306F903'           |'R0603'| '(SMR0603AW)'                  | '3.3'     | '1%'    | '1/4W'   | 'DISCRETE' | 'RES CHIP 3.3 1/4W+-1%(0603)SR RLC'                | 'CHIPR0603'    | ''          | ''            | '20210318'
 '3.3'        | '1%'      | '1/4W'   | '0603LF'  | 'EMPTY'  | 'CS-3306F903'(!)        = ''              | ''                 | 'CS-3306F903'           |'R0603'| '(SMR0603AW)'                  | '3.3'     | '1%'    | '1/4W'   | 'IO'       | 'RES CHIP 3.3 1/4W+-1%(0603)SR RLC'                | 'CHIPR0603'    | ''          | ''            | '20210318'
 '75K'        | '1%'      | '1/10W'  | '0603LF'  | 'CHIP'   | 'CS37503F904'(!)        = ''              | ''                 | 'CS37503F904'           |'R0603_H24'| '(SMR0603AW)'                  | '75K'     | '1%'    | '1/10W'  | 'DISCRETE' | 'RES CHIP 75K 1/10W +-1%(0603)WTC'                 | 'CHIPR0603'    | ''          | ''            | '20210330'
 '75K'        | '1%'      | '1/10W'  | '0603LF'  | 'EMPTY'  | 'CS37503F904'(!)        = ''              | ''                 | 'CS37503F904'           |'R0603_H24'| '(SMR0603AW)'                  | '75K'     | '1%'    | '1/10W'  | 'IO'       | 'RES CHIP 75K 1/10W +-1%(0603)WTC'                 | 'CHIPR0603'    | ''          | ''            | '20210330'
 '174K'       | '1%'      | '1/10W'  | '0603LF'  | 'CHIP'   | 'CS41743F910'(!)        = ''              | ''                 | 'CS41743F910'           |'R0603_H24'| '(SMR0603AW)'                  | '174K'    | '1%'    | '1/10W'  | 'DISCRETE' | 'RESISTOR CHIP 174K 1/10W+-1%(0603)'               | 'CHIPR0603'    | ''          | ''            | '20210330'
 '174K'       | '1%'      | '1/10W'  | '0603LF'  | 'EMPTY'  | 'CS41743F910'(!)        = ''              | ''                 | 'CS41743F910'           |'R0603_H24'| '(SMR0603AW)'                  | '174K'    | '1%'    | '1/10W'  | 'IO'       | 'RESISTOR CHIP 174K 1/10W+-1%(0603)'               | 'CHIPR0603'    | ''          | ''            | '20210330'
 '174K'       | '0.5%'    | '1/10W'  | '0603LF'  | 'CHIP'   | 'CS41743D909'(!)        = ''              | ''                 | 'CS41743D909'           |'R0603_H24'| '(SMR0603AW)'                  | '174K'    | '0.5%'  | '1/10W'  | 'DISCRETE' | 'RES CHIP 174K 1/10W +-0.5%(0603)EP'               | 'CHIPR0603'    | ''          | ''            | '20210330'
 '174K'       | '0.5%'    | '1/10W'  | '0603LF'  | 'EMPTY'  | 'CS41743D909'(!)        = ''              | ''                 | 'CS41743D909'           |'R0603_H24'| '(SMR0603AW)'                  | '174K'    | '0.5%'  | '1/10W'  | 'IO'       | 'RES CHIP 174K 1/10W +-0.5%(0603)EP'               | 'CHIPR0603'    | ''          | ''            | '20210330'
 '75K'        | '0.5%'    | '1/10W'  | '0603LF'  | 'CHIP'   | 'CS37503D916'(!)        = ''              | ''                 | 'CS37503D916'           |'R0603'| '(SMR0603AW)'                  | '75K'     | '0.5%'  | '1/10W'  | 'DISCRETE' | 'RESISTOR CHIP 75K 1/10W+-0.5%(0603)'              | 'CHIPR0603'    | ''          | ''            | '20210330'
 '75K'        | '0.5%'    | '1/10W'  | '0603LF'  | 'EMPTY'  | 'CS37503D916'(!)        = ''              | ''                 | 'CS37503D916'           |'R0603'| '(SMR0603AW)'                  | '75K'     | '0.5%'  | '1/10W'  | 'IO'       | 'RESISTOR CHIP 75K 1/10W+-0.5%(0603)'              | 'CHIPR0603'    | ''          | ''            | '20210330'
 '681'        | '1%'      | '1/16W'  | '0402LF'  | 'CHIP'   | 'CS16812FB20'(!)        = 'End of Design' | 'Comp-Approve'     | 'CS16812FB20'           |'R0402'| '(R0402-0201)'                 | '681'     | '1%'    | '1/16W'  | 'DISCRETE' | 'RES CHIP 681 1/16W +-1%(0402)'                    | 'CHIPR0402'    | ''          | ''            | '20210330'
 '681'        | '1%'      | '1/16W'  | '0402LF'  | 'EMPTY'  | 'CS16812FB20'(!)        = 'End of Design' | 'Comp-Approve'     | 'CS16812FB20'           |'R0402'| '(R0402-0201)'                 | '681'     | '1%'    | '1/16W'  | 'IO'       | 'RES CHIP 681 1/16W +-1%(0402)'                    | 'CHIPR0402'    | ''          | ''            | '20210330'
 '0.47'       | '1%'      | '1/10W'  | '0603LF'  | 'CHIP'   | 'CS+4703F905'(!)        = ''              | ''                 | 'CS+4703F905'           |'R0603'| '(SMR0603AW)'                  | '0.47'    | '1%'    | '1/10W'  | 'DISCRETE' | 'RES CHIP 0.47 1/10W+-1%(0603)'                    | 'CHIPR0603'    | ''          | ''            | '20210330'
 '0.47'       | '1%'      | '1/10W'  | '0603LF'  | 'EMPTY'  | 'CS+4703F905'(!)        = ''              | ''                 | 'CS+4703F905'           |'R0603'| '(SMR0603AW)'                  | '0.47'    | '1%'    | '1/10W'  | 'IO'       | 'RES CHIP 0.47 1/10W+-1%(0603)'                    | 'CHIPR0603'    | ''          | ''            | '20210330'
 '750'        | '1%'      | '1/10W'  | '0603LF'  | 'CHIP'   | 'CS17503F902'(!)        = 'End of Design' | 'Comp-Approve'     | 'CS17503F902'           |'R0603'| '(SMR0603AW)'                  | '750'     | '1%'    | '1/10W'  | 'DISCRETE' | 'RES CHIP 750 1/10W +-1%(0603)EF'                  | 'CHIPR0603'    | ''          | ''            | '20210407'
 '750'        | '1%'      | '1/10W'  | '0603LF'  | 'EMPTY'  | 'CS17503F902'(!)        = 'End of Design' | 'Comp-Approve'     | 'CS17503F902'           |'R0603'| '(SMR0603AW)'                  | '750'     | '1%'    | '1/10W'  | 'IO'       | 'RES CHIP 750 1/10W +-1%(0603)EF'                  | 'CHIPR0603'    | ''          | ''            | '20210407'
 '0.003'      | '1%'      | '3W'     | '2512LF'  | 'CHIP'   | 'CS+003DFR03'(!)        = ''              | ''                 | 'CS+003DFR03'           |'R2512XY'| '(SMR2512AW)'                  | '0.003'   | '1%'    | '3W'     | 'DISCRETE' | 'RES CHIP 0.003 3W +-1%(2512)RLC'                  | 'CHIPR2512'    | ''          | ''            | '20210419'
 '0.003'      | '1%'      | '3W'     | '2512LF'  | 'EMPTY'  | 'CS+003DFR03'(!)        = ''              | ''                 | 'CS+003DFR03'           |'R2512XY'| '(SMR2512AW)'                  | '0.003'   | '1%'    | '3W'     | 'IO'       | 'RES CHIP 0.003 3W +-1%(2512)RLC'                  | 'CHIPR2512'    | ''          | ''            | '20210419'
 '0.0005'     | '1%'      | '3W'     | '2512LF'  | 'CHIP'   | 'CS0000DFR18'(!)        = ''              | ''                 | 'CS0000DFR18'           |'R2512XG'| '(SMR2512AW)'                  | '0.0005'  | '1%'    | '3W'     | 'DISCRETE' | 'RES CHIP 0.0005 3W +-1%(2512)RLC'                 | 'CHIPR2512'    | ''          | ''            | '20210428'
 '0.0005'     | '1%'      | '3W'     | '2512LF'  | 'EMPTY'  | 'CS0000DFR18'(!)        = ''              | ''                 | 'CS0000DFR18'           |'R2512XG'| '(SMR2512AW)'                  | '0.0005'  | '1%'    | '3W'     | 'IO'       | 'RES CHIP 0.0005 3W +-1%(2512)RLC'                 | 'CHIPR2512'    | ''          | ''            | '20210428'
 '0.001'      | '1%'      | '3W'     | '2512LF'  | 'CHIP'   | 'CS+001DFR10'(!)        = ''              | ''                 | 'CS+001DFR10'           |'R2512XJ'| '(SMR2512AW)'                  | '0.001'   | '1%'    | '3W'     | 'DISCRETE' | 'RES CHIP 0.001 3W +-1%(2512)RLC'                  | 'CHIPR2512'    | ''          | ''            | '20210428'
 '0.001'      | '1%'      | '3W'     | '2512LF'  | 'EMPTY'  | 'CS+001DFR10'(!)        = ''              | ''                 | 'CS+001DFR10'           |'R2512XJ'| '(SMR2512AW)'                  | '0.001'   | '1%'    | '3W'     | 'IO'       | 'RES CHIP 0.001 3W +-1%(2512)RLC'                  | 'CHIPR2512'    | ''          | ''            | '20210428'
 '0.68'       | '1%'      | '1/6W'   | '0402LF'  | 'CHIP'   | 'CS+6802FB00'(!)        = ''              | ''                 | 'CS+6802FB00'           |'R0402_H20'| '(R0402-0201_H20)'             | '0.68'    | '1%'    | '1/6W'   | 'DISCRETE' | 'RES CHIP 0.68 OHM 1/6W +-1%(0402)'                | 'CHIPR0402'    | ''          | ''            | '20210507'
 '0.68'       | '1%'      | '1/6W'   | '0402LF'  | 'EMPTY'  | 'CS+6802FB00'(!)        = ''              | ''                 | 'CS+6802FB00'           |'R0402_H20'| '(R0402-0201_H20)'             | '0.68'    | '1%'    | '1/6W'   | 'IO'       | 'RES CHIP 0.68 OHM 1/6W +-1%(0402)'                | 'CHIPR0402'    | ''          | ''            | '20210507'
 '374'        | '1%'      | '1/16W'  | '0402LF'  | 'CHIP'   | 'CS13742FB13'(!)        = 'End of Design' | 'Comp-Approve'     | 'CS13742FB13'           |'R0402'| '(R0402-0201)'                 | '374'     | '1%'    | '1/16W'  | 'DISCRETE' | 'RES CHIP 374 1/16W +-1%(0402)'                    | 'CHIPR0402'    | ''          | ''            | '20210514'
 '374'        | '1%'      | '1/16W'  | '0402LF'  | 'EMPTY'  | 'CS13742FB13'(!)        = 'End of Design' | 'Comp-Approve'     | 'CS13742FB13'           |'R0402'| '(R0402-0201)'                 | '374'     | '1%'    | '1/16W'  | 'IO'       | 'RES CHIP 374 1/16W +-1%(0402)'                    | 'CHIPR0402'    | ''          | ''            | '20210514'
 '3.74K'      | '0.1%'    | '1/16W'  | '0402LF'  | 'CHIP'   | 'CS23742BB01'(!)        = ''              | 'End of Life'      | 'CS23742BB01'           |'R0402_EOL'| '(R0402-0201)'                 | '3.74K'   | '0.1%'  | '1/16W'  | 'DISCRETE' | 'RES CHIP 3.74K 1/16W +-0.1%(0402)'                | 'CHIPR0402'    | ''          | ''            | '20210514'
 '3.74K'      | '0.1%'    | '1/16W'  | '0402LF'  | 'EMPTY'  | 'CS23742BB01'(!)        = ''              | 'End of Life'      | 'CS23742BB01'           |'R0402_EOL'| '(R0402-0201)'                 | '3.74K'   | '0.1%'  | '1/16W'  | 'IO'       | 'RES CHIP 3.74K 1/16W +-0.1%(0402)'                | 'CHIPR0402'    | ''          | ''            | '20210514'
 '13.3K'      | '0.1%'    | '1/16W'  | '0402LF'  | 'CHIP'   | 'CS31332BB01'(!)        = ''              | ''                 | 'CS31332BB01'           |'R0402'| '(R0402-0201)'                 | '13.3K'   | '0.1%'  | '1/16W'  | 'DISCRETE' | 'RES CHIP 13.3K 1/16W +-0.1%(0402)'                | 'CHIPR0402'    | ''          | ''            | '20210514'
 '13.3K'      | '0.1%'    | '1/16W'  | '0402LF'  | 'EMPTY'  | 'CS31332BB01'(!)        = ''              | ''                 | 'CS31332BB01'           |'R0402'| '(R0402-0201)'                 | '13.3K'   | '0.1%'  | '1/16W'  | 'IO'       | 'RES CHIP 13.3K 1/16W +-0.1%(0402)'                | 'CHIPR0402'    | ''          | ''            | '20210514'
 '90.9'       | '1%'      | '1/20W'  | '0201LF'  | 'CHIP'   | 'CS09091FE00'(!)        = ''              | ''                 | 'CS09091FE00'           |'R0201'| '(SMR0201AW)'                  | '90.9'    | '1%'    | '1/20W'  | 'DISCRETE' | 'RES CHIP 90.9 1/20W +-1%(0201)'                   | 'CHIPR0201'    | ''          | ''            | '20210520'
 '90.9'       | '1%'      | '1/20W'  | '0201LF'  | 'EMPTY'  | 'CS09091FE00'(!)        = ''              | ''                 | 'CS09091FE00'           |'R0201'| '(SMR0201AW)'                  | '90.9'    | '1%'    | '1/20W'  | 'IO'       | 'RES CHIP 90.9 1/20W +-1%(0201)'                   | 'CHIPR0201'    | ''          | ''            | '20210520'
 '280K'       | '1%'      | '1/16W'  | '0402LF'  | 'CHIP'   | 'CS42802FB05'(!)        = ''              | ''                 | 'CS42802FB05'           |'R0402'| '(R0402-0201)'                 | '280K'    | '1%'    | '1/16W'  | 'DISCRETE' | 'RES CHIP 280K 1/16W +-1%(0402)EF'                 | 'CHIPR0402'    | ''          | ''            | '20210526'
 '280K'       | '1%'      | '1/16W'  | '0402LF'  | 'EMPTY'  | 'CS42802FB05'(!)        = ''              | ''                 | 'CS42802FB05'           |'R0402'| '(R0402-0201)'                 | '280K'    | '1%'    | '1/16W'  | 'IO'       | 'RES CHIP 280K 1/16W +-1%(0402)EF'                 | 'CHIPR0402'    | ''          | ''            | '20210526'
 '53.6K'      | '0.1%'    | '1/16W'  | '0402LF'  | 'CHIP'   | 'CS35362BB03'(!)        = ''              | ''                 | 'CS35362BB03'           |'R0402'| '(R0402-0201)'                 | '53.6K'   | '0.1%'  | '1/16W'  | 'DISCRETE' | 'RES CHIP 53.6K 1/16W +-0.1%(0402)'                | 'CHIPR0402'    | ''          | ''            | '20210526'
 '53.6K'      | '0.1%'    | '1/16W'  | '0402LF'  | 'EMPTY'  | 'CS35362BB03'(!)        = ''              | ''                 | 'CS35362BB03'           |'R0402'| '(R0402-0201)'                 | '53.6K'   | '0.1%'  | '1/16W'  | 'IO'       | 'RES CHIP 53.6K 1/16W +-0.1%(0402)'                | 'CHIPR0402'    | ''          | ''            | '20210526'
 '6.65K'      | '0.1%'    | '1/16W'  | '0402LF'  | 'CHIP'   | 'CS26652BB01'(!)        = ''              | ''                 | 'CS26652BB01'           |'R0402'| '(R0402-0201)'                 | '6.65K'   | '0.1%'  | '1/16W'  | 'DISCRETE' | 'RES CHIP 6.65K 1/16W +-0.1%(0402)'                | 'CHIPR0402'    | ''          | ''            | '20210526'
 '6.65K'      | '0.1%'    | '1/16W'  | '0402LF'  | 'EMPTY'  | 'CS26652BB01'(!)        = ''              | ''                 | 'CS26652BB01'           |'R0402'| '(R0402-0201)'                 | '6.65K'   | '0.1%'  | '1/16W'  | 'IO'       | 'RES CHIP 6.65K 1/16W +-0.1%(0402)'                | 'CHIPR0402'    | ''          | ''            | '20210526'
 '3.74K'      | '0.1%'    | '1/16W'  | '0402LF'  | 'CHIP'   | 'CS23742BB00'(!)        = ''              | ''                 | 'CS23742BB00'           |'R0402'| '(R0402-0201)'                 | '3.74K'   | '0.1%'  | '1/16W'  | 'DISCRETE' | 'RES CHIP 3.74K 1/16W +-0.1%(0402)'                | 'CHIPR0402'    | ''          | ''            | '20210526'
 '3.74K'      | '0.1%'    | '1/16W'  | '0402LF'  | 'EMPTY'  | 'CS23742BB00'(!)        = ''              | ''                 | 'CS23742BB00'           |'R0402'| '(R0402-0201)'                 | '3.74K'   | '0.1%'  | '1/16W'  | 'IO'       | 'RES CHIP 3.74K 1/16W +-0.1%(0402)'                | 'CHIPR0402'    | ''          | ''            | '20210526'
 '97.6'       | '1%'      | '1/16W'  | '0402LF'  | 'CHIP'   | 'CS09762FB01'(!)        = ''              | ''                 | 'CS09762FB01'           |'R0402'| '(R0402-0201)'                 | '97.6'    | '1%'    | '1/16W'  | 'DISCRETE' | 'RES CHIP 97.6 1/16W +-1%(0402)'                   | 'CHIPR0402'    | ''          | ''            | '20210531'
 '97.6'       | '1%'      | '1/16W'  | '0402LF'  | 'EMPTY'  | 'CS09762FB01'(!)        = ''              | ''                 | 'CS09762FB01'           |'R0402'| '(R0402-0201)'                 | '97.6'    | '1%'    | '1/16W'  | 'IO'       | 'RES CHIP 97.6 1/16W +-1%(0402)'                   | 'CHIPR0402'    | ''          | ''            | '20210531'
 '0.03'       | '1%'      | '1/10W'  | '0603LF'  | 'CHIP'   | 'CS+0303F901'(!)        = ''              | ''                 | 'CS+0303F901'           |'R0603'| '(SMR0603AW)'                  | '0.03'    | '1%'    | '1/10W'  | 'DISCRETE' | 'RES CHIP 0.03 1/10W +-1%(0603)'                   | 'CHIPR0603'    | ''          | ''            | '20210531'
 '0.03'       | '1%'      | '1/10W'  | '0603LF'  | 'EMPTY'  | 'CS+0303F901'(!)        = ''              | ''                 | 'CS+0303F901'           |'R0603'| '(SMR0603AW)'                  | '0.03'    | '1%'    | '1/10W'  | 'IO'       | 'RES CHIP 0.03 1/10W +-1%(0603)'                   | 'CHIPR0603'    | ''          | ''            | '20210531'
 '0.25'       | '1%'      | '1/4W'   | '0805LF'  | 'CHIP'   | 'CS+2506FA00'(!)        = ''              | ''                 | 'CS+2506FA00'           |'R0805'| '(SMR0805AW)'                  | '0.25'    | '1%'    | '1/4W'   | 'DISCRETE' | 'RES CHIP 0.25 1/4W +-1%(0805)'                    | 'CHIPR0805'    | ''          | ''            | '20210607'
 '0.25'       | '1%'      | '1/4W'   | '0805LF'  | 'EMPTY'  | 'CS+2506FA00'(!)        = ''              | ''                 | 'CS+2506FA00'           |'R0805'| '(SMR0805AW)'                  | '0.25'    | '1%'    | '1/4W'   | 'IO'       | 'RES CHIP 0.25 1/4W +-1%(0805)'                    | 'CHIPR0805'    | ''          | ''            | '20210607'
 '75K'        | '0.1%'    | '1/16W'  | '0402LF'  | 'CHIP'   | 'CS37502BB00'(!)        = ''              | ''                 | 'CS37502BB00'           |'R0402'| '(R0402-0201)'                 | '75K'     | '0.1%'  | '1/16W'  | 'DISCRETE' | 'RES CHIP 75K 1/16W +-0.1%(0402)'                  | 'CHIPR0402'    | ''          | ''            | '20210610'
 '75K'        | '0.1%'    | '1/16W'  | '0402LF'  | 'EMPTY'  | 'CS37502BB00'(!)        = ''              | ''                 | 'CS37502BB00'           |'R0402'| '(R0402-0201)'                 | '75K'     | '0.1%'  | '1/16W'  | 'IO'       | 'RES CHIP 75K 1/16W +-0.1%(0402)'                  | 'CHIPR0402'    | ''          | ''            | '20210610'
 '4.7'        | '5%'      | '1/8W'   | '0805LF'  | 'CHIP'   | 'CS-4704JA31'(!)        = 'End of Design' | 'Comp-Approve'     | 'CS-4704JA31'           |'R0805_H26'| '(SMR0805AW)'                  | '4.7'     | '5%'    | '1/8W'   | 'DISCRETE' | 'RES CHIP 4.7 1/8W+-5%(0805)'                      | 'CHIPR0805'    | ''          | ''            | '20210610'
 '4.7'        | '5%'      | '1/8W'   | '0805LF'  | 'EMPTY'  | 'CS-4704JA31'(!)        = 'End of Design' | 'Comp-Approve'     | 'CS-4704JA31'           |'R0805_H26'| '(SMR0805AW)'                  | '4.7'     | '5%'    | '1/8W'   | 'IO'       | 'RES CHIP 4.7 1/8W+-5%(0805)'                      | 'CHIPR0805'    | ''          | ''            | '20210610'
 '300'        | '0.1%'    | '1/16W'  | '0402LF'  | 'CHIP'   | 'CS13002BB01'(!)        = ''              | ''                 | 'CS13002BB01'           |'R0402'| '(R0402-0201)'                 | '300'     | '0.1%'  | '1/16W'  | 'DISCRETE' | 'RES CHIP 300 1/16W +-0.1%(0402)'                  | 'CHIPR0402'    | ''          | ''            | '20210610'
 '300'        | '0.1%'    | '1/16W'  | '0402LF'  | 'EMPTY'  | 'CS13002BB01'(!)        = ''              | ''                 | 'CS13002BB01'           |'R0402'| '(R0402-0201)'                 | '300'     | '0.1%'  | '1/16W'  | 'IO'       | 'RES CHIP 300 1/16W +-0.1%(0402)'                  | 'CHIPR0402'    | ''          | ''            | '20210610'
 '430'        | '1%'      | '1/2W'   | '1206LF'  | 'CHIP'   | 'CS14307F200'(!)        = ''              | ''                 | 'CS14307F200'           |'R1206XF'| '(SMR1206AW)'                  | '430'     | '1%'    | '1/2W'   | 'DISCRETE' | 'RES CHIP 430 1/2W +-1%(1206)'                     | 'CHIPR1206'    | ''          | ''            | '20210616'
 '430'        | '1%'      | '1/2W'   | '1206LF'  | 'EMPTY'  | 'CS14307F200'(!)        = ''              | ''                 | 'CS14307F200'           |'R1206XF'| '(SMR1206AW)'                  | '430'     | '1%'    | '1/2W'   | 'IO'       | 'RES CHIP 430 1/2W +-1%(1206)'                     | 'CHIPR1206'    | ''          | ''            | '20210616'
 '34'         | '1%'      | '1/16W'  | '0402LF'  | 'CHIP'   | 'CS03402FB00'(!)        = 'End of Design' | 'Comp-Release Qty' | 'CS03402FB00'           |'R0402'| '(R0402-0201)'                 | '34'      | '1%'    | '1/16W'  | 'DISCRETE' | 'RES CHIP 34 1/16W +-1%(0402)'                     | 'CHIPR0402'    | ''          | ''            | '20210622'
 '34'         | '1%'      | '1/16W'  | '0402LF'  | 'EMPTY'  | 'CS03402FB00'(!)        = 'End of Design' | 'Comp-Release Qty' | 'CS03402FB00'           |'R0402'| '(R0402-0201)'                 | '34'      | '1%'    | '1/16W'  | 'IO'       | 'RES CHIP 34 1/16W +-1%(0402)'                     | 'CHIPR0402'    | ''          | ''            | '20210622'
 '300K'       | '0.1%'    | '1/16W'  | '0402LF'  | 'CHIP'   | 'CS43002BB01'(!)        = 'End of Design' | 'Comp-Approve'     | 'CS43002BB01'           |'R0402'| '(R0402-0201)'                 | '300K'    | '0.1%'  | '1/16W'  | 'DISCRETE' | 'RES CHIP 300K 1/16W +-0.1%(0402)'                 | 'CHIPR0402'    | ''          | ''            | '20210622'
 '300K'       | '0.1%'    | '1/16W'  | '0402LF'  | 'EMPTY'  | 'CS43002BB01'(!)        = 'End of Design' | 'Comp-Approve'     | 'CS43002BB01'           |'R0402'| '(R0402-0201)'                 | '300K'    | '0.1%'  | '1/16W'  | 'IO'       | 'RES CHIP 300K 1/16W +-0.1%(0402)'                 | 'CHIPR0402'    | ''          | ''            | '20210622'
 '0.0002'     | '5%'      | '1/2W'   | '0805LF'  | 'CHIP'   | 'CS00007JA00'(!)        = ''              | ''                 | 'CS00007JA00'           |'R0805_H32'| '(SMR0805AW)'                  | '0.0002'  | '5%'    | '1/2W'   | 'DISCRETE' | 'RESISTOR CHIP 0.0002 1/2W +-5%(0805)'             | 'CHIPR0805'    | ''          | ''            | '20210622'
 '0.0002'     | '5%'      | '1/2W'   | '0805LF'  | 'EMPTY'  | 'CS00007JA00'(!)        = ''              | ''                 | 'CS00007JA00'           |'R0805_H32'| '(SMR0805AW)'                  | '0.0002'  | '5%'    | '1/2W'   | 'IO'       | 'RESISTOR CHIP 0.0002 1/2W +-5%(0805)'             | 'CHIPR0805'    | ''          | ''            | '20210622'
 '169'        | '1%'      | '1/20W'  | '0201LF'  | 'CHIP'   | 'CS11691FE01'(!)        = ''              | ''                 | 'CS11691FE01'           |'R0201'| '(SMR0201AW)'                  | '169'     | '1%'    | '1/20W'  | 'DISCRETE' | 'RES CHIP 169 1/20W +-1%(0201)'                    | 'CHIPR0201'    | ''          | ''            | '20210622'
 '169'        | '1%'      | '1/20W'  | '0201LF'  | 'EMPTY'  | 'CS11691FE01'(!)        = ''              | ''                 | 'CS11691FE01'           |'R0201'| '(SMR0201AW)'                  | '169'     | '1%'    | '1/20W'  | 'IO'       | 'RES CHIP 169 1/20W +-1%(0201)'                    | 'CHIPR0201'    | ''          | ''            | '20210622'
 '8.66'       | '1%'      | '1/16W'  | '0402LF'  | 'CHIP'   | 'CS-8662FB00'(!)        = ''              | ''                 | 'CS-8662FB00'           |'R0402'| '(R0402-0201)'                 | '8.66'    | '1%'    | '1/16W'  | 'DISCRETE' | 'RES CHIP 8.66 1/16W+-1%(0402)'                    | 'CHIPR0402'    | ''          | ''            | '20210623'
 '8.66'       | '1%'      | '1/16W'  | '0402LF'  | 'EMPTY'  | 'CS-8662FB00'(!)        = ''              | ''                 | 'CS-8662FB00'           |'R0402'| '(R0402-0201)'                 | '8.66'    | '1%'    | '1/16W'  | 'IO'       | 'RES CHIP 8.66 1/16W+-1%(0402)'                    | 'CHIPR0402'    | ''          | ''            | '20210623'
 '2.15K'      | '1%'      | '1/4W'   | '1206LF'  | 'CHIP'   | 'CS22156F201'(!)        = 'End of Design' | 'Comp-Approve'     | 'CS22156F201'           |'R1206XF'| '(SMR1206AW)'                  | '2.15K'   | '1%'    | '1/4W'   | 'DISCRETE' | 'RES CHIP 2.15K 1/4W +-1%(1206)EF'                 | 'CHIPR1206'    | ''          | ''            | '20210624'
 '2.15K'      | '1%'      | '1/4W'   | '1206LF'  | 'EMPTY'  | 'CS22156F201'(!)        = 'End of Design' | 'Comp-Approve'     | 'CS22156F201'           |'R1206XF'| '(SMR1206AW)'                  | '2.15K'   | '1%'    | '1/4W'   | 'IO'       | 'RES CHIP 2.15K 1/4W +-1%(1206)EF'                 | 'CHIPR1206'    | ''          | ''            | '20210624'
 '475K'       | '1%'      | '1/8W'   | '0805LF'  | 'CHIP'   | 'CS44754FA03'(!)        = ''              | ''                 | 'CS44754FA03'           |'R0805_H26'| '(SMR0805AW)'                  | '475K'    | '1%'    | '1/8W'   | 'DISCRETE' | 'RES CHIP 475K 1/8W +-1%(0805)'                    | 'CHIPR0805'    | ''          | ''            | '20210628'
 '475K'       | '1%'      | '1/8W'   | '0805LF'  | 'EMPTY'  | 'CS44754FA03'(!)        = ''              | ''                 | 'CS44754FA03'           |'R0805_H26'| '(SMR0805AW)'                  | '475K'    | '1%'    | '1/8W'   | 'IO'       | 'RES CHIP 475K 1/8W +-1%(0805)'                    | 'CHIPR0805'    | ''          | ''            | '20210628'
 '124'        | '0.1%'    | '1/16W'  | '0402LF'  | 'CHIP'   | 'CS11242BB00'(!)        = ''              | ''                 | 'CS11242BB00'           |'R0402'| '(R0402-0201)'                 | '124'     | '0.1%'  | '1/16W'  | 'DISCRETE' | 'RES CHIP 124 1/16W+-0.1%(0402)'                   | 'CHIPR0402'    | ''          | ''            | '20210630'
 '124'        | '0.1%'    | '1/16W'  | '0402LF'  | 'EMPTY'  | 'CS11242BB00'(!)        = ''              | ''                 | 'CS11242BB00'           |'R0402'| '(R0402-0201)'                 | '124'     | '0.1%'  | '1/16W'  | 'IO'       | 'RES CHIP 124 1/16W+-0.1%(0402)'                   | 'CHIPR0402'    | ''          | ''            | '20210630'
 '909'        | '0.1%'    | '1/16W'  | '0402LF'  | 'CHIP'   | 'CS19092BB01'(!)        = ''              | ''                 | 'CS19092BB01'           |'R0402'| '(R0402-0201)'                 | '909'     | '0.1%'  | '1/16W'  | 'DISCRETE' | 'RES CHIP 909 1/16W+-0.1%(0402)'                   | 'CHIPR0402'    | ''          | ''            | '20210630'
 '909'        | '0.1%'    | '1/16W'  | '0402LF'  | 'EMPTY'  | 'CS19092BB01'(!)        = ''              | ''                 | 'CS19092BB01'           |'R0402'| '(R0402-0201)'                 | '909'     | '0.1%'  | '1/16W'  | 'IO'       | 'RES CHIP 909 1/16W+-0.1%(0402)'                   | 'CHIPR0402'    | ''          | ''            | '20210630'
 '49.9K'      | '0.1%'    | '1/16W'  | '0402LF'  | 'CHIP'   | 'CS34992BB08'(!)        = ''              | ''                 | 'CS34992BB08'           |'R0402'| '(R0402-0201)'                 | '49.9K'   | '0.1%'  | '1/16W'  | 'DISCRETE' | 'RES CHIP 49.9K 1/16W+-0.1%(0402)'                 | 'CHIPR0402'    | ''          | ''            | '20210630'
 '49.9K'      | '0.1%'    | '1/16W'  | '0402LF'  | 'EMPTY'  | 'CS34992BB08'(!)        = ''              | ''                 | 'CS34992BB08'           |'R0402'| '(R0402-0201)'                 | '49.9K'   | '0.1%'  | '1/16W'  | 'IO'       | 'RES CHIP 49.9K 1/16W+-0.1%(0402)'                 | 'CHIPR0402'    | ''          | ''            | '20210630'
 '23.2K'      | '0.1%'    | '1/16W'  | '0402LF'  | 'CHIP'   | 'CS32322BB00'(!)        = ''              | ''                 | 'CS32322BB00'           |'R0402'| '(R0402-0201)'                 | '23.2K'   | '0.1%'  | '1/16W'  | 'DISCRETE' | 'RES CHIP 23.2K 1/16W +-0.1%(0402)'                | 'CHIPR0402'    | ''          | ''            | '20210630'
 '23.2K'      | '0.1%'    | '1/16W'  | '0402LF'  | 'EMPTY'  | 'CS32322BB00'(!)        = ''              | ''                 | 'CS32322BB00'           |'R0402'| '(R0402-0201)'                 | '23.2K'   | '0.1%'  | '1/16W'  | 'IO'       | 'RES CHIP 23.2K 1/16W +-0.1%(0402)'                | 'CHIPR0402'    | ''          | ''            | '20210630'
 '1.69K'      | '0.1%'    | '1/16W'  | '0402LF'  | 'CHIP'   | 'CS21692BB00'(!)        = ''              | ''                 | 'CS21692BB00'           |'R0402'| '(R0402-0201)'                 | '1.69K'   | '0.1%'  | '1/16W'  | 'DISCRETE' | 'RES CHIP 1.69K 1/16W+-0.1%(0402)'                 | 'CHIPR0402'    | ''          | ''            | '20210630'
 '1.69K'      | '0.1%'    | '1/16W'  | '0402LF'  | 'EMPTY'  | 'CS21692BB00'(!)        = ''              | ''                 | 'CS21692BB00'           |'R0402'| '(R0402-0201)'                 | '1.69K'   | '0.1%'  | '1/16W'  | 'IO'       | 'RES CHIP 1.69K 1/16W+-0.1%(0402)'                 | 'CHIPR0402'    | ''          | ''            | '20210630'
 '3.09K'      | '0.1%'    | '1/16W'  | '0402LF'  | 'CHIP'   | 'CS23092BB02'(!)        = ''              | ''                 | 'CS23092BB02'           |'R0402'| '(R0402-0201)'                 | '3.09K'   | '0.1%'  | '1/16W'  | 'DISCRETE' | 'RES CHIP 3.09K 1/16W+-0.1%(0402)'                 | 'CHIPR0402'    | ''          | ''            | '20210630'
 '3.09K'      | '0.1%'    | '1/16W'  | '0402LF'  | 'EMPTY'  | 'CS23092BB02'(!)        = ''              | ''                 | 'CS23092BB02'           |'R0402'| '(R0402-0201)'                 | '3.09K'   | '0.1%'  | '1/16W'  | 'IO'       | 'RES CHIP 3.09K 1/16W+-0.1%(0402)'                 | 'CHIPR0402'    | ''          | ''            | '20210630'
 '1.74K'      | '0.1%'    | '1/16W'  | '0402LF'  | 'CHIP'   | 'CS21742BB02'(!)        = ''              | ''                 | 'CS21742BB02'           |'R0402'| '(R0402-0201)'                 | '1.74K'   | '0.1%'  | '1/16W'  | 'DISCRETE' | 'RES CHIP 1.74K 1/16W+-0.1%(0402)'                 | 'CHIPR0402'    | ''          | ''            | '20210630'
 '1.74K'      | '0.1%'    | '1/16W'  | '0402LF'  | 'EMPTY'  | 'CS21742BB02'(!)        = ''              | ''                 | 'CS21742BB02'           |'R0402'| '(R0402-0201)'                 | '1.74K'   | '0.1%'  | '1/16W'  | 'IO'       | 'RES CHIP 1.74K 1/16W+-0.1%(0402)'                 | 'CHIPR0402'    | ''          | ''            | '20210630'
 '2.55K'      | '0.1%'    | '1/16W'  | '0402LF'  | 'CHIP'   | 'CS22552BB01'(!)        = ''              | ''                 | 'CS22552BB01'           |'R0402'| '(R0402-0201)'                 | '2.55K'   | '0.1%'  | '1/16W'  | 'DISCRETE' | 'RES CHIP 2.55K 1/16W+-0.1%(0402)'                 | 'CHIPR0402'    | ''          | ''            | '20210630'
 '2.55K'      | '0.1%'    | '1/16W'  | '0402LF'  | 'EMPTY'  | 'CS22552BB01'(!)        = ''              | ''                 | 'CS22552BB01'           |'R0402'| '(R0402-0201)'                 | '2.55K'   | '0.1%'  | '1/16W'  | 'IO'       | 'RES CHIP 2.55K 1/16W+-0.1%(0402)'                 | 'CHIPR0402'    | ''          | ''            | '20210630'
 '1.37K'      | '0.1%'    | '1/16W'  | '0402LF'  | 'CHIP'   | 'CS21372BB00'(!)        = ''              | ''                 | 'CS21372BB00'           |'R0402'| '(R0402-0201)'                 | '1.37K'   | '0.1%'  | '1/16W'  | 'DISCRETE' | 'RES CHIP 1.37K 1/16W +-0.1%(0402)'                | 'CHIPR0402'    | ''          | ''            | '20210630'
 '1.37K'      | '0.1%'    | '1/16W'  | '0402LF'  | 'EMPTY'  | 'CS21372BB00'(!)        = ''              | ''                 | 'CS21372BB00'           |'R0402'| '(R0402-0201)'                 | '1.37K'   | '0.1%'  | '1/16W'  | 'IO'       | 'RES CHIP 1.37K 1/16W +-0.1%(0402)'                | 'CHIPR0402'    | ''          | ''            | '20210630'
 '453K'       | '1%'      | '1/16W'  | '0402LF'  | 'CHIP'   | 'CS44532FB05'(!)        = ''              | ''                 | 'CS44532FB05'           |'R0402'| '(R0402-0201)'                 | '453K'    | '1%'    | '1/16W'  | 'DISCRETE' | 'RES CHIP 453K 1/16W +-1%(0402)EF'                 | 'CHIPR0402'    | ''          | ''            | '20210630'
 '453K'       | '1%'      | '1/16W'  | '0402LF'  | 'EMPTY'  | 'CS44532FB05'(!)        = ''              | ''                 | 'CS44532FB05'           |'R0402'| '(R0402-0201)'                 | '453K'    | '1%'    | '1/16W'  | 'IO'       | 'RES CHIP 453K 1/16W +-1%(0402)EF'                 | 'CHIPR0402'    | ''          | ''            | '20210630'
 '17.4'       | '0.1%'    | '1/16W'  | '0402LF'  | 'CHIP'   | 'CS01742BB00'(!)        = ''              | ''                 | 'CS01742BB00'           |'R0402'| '(R0402-0201)'                 | '17.4'    | '0.1%'  | '1/16W'  | 'DISCRETE' | 'RES CHIP 17.4 1/16W +-0.1%( 0402)'                | 'CHIPR0402'    | ''          | ''            | '20210701'
 '17.4'       | '0.1%'    | '1/16W'  | '0402LF'  | 'EMPTY'  | 'CS01742BB00'(!)        = ''              | ''                 | 'CS01742BB00'           |'R0402'| '(R0402-0201)'                 | '17.4'    | '0.1%'  | '1/16W'  | 'IO'       | 'RES CHIP 17.4 1/16W +-0.1%( 0402)'                | 'CHIPR0402'    | ''          | ''            | '20210701'
 '91'         | '0.1%'    | '1/16W'  | '0402LF'  | 'CHIP'   | 'CS09102BB00'(!)        = ''              | ''                 | 'CS09102BB00'           |'R0402'| '(R0402-0201)'                 | '91'      | '0.1%'  | '1/16W'  | 'DISCRETE' | 'RES CHIP 91 1/16W +-0.1%( 0402)'                  | 'CHIPR0402'    | ''          | ''            | '20210701'
 '91'         | '0.1%'    | '1/16W'  | '0402LF'  | 'EMPTY'  | 'CS09102BB00'(!)        = ''              | ''                 | 'CS09102BB00'           |'R0402'| '(R0402-0201)'                 | '91'      | '0.1%'  | '1/16W'  | 'IO'       | 'RES CHIP 91 1/16W +-0.1%( 0402)'                  | 'CHIPR0402'    | ''          | ''            | '20210701'
 '332'        | '0.1%'    | '1/16W'  | '0402LF'  | 'CHIP'   | 'CS13322BB00'(!)        = ''              | ''                 | 'CS13322BB00'           |'R0402'| '(R0402-0201)'                 | '332'     | '0.1%'  | '1/16W'  | 'DISCRETE' | 'RES CHIP 332 1/16W +-0.1%( 0402)'                 | 'CHIPR0402'    | ''          | ''            | '20210702'
 '332'        | '0.1%'    | '1/16W'  | '0402LF'  | 'EMPTY'  | 'CS13322BB00'(!)        = ''              | ''                 | 'CS13322BB00'           |'R0402'| '(R0402-0201)'                 | '332'     | '0.1%'  | '1/16W'  | 'IO'       | 'RES CHIP 332 1/16W +-0.1%( 0402)'                 | 'CHIPR0402'    | ''          | ''            | '20210702'
 '374'        | '0.1%'    | '1/16W'  | '0402LF'  | 'CHIP'   | 'CS13742BB00'(!)        = ''              | ''                 | 'CS13742BB00'           |'R0402'| '(R0402-0201)'                 | '374'     | '0.1%'  | '1/16W'  | 'DISCRETE' | 'RES CHIP 374 1/16W +-0.1%( 0402)'                 | 'CHIPR0402'    | ''          | ''            | '20210702'
 '374'        | '0.1%'    | '1/16W'  | '0402LF'  | 'EMPTY'  | 'CS13742BB00'(!)        = ''              | ''                 | 'CS13742BB00'           |'R0402'| '(R0402-0201)'                 | '374'     | '0.1%'  | '1/16W'  | 'IO'       | 'RES CHIP 374 1/16W +-0.1%( 0402)'                 | 'CHIPR0402'    | ''          | ''            | '20210702'
 '590'        | '0.1%'    | '1/16W'  | '0402LF'  | 'CHIP'   | 'CS15902BB00'(!)        = ''              | ''                 | 'CS15902BB00'           |'R0402'| '(R0402-0201)'                 | '590'     | '0.1%'  | '1/16W'  | 'DISCRETE' | 'RES CHIP 590 1/16W +-0.1%( 0402)'                 | 'CHIPR0402'    | ''          | ''            | '20210702'
 '590'        | '0.1%'    | '1/16W'  | '0402LF'  | 'EMPTY'  | 'CS15902BB00'(!)        = ''              | ''                 | 'CS15902BB00'           |'R0402'| '(R0402-0201)'                 | '590'     | '0.1%'  | '1/16W'  | 'IO'       | 'RES CHIP 590 1/16W +-0.1%( 0402)'                 | 'CHIPR0402'    | ''          | ''            | '20210702'
 '300K'       | '1%'      | '1/16W'  | '0402LF'  | 'CHIP'   | 'CS43002FB01'(!)        = 'End of Design' | 'Comp-Approve'     | 'CS43002FB01'           |'R0402'| '(R0402-0201)'                 | '300K'    | '1%'    | '1/16W'  | 'DISCRETE' | 'RES CHIP 300K 1/16W +-1%(0402)EF'                 | 'CHIPR0402'    | ''          | ''            | '20210702'
 '300K'       | '1%'      | '1/16W'  | '0402LF'  | 'EMPTY'  | 'CS43002FB01'(!)        = 'End of Design' | 'Comp-Approve'     | 'CS43002FB01'           |'R0402'| '(R0402-0201)'                 | '300K'    | '1%'    | '1/16W'  | 'IO'       | 'RES CHIP 300K 1/16W +-1%(0402)EF'                 | 'CHIPR0402'    | ''          | ''            | '20210702'
 '3.92K'      | '0.1%'    | '1/16W'  | '0402LF'  | 'CHIP'   | 'CS23922BB00'(!)        = 'End of Design' | 'Comp-Approve'     | 'CS23922BB00'           |'R0402'| '(R0402-0201)'                 | '3.92K'   | '0.1%'  | '1/16W'  | 'DISCRETE' | 'RES CHIP 3.92K 1/16W +-0.1%(0402)'                | 'CHIPR0402'    | ''          | ''            | '20210702'
 '3.92K'      | '0.1%'    | '1/16W'  | '0402LF'  | 'EMPTY'  | 'CS23922BB00'(!)        = 'End of Design' | 'Comp-Approve'     | 'CS23922BB00'           |'R0402'| '(R0402-0201)'                 | '3.92K'   | '0.1%'  | '1/16W'  | 'IO'       | 'RES CHIP 3.92K 1/16W +-0.1%(0402)'                | 'CHIPR0402'    | ''          | ''            | '20210702'
 '17.4'       | '1%'      | '1/16W'  | '0402LF'  | 'CHIP'   | 'CS01742FB00'(!)        = ''              | ''                 | 'CS01742FB00'           |'R0402'| '(R0402-0201)'                 | '17.4'    | '1%'    | '1/16W'  | 'DISCRETE' | 'RES CHIP 17.4 1/16W +-1%( 0402)'                  | 'CHIPR0402'    | ''          | ''            | '20210707'
 '17.4'       | '1%'      | '1/16W'  | '0402LF'  | 'EMPTY'  | 'CS01742FB00'(!)        = ''              | ''                 | 'CS01742FB00'           |'R0402'| '(R0402-0201)'                 | '17.4'    | '1%'    | '1/16W'  | 'IO'       | 'RES CHIP 17.4 1/16W +-1%( 0402)'                  | 'CHIPR0402'    | ''          | ''            | '20210707'
 '84.5'       | '1%'      | '1/16W'  | '0402LF'  | 'CHIP'   | 'CS08452FB01'(!)        = 'End of Design' | 'Comp-Approve'     | 'CS08452FB01'           |'R0402'| '(R0402-0201)'                 | '84.5'    | '1%'    | '1/16W'  | 'DISCRETE' | 'RES CHIP 84.5 1/16W 1%(0402)'                     | 'CHIPR0402'    | ''          | ''            | '20210707'
 '84.5'       | '1%'      | '1/16W'  | '0402LF'  | 'EMPTY'  | 'CS08452FB01'(!)        = 'End of Design' | 'Comp-Approve'     | 'CS08452FB01'           |'R0402'| '(R0402-0201)'                 | '84.5'    | '1%'    | '1/16W'  | 'IO'       | 'RES CHIP 84.5 1/16W 1%(0402)'                     | 'CHIPR0402'    | ''          | ''            | '20210707'
 '5.1'        | '5%'      | '1/16W'  | '0402LF'  | 'CHIP'   | 'CS-5102JB02'(!)        = ''              | ''                 | 'CS-5102JB02'           |'R0402'| '(R0402-0201)'                 | '5.1'     | '5%'    | '1/16W'  | 'DISCRETE' | 'RES CHIP 5.1 1/16W +-5%(0402)EF'                  | 'CHIPR0402'    | ''          | ''            | '20210715'
 '5.1'        | '5%'      | '1/16W'  | '0402LF'  | 'EMPTY'  | 'CS-5102JB02'(!)        = ''              | ''                 | 'CS-5102JB02'           |'R0402'| '(R0402-0201)'                 | '5.1'     | '5%'    | '1/16W'  | 'IO'       | 'RES CHIP 5.1 1/16W +-5%(0402)EF'                  | 'CHIPR0402'    | ''          | ''            | '20210715'
 '2.4K'       | '1%'      | '1/16W'  | '0402LF'  | 'CHIP'   | 'CS22402FB02'(!)        = ''              | ''                 | 'CS22402FB02'           |'R0402'| '(R0402-0201)'                 | '2.4K'    | '1%'    | '1/16W'  | 'DISCRETE' | 'RES CHIP 2.4K 1/16W+-1%(0402)EF'                  | 'CHIPR0402'    | ''          | ''            | '20210715'
 '2.4K'       | '1%'      | '1/16W'  | '0402LF'  | 'EMPTY'  | 'CS22402FB02'(!)        = ''              | ''                 | 'CS22402FB02'           |'R0402'| '(R0402-0201)'                 | '2.4K'    | '1%'    | '1/16W'  | 'IO'       | 'RES CHIP 2.4K 1/16W+-1%(0402)EF'                  | 'CHIPR0402'    | ''          | ''            | '20210715'
 '4.64K'      | '0.5%'    | '1/16W'  | '0402LF'  | 'CHIP'   | 'CS24642DB01'(!)        = ''              | ''                 | 'CS24642DB01'           |'R0402'| '(R0402-0201)'                 | '4.64K'   | '0.5%'  | '1/16W'  | 'DISCRETE' | 'RES CHIP 4.64K 1/16W +-0.5%(0402)EF'              | 'CHIPR0402'    | ''          | ''            | '20210715'
 '4.64K'      | '0.5%'    | '1/16W'  | '0402LF'  | 'EMPTY'  | 'CS24642DB01'(!)        = ''              | ''                 | 'CS24642DB01'           |'R0402'| '(R0402-0201)'                 | '4.64K'   | '0.5%'  | '1/16W'  | 'IO'       | 'RES CHIP 4.64K 1/16W +-0.5%(0402)EF'              | 'CHIPR0402'    | ''          | ''            | '20210715'
 '15.4K'      | '1%'      | '1/16W'  | '0402LF'  | 'CHIP'   | 'CS31542FB02'(!)        = ''              | ''                 | 'CS31542FB02'           |'R0402'| '(R0402-0201)'                 | '15.4K'   | '1%'    | '1/16W'  | 'DISCRETE' | 'RES CHIP 15.4K 1/16W +-1%(0402)EF'                | 'CHIPR0402'    | ''          | ''            | '20210715'
 '15.4K'      | '1%'      | '1/16W'  | '0402LF'  | 'EMPTY'  | 'CS31542FB02'(!)        = ''              | ''                 | 'CS31542FB02'           |'R0402'| '(R0402-0201)'                 | '15.4K'   | '1%'    | '1/16W'  | 'IO'       | 'RES CHIP 15.4K 1/16W +-1%(0402)EF'                | 'CHIPR0402'    | ''          | ''            | '20210715'
 '18.2K'      | '0.1%'    | '1/16W'  | '0402LF'  | 'CHIP'   | 'CS31822BB01'(!)        = ''              | ''                 | 'CS31822BB01'           |'R0402'| '(R0402-0201)'                 | '18.2K'   | '0.1%'  | '1/16W'  | 'DISCRETE' | 'RES CHIP 18.2K 1/16W +-0.1%(0402)EF'              | 'CHIPR0402'    | ''          | ''            | '20210715'
 '18.2K'      | '0.1%'    | '1/16W'  | '0402LF'  | 'EMPTY'  | 'CS31822BB01'(!)        = ''              | ''                 | 'CS31822BB01'           |'R0402'| '(R0402-0201)'                 | '18.2K'   | '0.1%'  | '1/16W'  | 'IO'       | 'RES CHIP 18.2K 1/16W +-0.1%(0402)EF'              | 'CHIPR0402'    | ''          | ''            | '20210715'
 '127K'       | '1%'      | '1/16W'  | '0402LF'  | 'CHIP'   | 'CS41272FB07'(!)        = ''              | ''                 | 'CS41272FB07'           |'R0402'| '(R0402-0201)'                 | '127K'    | '1%'    | '1/16W'  | 'DISCRETE' | 'RES CHIP 127K 1/16W +-1%(0402)EF'                 | 'CHIPR0402'    | ''          | ''            | '20210715'
 '127K'       | '1%'      | '1/16W'  | '0402LF'  | 'EMPTY'  | 'CS41272FB07'(!)        = ''              | ''                 | 'CS41272FB07'           |'R0402'| '(R0402-0201)'                 | '127K'    | '1%'    | '1/16W'  | 'IO'       | 'RES CHIP 127K 1/16W +-1%(0402)EF'                 | 'CHIPR0402'    | ''          | ''            | '20210715'
 '0'          | '5%'      | '1/4W'   | '1206LF'  | 'CHIP'   | 'CS00006J207'(!)        = 'End of Design' | 'Comp-Approve'     | 'CS00006J207'           |'R1206XF'| '(SMR1206AW)'                  | '0'       | '5%'    | '1/4W'   | 'DISCRETE' | 'RES CHIP 0 1/4W +-5%(1206)EF'                     | 'CHIPR1206'    | ''          | ''            | '20210715'
 '0'          | '5%'      | '1/4W'   | '1206LF'  | 'EMPTY'  | 'CS00006J207'(!)        = 'End of Design' | 'Comp-Approve'     | 'CS00006J207'           |'R1206XF'| '(SMR1206AW)'                  | '0'       | '5%'    | '1/4W'   | 'IO'       | 'RES CHIP 0 1/4W +-5%(1206)EF'                     | 'CHIPR1206'    | ''          | ''            | '20210715'
 '3.3'        | '1%'      | '1/16W'  | '0402LF'  | 'CHIP'   | 'CS-3302FB01'(!)        = 'End of Design' | 'Comp-Approve'     | 'CS-3302FB01'           |'R0402'| '(R0402-0201)'                 | '3.3'     | '1%'    | '1/16W'  | 'DISCRETE' | 'RES CHIP 3.3 1/16W +-1%(0402)EF'                  | 'CHIPR0402'    | ''          | ''            | '20210715'
 '3.3'        | '1%'      | '1/16W'  | '0402LF'  | 'EMPTY'  | 'CS-3302FB01'(!)        = 'End of Design' | 'Comp-Approve'     | 'CS-3302FB01'           |'R0402'| '(R0402-0201)'                 | '3.3'     | '1%'    | '1/16W'  | 'IO'       | 'RES CHIP 3.3 1/16W +-1%(0402)EF'                  | 'CHIPR0402'    | ''          | ''            | '20210715'
 '470'        | '1%'      | '1/16W'  | '0402LF'  | 'CHIP'   | 'CS14702FB04'(!)        = 'End of Design' | 'Comp-Approve'     | 'CS14702FB04'           |'R0402'| '(R0402-0201)'                 | '470'     | '1%'    | '1/16W'  | 'DISCRETE' | 'RES CHIP 470 1/16W +-1%(0402)EF'                  | 'CHIPR0402'    | ''          | ''            | '20210715'
 '470'        | '1%'      | '1/16W'  | '0402LF'  | 'EMPTY'  | 'CS14702FB04'(!)        = 'End of Design' | 'Comp-Approve'     | 'CS14702FB04'           |'R0402'| '(R0402-0201)'                 | '470'     | '1%'    | '1/16W'  | 'IO'       | 'RES CHIP 470 1/16W +-1%(0402)EF'                  | 'CHIPR0402'    | ''          | ''            | '20210715'
 '3.9K'       | '5%'      | '1/16W'  | '0402LF'  | 'CHIP'   | 'CS23902JB04'(!)        = 'End of Design' | 'Comp-Approve'     | 'CS23902JB04'           |'R0402'| '(R0402-0201)'                 | '3.9K'    | '5%'    | '1/16W'  | 'DISCRETE' | 'RES CHIP 3.9K 1/16W +-5%(0402)EF'                 | 'CHIPR0402'    | ''          | ''            | '20210715'
 '3.9K'       | '5%'      | '1/16W'  | '0402LF'  | 'EMPTY'  | 'CS23902JB04'(!)        = 'End of Design' | 'Comp-Approve'     | 'CS23902JB04'           |'R0402'| '(R0402-0201)'                 | '3.9K'    | '5%'    | '1/16W'  | 'IO'       | 'RES CHIP 3.9K 1/16W +-5%(0402)EF'                 | 'CHIPR0402'    | ''          | ''            | '20210715'
 '4.32K'      | '1%'      | '1/16W'  | '0402LF'  | 'CHIP'   | 'CS24322FB03'(!)        = 'End of Design' | 'Comp-Approve'     | 'CS24322FB03'           |'R0402'| '(R0402-0201)'                 | '4.32K'   | '1%'    | '1/16W'  | 'DISCRETE' | 'RES CHIP 4.32K 1/16W +-1%(0402)EF'                | 'CHIPR0402'    | ''          | ''            | '20210715'
 '4.32K'      | '1%'      | '1/16W'  | '0402LF'  | 'EMPTY'  | 'CS24322FB03'(!)        = 'End of Design' | 'Comp-Approve'     | 'CS24322FB03'           |'R0402'| '(R0402-0201)'                 | '4.32K'   | '1%'    | '1/16W'  | 'IO'       | 'RES CHIP 4.32K 1/16W +-1%(0402)EF'                | 'CHIPR0402'    | ''          | ''            | '20210715'
 '9.09K'      | '1%'      | '1/16W'  | '0402LF'  | 'CHIP'   | 'CS29092FB05'(!)        = 'End of Design' | 'Comp-Approve'     | 'CS29092FB05'           |'R0402'| '(R0402-0201)'                 | '9.09K'   | '1%'    | '1/16W'  | 'DISCRETE' | 'RES CHIP 9.09K 1/16W +-1%(0402)EF'                | 'CHIPR0402'    | ''          | ''            | '20210715'
 '9.09K'      | '1%'      | '1/16W'  | '0402LF'  | 'EMPTY'  | 'CS29092FB05'(!)        = 'End of Design' | 'Comp-Approve'     | 'CS29092FB05'           |'R0402'| '(R0402-0201)'                 | '9.09K'   | '1%'    | '1/16W'  | 'IO'       | 'RES CHIP 9.09K 1/16W +-1%(0402)EF'                | 'CHIPR0402'    | ''          | ''            | '20210715'
 '30.1K'      | '1%'      | '1/16W'  | '0402LF'  | 'CHIP'   | 'CS33012FB03'(!)        = 'End of Design' | 'Comp-Approve'     | 'CS33012FB03'           |'R0402'| '(R0402-0201)'                 | '30.1K'   | '1%'    | '1/16W'  | 'DISCRETE' | 'RES CHIP 30.1K 1/16W +-1%(0402)EF'                | 'CHIPR0402'    | ''          | ''            | '20210715'
 '30.1K'      | '1%'      | '1/16W'  | '0402LF'  | 'EMPTY'  | 'CS33012FB03'(!)        = 'End of Design' | 'Comp-Approve'     | 'CS33012FB03'           |'R0402'| '(R0402-0201)'                 | '30.1K'   | '1%'    | '1/16W'  | 'IO'       | 'RES CHIP 30.1K 1/16W +-1%(0402)EF'                | 'CHIPR0402'    | ''          | ''            | '20210715'
 '84.5K'      | '1%'      | '1/16W'  | '0402LF'  | 'CHIP'   | 'CS38452FB05'(!)        = 'End of Design' | 'Comp-Approve'     | 'CS38452FB05'           |'R0402'| '(R0402-0201)'                 | '84.5K'   | '1%'    | '1/16W'  | 'DISCRETE' | 'RES CHIP 84.5K 1/16W +-1%(0402)EF'                | 'CHIPR0402'    | ''          | ''            | '20210715'
 '84.5K'      | '1%'      | '1/16W'  | '0402LF'  | 'EMPTY'  | 'CS38452FB05'(!)        = 'End of Design' | 'Comp-Approve'     | 'CS38452FB05'           |'R0402'| '(R0402-0201)'                 | '84.5K'   | '1%'    | '1/16W'  | 'IO'       | 'RES CHIP 84.5K 1/16W +-1%(0402)EF'                | 'CHIPR0402'    | ''          | ''            | '20210715'
 '196K'       | '1%'      | '1/16W'  | '0402LF'  | 'CHIP'   | 'CS41962FB03'(!)        = 'End of Design' | 'Comp-Approve'     | 'CS41962FB03'           |'R0402'| '(R0402-0201)'                 | '196K'    | '1%'    | '1/16W'  | 'DISCRETE' | 'RES CHIP 196K 1/16W +-1%(0402)EF'                 | 'CHIPR0402'    | ''          | ''            | '20210715'
 '196K'       | '1%'      | '1/16W'  | '0402LF'  | 'EMPTY'  | 'CS41962FB03'(!)        = 'End of Design' | 'Comp-Approve'     | 'CS41962FB03'           |'R0402'| '(R0402-0201)'                 | '196K'    | '1%'    | '1/16W'  | 'IO'       | 'RES CHIP 196K 1/16W +-1%(0402)EF'                 | 'CHIPR0402'    | ''          | ''            | '20210715'
 '18K'        | '1%'      | '1/16W'  | '0402LF'  | 'CHIP'   | 'CS31802FB04'(!)        = ''              | ''                 | 'CS31802FB04'           |'R0402'| '(R0402-0201)'                 | '18K'     | '1%'    | '1/16W'  | 'DISCRETE' | 'RES CHIP 18K 1/16W +-1%(0402)EF'                  | 'CHIPR0402'    | ''          | ''            | '20210719'
 '18K'        | '1%'      | '1/16W'  | '0402LF'  | 'EMPTY'  | 'CS31802FB04'(!)        = ''              | ''                 | 'CS31802FB04'           |'R0402'| '(R0402-0201)'                 | '18K'     | '1%'    | '1/16W'  | 'IO'       | 'RES CHIP 18K 1/16W +-1%(0402)EF'                  | 'CHIPR0402'    | ''          | ''            | '20210719'
 '4.7'        | '1%'      | '1/16W'  | '0402LF'  | 'CHIP'   | 'CS-4702FB09'(!)        = ''              | ''                 | 'CS-4702FB09'           |'R0402'| '(R0402-0201)'                 | '4.7'     | '1%'    | '1/16W'  | 'DISCRETE' | 'RES CHIP 4.7 1/16W +-1%(0402)EF'                  | 'CHIPR0402'    | ''          | ''            | '20210719'
 '4.7'        | '1%'      | '1/16W'  | '0402LF'  | 'EMPTY'  | 'CS-4702FB09'(!)        = ''              | ''                 | 'CS-4702FB09'           |'R0402'| '(R0402-0201)'                 | '4.7'     | '1%'    | '1/16W'  | 'IO'       | 'RES CHIP 4.7 1/16W +-1%(0402)EF'                  | 'CHIPR0402'    | ''          | ''            | '20210719'
 '5.23K'      | '1%'      | '1/16W'  | '0402LF'  | 'CHIP'   | 'CS25232FB08'(!)        = ''              | ''                 | 'CS25232FB08'           |'R0402'| '(R0402-0201)'                 | '5.23K'   | '1%'    | '1/16W'  | 'DISCRETE' | 'RES CHIP 5.23K 1/16W +-1%(0402)EF'                | 'CHIPR0402'    | ''          | ''            | '20210719'
 '5.23K'      | '1%'      | '1/16W'  | '0402LF'  | 'EMPTY'  | 'CS25232FB08'(!)        = ''              | ''                 | 'CS25232FB08'           |'R0402'| '(R0402-0201)'                 | '5.23K'   | '1%'    | '1/16W'  | 'IO'       | 'RES CHIP 5.23K 1/16W +-1%(0402)EF'                | 'CHIPR0402'    | ''          | ''            | '20210719'
 '7.32K'      | '0.1%'    | '1/16W'  | '0402LF'  | 'CHIP'   | 'CS27322BB09'(!)        = ''              | ''                 | 'CS27322BB09'           |'R0402'| '(R0402-0201)'                 | '7.32K'   | '0.1%'  | '1/16W'  | 'DISCRETE' | 'RES CHIP 7.32K 1/16W +-0.1% (0402)EF'             | 'CHIPR0402'    | ''          | ''            | '20210719'
 '7.32K'      | '0.1%'    | '1/16W'  | '0402LF'  | 'EMPTY'  | 'CS27322BB09'(!)        = ''              | ''                 | 'CS27322BB09'           |'R0402'| '(R0402-0201)'                 | '7.32K'   | '0.1%'  | '1/16W'  | 'IO'       | 'RES CHIP 7.32K 1/16W +-0.1% (0402)EF'             | 'CHIPR0402'    | ''          | ''            | '20210719'
 '11.8K'      | '0.1%'    | '1/16W'  | '0402LF'  | 'CHIP'   | 'CS31182BB06'(!)        = ''              | ''                 | 'CS31182BB06'           |'R0402'| '(R0402-0201)'                 | '11.8K'   | '0.1%'  | '1/16W'  | 'DISCRETE' | 'RES CHIP 11.8K 1/16W +-0.1%(0402)EF'              | 'CHIPR0402'    | ''          | ''            | '20210719'
 '11.8K'      | '0.1%'    | '1/16W'  | '0402LF'  | 'EMPTY'  | 'CS31182BB06'(!)        = ''              | ''                 | 'CS31182BB06'           |'R0402'| '(R0402-0201)'                 | '11.8K'   | '0.1%'  | '1/16W'  | 'IO'       | 'RES CHIP 11.8K 1/16W +-0.1%(0402)EF'              | 'CHIPR0402'    | ''          | ''            | '20210719'
 '12.4K'      | '0.1%'    | '1/16W'  | '0402LF'  | 'CHIP'   | 'CS31242BB10'(!)        = ''              | ''                 | 'CS31242BB10'           |'R0402'| '(R0402-0201)'                 | '12.4K'   | '0.1%'  | '1/16W'  | 'DISCRETE' | 'RES CHIP 12.4K 1/16W +-0.1%( 0402)EF'             | 'CHIPR0402'    | ''          | ''            | '20210719'
 '12.4K'      | '0.1%'    | '1/16W'  | '0402LF'  | 'EMPTY'  | 'CS31242BB10'(!)        = ''              | ''                 | 'CS31242BB10'           |'R0402'| '(R0402-0201)'                 | '12.4K'   | '0.1%'  | '1/16W'  | 'IO'       | 'RES CHIP 12.4K 1/16W +-0.1%( 0402)EF'             | 'CHIPR0402'    | ''          | ''            | '20210719'
 '26.1K'      | '0.1%'    | '1/16W'  | '0402LF'  | 'CHIP'   | 'CS32612BB02'(!)        = ''              | ''                 | 'CS32612BB02'           |'R0402'| '(R0402-0201)'                 | '26.1K'   | '0.1%'  | '1/16W'  | 'DISCRETE' | 'RES CHIP 26.1K 1/16W +-0.1%(0402)EF'              | 'CHIPR0402'    | ''          | ''            | '20210720'
 '26.1K'      | '0.1%'    | '1/16W'  | '0402LF'  | 'EMPTY'  | 'CS32612BB02'(!)        = ''              | ''                 | 'CS32612BB02'           |'R0402'| '(R0402-0201)'                 | '26.1K'   | '0.1%'  | '1/16W'  | 'IO'       | 'RES CHIP 26.1K 1/16W +-0.1%(0402)EF'              | 'CHIPR0402'    | ''          | ''            | '20210720'
 '36K'        | '0.1%'    | '1/16W'  | '0402LF'  | 'CHIP'   | 'CS33602BB01'(!)        = ''              | ''                 | 'CS33602BB01'           |'R0402'| '(R0402-0201)'                 | '36K'     | '0.1%'  | '1/16W'  | 'DISCRETE' | 'RES CHIP 36K 1/16W +-0.1%(0402)EF'                | 'CHIPR0402'    | ''          | ''            | '20210720'
 '36K'        | '0.1%'    | '1/16W'  | '0402LF'  | 'EMPTY'  | 'CS33602BB01'(!)        = ''              | ''                 | 'CS33602BB01'           |'R0402'| '(R0402-0201)'                 | '36K'     | '0.1%'  | '1/16W'  | 'IO'       | 'RES CHIP 36K 1/16W +-0.1%(0402)EF'                | 'CHIPR0402'    | ''          | ''            | '20210720'
 '23.2K'      | '1%'      | '1/16W'  | '0402LF'  | 'CHIP'   | 'CS32322FB03'(!)        = 'End of Design' | 'Comp-Approve'     | 'CS32322FB03'           |'R0402'| '(R0402-0201)'                 | '23.2K'   | '1%'    | '1/16W'  | 'DISCRETE' | 'RES CHIP 23.2K 1/16W +-1%(0402)EF'                | 'CHIPR0402'    | ''          | ''            | '20210720'
 '23.2K'      | '1%'      | '1/16W'  | '0402LF'  | 'EMPTY'  | 'CS32322FB03'(!)        = 'End of Design' | 'Comp-Approve'     | 'CS32322FB03'           |'R0402'| '(R0402-0201)'                 | '23.2K'   | '1%'    | '1/16W'  | 'IO'       | 'RES CHIP 23.2K 1/16W +-1%(0402)EF'                | 'CHIPR0402'    | ''          | ''            | '20210720'
 '0.003'      | '1%'      | '3W'     | '2512LF'  | 'CHIP'   | 'CS+003DFR06'(!)        = ''              | ''                 | 'CS+003DFR06'           |'R2512XZ'| '(SMR2512AW)'                  | '0.003'   | '1%'    | '3W'     | 'DISCRETE' | 'RES CHIP 0.003 3W +-1%(2512)CYN'                  | 'CHIPR2512'    | ''          | ''            | '20210727'
 '0.003'      | '1%'      | '3W'     | '2512LF'  | 'EMPTY'  | 'CS+003DFR06'(!)        = ''              | ''                 | 'CS+003DFR06'           |'R2512XZ'| '(SMR2512AW)'                  | '0.003'   | '1%'    | '3W'     | 'IO'       | 'RES CHIP 0.003 3W +-1%(2512)CYN'                  | 'CHIPR2512'    | ''          | ''            | '20210727'
 '316'        | '1%'      | '1/16W'  | '0402LF'  | 'CHIP'   | 'CS13162FB01'(!)        = ''              | ''                 | 'CS13162FB01'           |'R0402'| '(R0402-0201)'                 | '316'     | '1%'    | '1/16W'  | 'DISCRETE' | 'RES CHIP 316 1/16W +-1%(0402)EF'                  | 'CHIPR0402'    | ''          | ''            | '20210727'
 '316'        | '1%'      | '1/16W'  | '0402LF'  | 'EMPTY'  | 'CS13162FB01'(!)        = ''              | ''                 | 'CS13162FB01'           |'R0402'| '(R0402-0201)'                 | '316'     | '1%'    | '1/16W'  | 'IO'       | 'RES CHIP 316 1/16W +-1%(0402)EF'                  | 'CHIPR0402'    | ''          | ''            | '20210727'
 '1K'         | '5%'      | '1/4W'   | '1206LF'  | 'CHIP'   | 'CS21006J202'(!)        = ''              | ''                 | 'CS21006J202'           |'R1206XN'| '(SMR1206AW)'                  | '1K'      | '5%'    | '1/4W'   | 'DISCRETE' | 'RES CHIP 1K 1/4W +-5%(1206)EF'                    | 'CHIPR1206'    | ''          | ''            | '20210727'
 '1K'         | '5%'      | '1/4W'   | '1206LF'  | 'EMPTY'  | 'CS21006J202'(!)        = ''              | ''                 | 'CS21006J202'           |'R1206XN'| '(SMR1206AW)'                  | '1K'      | '5%'    | '1/4W'   | 'IO'       | 'RES CHIP 1K 1/4W +-5%(1206)EF'                    | 'CHIPR1206'    | ''          | ''            | '20210727'
 '2.2K'       | '0.1%'    | '1/16W'  | '0402LF'  | 'CHIP'   | 'CS22202BB02'(!)        = ''              | ''                 | 'CS22202BB02'           |'R0402'| '(R0402-0201)'                 | '2.2K'    | '0.1%'  | '1/16W'  | 'DISCRETE' | 'RES CHIP 2.2K 1/16W +-0.1%(0402)'                 | 'CHIPR0402'    | ''          | ''            | '20210730'
 '2.2K'       | '0.1%'    | '1/16W'  | '0402LF'  | 'EMPTY'  | 'CS22202BB02'(!)        = ''              | ''                 | 'CS22202BB02'           |'R0402'| '(R0402-0201)'                 | '2.2K'    | '0.1%'  | '1/16W'  | 'IO'       | 'RES CHIP 2.2K 1/16W +-0.1%(0402)'                 | 'CHIPR0402'    | ''          | ''            | '20210730'
 '0.05'       | '1%'      | '1/2W'   | '1206LF'  | 'CHIP'   | 'CS+0507F200'(!)        = ''              | ''                 | 'CS+0507F200'           |'R1206XQ'| '(SMR1206AW)'                  | '0.05'    | '1%'    | '1/2W'   | 'DISCRETE' | 'RES CHIP 0.05 1/2W +-1%(1206)'                    | 'CHIPR1206'    | ''          | ''            | '20210802'
 '0.05'       | '1%'      | '1/2W'   | '1206LF'  | 'EMPTY'  | 'CS+0507F200'(!)        = ''              | ''                 | 'CS+0507F200'           |'R1206XQ'| '(SMR1206AW)'                  | '0.05'    | '1%'    | '1/2W'   | 'IO'       | 'RES CHIP 0.05 1/2W +-1%(1206)'                    | 'CHIPR1206'    | ''          | ''            | '20210802'
 '27.4'       | '1%'      | '1/20W'  | '0201LF'  | 'CHIP'   | 'CS02741FE02'(!)        = ''              | ''                 | 'CS02741FE02'           |'R0201'| '(SMR0201AW)'                  | '27.4'    | '1%'    | '1/20W'  | 'DISCRETE' | 'RES CHIP 27.4 1/20W +-1%(0201)EF'                 | 'CHIPR0201'    | ''          | ''            | '20210804'
 '27.4'       | '1%'      | '1/20W'  | '0201LF'  | 'EMPTY'  | 'CS02741FE02'(!)        = ''              | ''                 | 'CS02741FE02'           |'R0201'| '(SMR0201AW)'                  | '27.4'    | '1%'    | '1/20W'  | 'IO'       | 'RES CHIP 27.4 1/20W +-1%(0201)EF'                 | 'CHIPR0201'    | ''          | ''            | '20210804'
 '1.5K'       | '1%'      | '1/20W'  | '0201LF'  | 'CHIP'   | 'CS21501FE14'(!)        = ''              | ''                 | 'CS21501FE14'           |'R0201'| '(SMR0201AW)'                  | '1.5K'    | '1%'    | '1/20W'  | 'DISCRETE' | 'RES CHIP 1.5K 1/20W +-1%(0201)EF'                 | 'CHIPR0201'    | ''          | ''            | '20210804'
 '1.5K'       | '1%'      | '1/20W'  | '0201LF'  | 'EMPTY'  | 'CS21501FE14'(!)        = ''              | ''                 | 'CS21501FE14'           |'R0201'| '(SMR0201AW)'                  | '1.5K'    | '1%'    | '1/20W'  | 'IO'       | 'RES CHIP 1.5K 1/20W +-1%(0201)EF'                 | 'CHIPR0201'    | ''          | ''            | '20210804'
 '1.24K'      | '1%'      | '1/16W'  | '0402LF'  | 'CHIP'   | 'CS21242FB04'(!)        = 'End of Design' | 'Comp-Approve'     | 'CS21242FB04'           |'R0402'| '(R0402-0201)'                 | '1.24K'   | '1%'    | '1/16W'  | 'DISCRETE' | 'RES CHIP 1.24K 1/16W +-1%(0402)EF'                | 'CHIPR0402'    | ''          | ''            | '20210804'
 '1.24K'      | '1%'      | '1/16W'  | '0402LF'  | 'EMPTY'  | 'CS21242FB04'(!)        = 'End of Design' | 'Comp-Approve'     | 'CS21242FB04'           |'R0402'| '(R0402-0201)'                 | '1.24K'   | '1%'    | '1/16W'  | 'IO'       | 'RES CHIP 1.24K 1/16W +-1%(0402)EF'                | 'CHIPR0402'    | ''          | ''            | '20210804'
 '1.69K'      | '1%'      | '1/16W'  | '0402LF'  | 'CHIP'   | 'CS21692FB04'(!)        = 'End of Design' | 'Comp-Approve'     | 'CS21692FB04'           |'R0402'| '(R0402-0201)'                 | '1.69K'   | '1%'    | '1/16W'  | 'DISCRETE' | 'RES CHIP 1.69K 1/16W +-1%(0402)EF'                | 'CHIPR0402'    | ''          | ''            | '20210804'
 '1.69K'      | '1%'      | '1/16W'  | '0402LF'  | 'EMPTY'  | 'CS21692FB04'(!)        = 'End of Design' | 'Comp-Approve'     | 'CS21692FB04'           |'R0402'| '(R0402-0201)'                 | '1.69K'   | '1%'    | '1/16W'  | 'IO'       | 'RES CHIP 1.69K 1/16W +-1%(0402)EF'                | 'CHIPR0402'    | ''          | ''            | '20210804'
 '2.74K'      | '1%'      | '1/16W'  | '0402LF'  | 'CHIP'   | 'CS22742FB05'(!)        = 'End of Design' | 'Comp-Approve'     | 'CS22742FB05'           |'R0402'| '(R0402-0201)'                 | '2.74K'   | '1%'    | '1/16W'  | 'DISCRETE' | 'RES CHIP 2.74K 1/16W +-1%(0402)EF'                | 'CHIPR0402'    | ''          | ''            | '20210804'
 '2.74K'      | '1%'      | '1/16W'  | '0402LF'  | 'EMPTY'  | 'CS22742FB05'(!)        = 'End of Design' | 'Comp-Approve'     | 'CS22742FB05'           |'R0402'| '(R0402-0201)'                 | '2.74K'   | '1%'    | '1/16W'  | 'IO'       | 'RES CHIP 2.74K 1/16W +-1%(0402)EF'                | 'CHIPR0402'    | ''          | ''            | '20210804'
 '5.49K'      | '1%'      | '1/16W'  | '0402LF'  | 'CHIP'   | 'CS25492FB02'(!)        = 'End of Design' | 'Comp-Approve'     | 'CS25492FB02'           |'R0402'| '(R0402-0201)'                 | '5.49K'   | '1%'    | '1/16W'  | 'DISCRETE' | 'RES CHIP 5.49K 1/16W +-1%(0402) EF'               | 'CHIPR0402'    | ''          | ''            | '20210804'
 '5.49K'      | '1%'      | '1/16W'  | '0402LF'  | 'EMPTY'  | 'CS25492FB02'(!)        = 'End of Design' | 'Comp-Approve'     | 'CS25492FB02'           |'R0402'| '(R0402-0201)'                 | '5.49K'   | '1%'    | '1/16W'  | 'IO'       | 'RES CHIP 5.49K 1/16W +-1%(0402) EF'               | 'CHIPR0402'    | ''          | ''            | '20210804'
 '680'        | '0.1%'    | '1/16W'  | '0402LF'  | 'CHIP'   | 'CS16802BB00'(!)        = ''              | ''                 | 'CS16802BB00'           |'R0402'| '(R0402-0201)'                 | '680'     | '0.1%'  | '1/16W'  | 'DISCRETE' | 'RES CHIP 680 1/16W +-0.1%(0402)'                  | 'CHIPR0402'    | ''          | ''            | '20210804'
 '680'        | '0.1%'    | '1/16W'  | '0402LF'  | 'EMPTY'  | 'CS16802BB00'(!)        = ''              | ''                 | 'CS16802BB00'           |'R0402'| '(R0402-0201)'                 | '680'     | '0.1%'  | '1/16W'  | 'IO'       | 'RES CHIP 680 1/16W +-0.1%(0402)'                  | 'CHIPR0402'    | ''          | ''            | '20210804'
 '15K'        | '1%'      | '1/16W'  | '0402LF'  | 'CHIP'   | 'CS31502FB12'(!)        = ''              | ''                 | 'CS31502FB12'           |'R0402'| '(R0402-0201)'                 | '15K'     | '1%'    | '1/16W'  | 'DISCRETE' | 'RES CHIP 15K 1/16W +-1%(0402)TAI'                 | 'CHIPR0402'    | ''          | ''            | '20210809'
 '15K'        | '1%'      | '1/16W'  | '0402LF'  | 'EMPTY'  | 'CS31502FB12'(!)        = ''              | ''                 | 'CS31502FB12'           |'R0402'| '(R0402-0201)'                 | '15K'     | '1%'    | '1/16W'  | 'IO'       | 'RES CHIP 15K 1/16W +-1%(0402)TAI'                 | 'CHIPR0402'    | ''          | ''            | '20210809'
 '1.65K'      | '0.1%'    | '1/16W'  | '0402LF'  | 'CHIP'   | 'CS21652BB00'(!)        = ''              | ''                 | 'CS21652BB00'           |'R0402'| '(R0402-0201)'                 | '1.65K'   | '0.1%'  | '1/16W'  | 'DISCRETE' | 'RES CHIP 1.65K 1/16W +-0.1%(0402)'                | 'CHIPR0402'    | ''          | ''            | '20210811'
 '1.65K'      | '0.1%'    | '1/16W'  | '0402LF'  | 'EMPTY'  | 'CS21652BB00'(!)        = ''              | ''                 | 'CS21652BB00'           |'R0402'| '(R0402-0201)'                 | '1.65K'   | '0.1%'  | '1/16W'  | 'IO'       | 'RES CHIP 1.65K 1/16W +-0.1%(0402)'                | 'CHIPR0402'    | ''          | ''            | '20210811'
 '2.87K'      | '0.1%'    | '1/16W'  | '0402LF'  | 'CHIP'   | 'CS22872BB01'(!)        = ''              | ''                 | 'CS22872BB01'           |'R0402'| '(R0402-0201)'                 | '2.87K'   | '0.1%'  | '1/16W'  | 'DISCRETE' | 'RES CHIP 2.87K 1/16W+-0.1%( 0402)'                | 'CHIPR0402'    | ''          | ''            | '20210811'
 '2.87K'      | '0.1%'    | '1/16W'  | '0402LF'  | 'EMPTY'  | 'CS22872BB01'(!)        = ''              | ''                 | 'CS22872BB01'           |'R0402'| '(R0402-0201)'                 | '2.87K'   | '0.1%'  | '1/16W'  | 'IO'       | 'RES CHIP 2.87K 1/16W+-0.1%( 0402)'                | 'CHIPR0402'    | ''          | ''            | '20210811'
 '1.13K'      | '0.1%'    | '1/16W'  | '0402LF'  | 'CHIP'   | 'CS21132BB00'(!)        = ''              | ''                 | 'CS21132BB00'           |'R0402'| '(R0402-0201)'                 | '1.13K'   | '0.1%'  | '1/16W'  | 'DISCRETE' | 'RES CHIP 1.13K 1/16W+-0.1%( 0402)'                | 'CHIPR0402'    | ''          | ''            | '20210811'
 '1.13K'      | '0.1%'    | '1/16W'  | '0402LF'  | 'EMPTY'  | 'CS21132BB00'(!)        = ''              | ''                 | 'CS21132BB00'           |'R0402'| '(R0402-0201)'                 | '1.13K'   | '0.1%'  | '1/16W'  | 'IO'       | 'RES CHIP 1.13K 1/16W+-0.1%( 0402)'                | 'CHIPR0402'    | ''          | ''            | '20210811'
 '4.53K'      | '0.1%'    | '1/16W'  | '0402LF'  | 'CHIP'   | 'CS24532BB00'(!)        = ''              | ''                 | 'CS24532BB00'           |'R0402'| '(R0402-0201)'                 | '4.53K'   | '0.1%'  | '1/16W'  | 'DISCRETE' | 'RES CHIP 4.53K 1/16W+-0.1%( 0402)'                | 'CHIPR0402'    | ''          | ''            | '20210811'
 '4.53K'      | '0.1%'    | '1/16W'  | '0402LF'  | 'EMPTY'  | 'CS24532BB00'(!)        = ''              | ''                 | 'CS24532BB00'           |'R0402'| '(R0402-0201)'                 | '4.53K'   | '0.1%'  | '1/16W'  | 'IO'       | 'RES CHIP 4.53K 1/16W+-0.1%( 0402)'                | 'CHIPR0402'    | ''          | ''            | '20210811'
 '360'        | '1%'      | '1/16W'  | '0402LF'  | 'CHIP'   | 'CS13602FB00'(!)        = 'End of Design' | 'Comp-Approve'     | 'CS13602FB00'           |'R0402'| '(R0402-0201)'                 | '360'     | '1%'    | '1/16W'  | 'DISCRETE' | 'RES CHIP 360 1/16W +-1%(0402)'                    | 'CHIPR0402'    | ''          | ''            | '20210817'
 '360'        | '1%'      | '1/16W'  | '0402LF'  | 'EMPTY'  | 'CS13602FB00'(!)        = 'End of Design' | 'Comp-Approve'     | 'CS13602FB00'           |'R0402'| '(R0402-0201)'                 | '360'     | '1%'    | '1/16W'  | 'IO'       | 'RES CHIP 360 1/16W +-1%(0402)'                    | 'CHIPR0402'    | ''          | ''            | '20210817'
 '0.0002'     | '1%'      | '4W'     | '2725LF'  | 'CHIP'   | 'CS0000FFT11'(!)        = ''              | ''                 | 'CS0000FFT11'           |'R2725'| '(SMR2725AW)'                  | '0.0002'  | '1%'    | '4W'     | 'DISCRETE' | 'RES CHIP 0.0002 4W +-1%(2725)RLC'                 | 'CHIPR2725'    | ''          | ''            | '20210817'
 '0.0002'     | '1%'      | '4W'     | '2725LF'  | 'EMPTY'  | 'CS0000FFT11'(!)        = ''              | ''                 | 'CS0000FFT11'           |'R2725'| '(SMR2725AW)'                  | '0.0002'  | '1%'    | '4W'     | 'IO'       | 'RES CHIP 0.0002 4W +-1%(2725)RLC'                 | 'CHIPR2725'    | ''          | ''            | '20210817'
 '10K'        | '1%'      | '1/2W'   | '1206LF'  | 'CHIP'   | 'CS31007F200'(!)        = ''              | ''                 | 'CS31007F200'           |'R1206XI'| '(SMR1206AW)'                  | '10K'     | '1%'    | '1/2W'   | 'DISCRETE' | 'RES CHIP 10K 1/2W +-1%(1206)'                     | 'CHIPR1206'    | ''          | ''            | '20210820'
 '10K'        | '1%'      | '1/2W'   | '1206LF'  | 'EMPTY'  | 'CS31007F200'(!)        = ''              | ''                 | 'CS31007F200'           |'R1206XI'| '(SMR1206AW)'                  | '10K'     | '1%'    | '1/2W'   | 'IO'       | 'RES CHIP 10K 1/2W +-1%(1206)'                     | 'CHIPR1206'    | ''          | ''            | '20210820'
 '20K'        | '0.1%'    | '1/4W'   | '1206LF'  | 'CHIP'   | 'CS32006B200'(!)        = ''              | ''                 | 'CS32006B200'           |'R1206XM'| '(SMR1206AW)'                  | '20K'     | '0.1%'  | '1/4W'   | 'DISCRETE' | 'RES CHIP 20K 1/4W +-0.1%(1206)'                   | 'CHIPR1206'    | ''          | ''            | '20210823'
 '20K'        | '0.1%'    | '1/4W'   | '1206LF'  | 'EMPTY'  | 'CS32006B200'(!)        = ''              | ''                 | 'CS32006B200'           |'R1206XM'| '(SMR1206AW)'                  | '20K'     | '0.1%'  | '1/4W'   | 'IO'       | 'RES CHIP 20K 1/4W +-0.1%(1206)'                   | 'CHIPR1206'    | ''          | ''            | '20210823'
 '20K'        | '1%'      | '1/8W'   | '0805LF'  | 'CHIP'   | 'CS32004FA05'(!)        = ''              | ''                 | 'CS32004FA05'           |'R0805_H26'| '(SMR0805AW)'                  | '20K'     | '1%'    | '1/8W'   | 'DISCRETE' | 'RES CHIP 20K 1/8W +-1%(0805)EF'                   | 'CHIPR0805'    | ''          | ''            | '20210824'
 '20K'        | '1%'      | '1/8W'   | '0805LF'  | 'EMPTY'  | 'CS32004FA05'(!)        = ''              | ''                 | 'CS32004FA05'           |'R0805_H26'| '(SMR0805AW)'                  | '20K'     | '1%'    | '1/8W'   | 'IO'       | 'RES CHIP 20K 1/8W +-1%(0805)EF'                   | 'CHIPR0805'    | ''          | ''            | '20210824'
 '100'        | '1%'      | '1/8W'   | '0805LF'  | 'CHIP'   | 'CS11004FA05'(!)        = ''              | ''                 | 'CS11004FA05'           |'R0805_H26'| '(SMR0805AW)'                  | '100'     | '1%'    | '1/8W'   | 'DISCRETE' | 'RES CHIP 100 1/8W +-1%(0805)EF'                   | 'CHIPR0805'    | ''          | ''            | '20210824'
 '100'        | '1%'      | '1/8W'   | '0805LF'  | 'EMPTY'  | 'CS11004FA05'(!)        = ''              | ''                 | 'CS11004FA05'           |'R0805_H26'| '(SMR0805AW)'                  | '100'     | '1%'    | '1/8W'   | 'IO'       | 'RES CHIP 100 1/8W +-1%(0805)EF'                   | 'CHIPR0805'    | ''          | ''            | '20210824'
 '3.3K'       | '1%'      | '1/8W'   | '0805LF'  | 'CHIP'   | 'CS23304FA00'(!)        = ''              | ''                 | 'CS23304FA00'           |'R0805_H26'| '(SMR0805AW)'                  | '3.3K'    | '1%'    | '1/8W'   | 'DISCRETE' | 'RES CHIP 3.3K 1/8W +-1%(0805)EF'                  | 'CHIPR0805'    | ''          | ''            | '20210824'
 '3.3K'       | '1%'      | '1/8W'   | '0805LF'  | 'EMPTY'  | 'CS23304FA00'(!)        = ''              | ''                 | 'CS23304FA00'           |'R0805_H26'| '(SMR0805AW)'                  | '3.3K'    | '1%'    | '1/8W'   | 'IO'       | 'RES CHIP 3.3K 1/8W +-1%(0805)EF'                  | 'CHIPR0805'    | ''          | ''            | '20210824'
 '43K'        | '1%'      | '1/8W'   | '0805LF'  | 'CHIP'   | 'CS34304FA01'(!)        = ''              | ''                 | 'CS34304FA01'           |'R0805_H26'| '(SMR0805AW)'                  | '43K'     | '1%'    | '1/8W'   | 'DISCRETE' | 'RES CHIP 43K 1/8W +-1%(0805)EF'                   | 'CHIPR0805'    | ''          | ''            | '20210824'
 '43K'        | '1%'      | '1/8W'   | '0805LF'  | 'EMPTY'  | 'CS34304FA01'(!)        = ''              | ''                 | 'CS34304FA01'           |'R0805_H26'| '(SMR0805AW)'                  | '43K'     | '1%'    | '1/8W'   | 'IO'       | 'RES CHIP 43K 1/8W +-1%(0805)EF'                   | 'CHIPR0805'    | ''          | ''            | '20210824'
 '174K'       | '1%'      | '1/8W'   | '0805LF'  | 'CHIP'   | 'CS41744FA01'(!)        = ''              | ''                 | 'CS41744FA01'           |'R0805_H26'| '(SMR0805AW)'                  | '174K'    | '1%'    | '1/8W'   | 'DISCRETE' | 'RES CHIP 174K 1/8W +-1%(0805)EF'                  | 'CHIPR0805'    | ''          | ''            | '20210824'
 '174K'       | '1%'      | '1/8W'   | '0805LF'  | 'EMPTY'  | 'CS41744FA01'(!)        = ''              | ''                 | 'CS41744FA01'           |'R0805_H26'| '(SMR0805AW)'                  | '174K'    | '1%'    | '1/8W'   | 'IO'       | 'RES CHIP 174K 1/8W +-1%(0805)EF'                  | 'CHIPR0805'    | ''          | ''            | '20210824'
 '2.05M'      | '1%'      | '1/8W'   | '0805LF'  | 'CHIP'   | 'CS52054FA01'(!)        = ''              | ''                 | 'CS52054FA01'           |'R0805_H26'| '(SMR0805AW)'                  | '2.05M'   | '1%'    | '1/8W'   | 'DISCRETE' | 'RES CHIP 2.05M 1/8W +-1%(0805)EF'                 | 'CHIPR0805'    | ''          | ''            | '20210824'
 '2.05M'      | '1%'      | '1/8W'   | '0805LF'  | 'EMPTY'  | 'CS52054FA01'(!)        = ''              | ''                 | 'CS52054FA01'           |'R0805_H26'| '(SMR0805AW)'                  | '2.05M'   | '1%'    | '1/8W'   | 'IO'       | 'RES CHIP 2.05M 1/8W +-1%(0805)EF'                 | 'CHIPR0805'    | ''          | ''            | '20210824'
 '330K'       | '1%'      | '1/16W'  | '0402LF'  | 'CHIP'   | 'CS43302FB06'(!)        = ''              | ''                 | 'CS43302FB06'           |'R0402'| '(R0402-0201)'                 | '330K'    | '1%'    | '1/16W'  | 'DISCRETE' | 'RES CHIP 330K 1/16W +-1%(0402)EF'                 | 'CHIPR0402'    | ''          | ''            | '20210824'
 '330K'       | '1%'      | '1/16W'  | '0402LF'  | 'EMPTY'  | 'CS43302FB06'(!)        = ''              | ''                 | 'CS43302FB06'           |'R0402'| '(R0402-0201)'                 | '330K'    | '1%'    | '1/16W'  | 'IO'       | 'RES CHIP 330K 1/16W +-1%(0402)EF'                 | 'CHIPR0402'    | ''          | ''            | '20210824'
 '43K'        | '1%'      | '1/10W'  | '0603LF'  | 'CHIP'   | 'CS34303F905'(!)        = ''              | ''                 | 'CS34303F905'           |'R0603'| '(SMR0603AW)'                  | '43K'     | '1%'    | '1/10W'  | 'DISCRETE' | 'RES CHIP 43K 1/10W +-1%(0603)EF'                  | 'CHIPR0603'    | ''          | ''            | '20210824'
 '43K'        | '1%'      | '1/10W'  | '0603LF'  | 'EMPTY'  | 'CS34303F905'(!)        = ''              | ''                 | 'CS34303F905'           |'R0603'| '(SMR0603AW)'                  | '43K'     | '1%'    | '1/10W'  | 'IO'       | 'RES CHIP 43K 1/10W +-1%(0603)EF'                  | 'CHIPR0603'    | ''          | ''            | '20210824'
 '1K'         | '0.5%'    | '1/20W'  | '0201LF'  | 'CHIP'   | 'CS21001DE02'(!)        = ''              | ''                 | 'CS21001DE02'           |'R0201'| '(SMR0201AW)'                  | '1K'      | '0.5%'  | '1/20W'  | 'DISCRETE' | 'RES CHIP 1K 1/20W +-0.5%(0201)'                   | 'CHIPR0201'    | ''          | ''            | '20210825'
 '1K'         | '0.5%'    | '1/20W'  | '0201LF'  | 'EMPTY'  | 'CS21001DE02'(!)        = ''              | ''                 | 'CS21001DE02'           |'R0201'| '(SMR0201AW)'                  | '1K'      | '0.5%'  | '1/20W'  | 'IO'       | 'RES CHIP 1K 1/20W +-0.5%(0201)'                   | 'CHIPR0201'    | ''          | ''            | '20210825'
 '910'        | '1%'      | '1/2W'   | '1206LF'  | 'CHIP'   | 'CS19107F200'(!)        = ''              | ''                 | 'CS19107F200'           |'R1206XF'| '(SMR1206AW)'                  | '910'     | '1%'    | '1/2W'   | 'DISCRETE' | 'RES CHIP 910 1/2W +-1%(1206)'                     | 'CHIPR1206'    | ''          | ''            | '20210830'
 '910'        | '1%'      | '1/2W'   | '1206LF'  | 'EMPTY'  | 'CS19107F200'(!)        = ''              | ''                 | 'CS19107F200'           |'R1206XF'| '(SMR1206AW)'                  | '910'     | '1%'    | '1/2W'   | 'IO'       | 'RES CHIP 910 1/2W +-1%(1206)'                     | 'CHIPR1206'    | ''          | ''            | '20210830'
 '261'        | '1%'      | '1/10W'  | '0603LF'  | 'CHIP'   | 'CS12613F900'(!)        = ''              | ''                 | 'CS12613F900'           |'R0603'| '(SMR0603AW)'                  | '261'     | '1%'    | '1/10W'  | 'DISCRETE' | 'RES CHIP 261 1/10W +-1%(0603)'                    | 'CHIPR0603'    | ''          | ''            | '20210830'
 '261'        | '1%'      | '1/10W'  | '0603LF'  | 'EMPTY'  | 'CS12613F900'(!)        = ''              | ''                 | 'CS12613F900'           |'R0603'| '(SMR0603AW)'                  | '261'     | '1%'    | '1/10W'  | 'IO'       | 'RES CHIP 261 1/10W +-1%(0603)'                    | 'CHIPR0603'    | ''          | ''            | '20210830'
 '330'        | '1%'      | '1/2W'   | '1206LF'  | 'CHIP'   | 'CS13307F201'(!)        = ''              | ''                 | 'CS13307F201'           |'R1206XT'| '(SMR1206AW)'                  | '330'     | '1%'    | '1/2W'   | 'DISCRETE' | 'RES CHIP 330 1/2W+-1%(1206)SR'                    | 'CHIPR1206'    | ''          | ''            | '20210910'
 '330'        | '1%'      | '1/2W'   | '1206LF'  | 'EMPTY'  | 'CS13307F201'(!)        = ''              | ''                 | 'CS13307F201'           |'R1206XT'| '(SMR1206AW)'                  | '330'     | '1%'    | '1/2W'   | 'IO'       | 'RES CHIP 330 1/2W+-1%(1206)SR'                    | 'CHIPR1206'    | ''          | ''            | '20210910'
 '0'          | ''        | '1/3W'   | '0603LF'  | 'CHIP'   | 'CS0000CT900'(!)        = ''              | ''                 | 'CS0000CT900'           |'R0603'| '(SMR0603AW)'                  | '0'       | ''      | '1/3W'   | 'DISCRETE' | 'RES CHIP 0 1/3W (0603)WTC'                        | 'CHIPR0603'    | ''          | ''            | '20210910'
 '0'          | ''        | '1/3W'   | '0603LF'  | 'EMPTY'  | 'CS0000CT900'(!)        = ''              | ''                 | 'CS0000CT900'           |'R0603'| '(SMR0603AW)'                  | '0'       | ''      | '1/3W'   | 'IO'       | 'RES CHIP 0 1/3W (0603)WTC'                        | 'CHIPR0603'    | ''          | ''            | '20210910'
 '158K'       | '1%'      | '1/16W'  | '0402LF'  | 'CHIP'   | 'CS41582FB02'(!)        = ''              | ''                 | 'CS41582FB02'           |'R0402'| '(R0402-0201)'                 | '158K'    | '1%'    | '1/16W'  | 'DISCRETE' | 'RES CHIP 158K 1/16W +-1% (0402)EF'                | 'CHIPR0402'    | ''          | ''            | '20210916'
 '158K'       | '1%'      | '1/16W'  | '0402LF'  | 'EMPTY'  | 'CS41582FB02'(!)        = ''              | ''                 | 'CS41582FB02'           |'R0402'| '(R0402-0201)'                 | '158K'    | '1%'    | '1/16W'  | 'IO'       | 'RES CHIP 158K 1/16W +-1% (0402)EF'                | 'CHIPR0402'    | ''          | ''            | '20210916'
 '95.3K'      | '1%'      | '1/8W'   | '0805LF'  | 'CHIP'   | 'CS39534FA04'(!)        = ''              | ''                 | 'CS39534FA04'           |'R0805_H26'| '(SMR0805AW)'                  | '95.3K'   | '1%'    | '1/8W'   | 'DISCRETE' | 'RES CHIP 95.3K 1/8W +-1%(0805)EF'                 | 'CHIPR0805'    | ''          | ''            | '20210916'
 '95.3K'      | '1%'      | '1/8W'   | '0805LF'  | 'EMPTY'  | 'CS39534FA04'(!)        = ''              | ''                 | 'CS39534FA04'           |'R0805_H26'| '(SMR0805AW)'                  | '95.3K'   | '1%'    | '1/8W'   | 'IO'       | 'RES CHIP 95.3K 1/8W +-1%(0805)EF'                 | 'CHIPR0805'    | ''          | ''            | '20210916'
 '10'         | '1%'      | '1/10W'  | '0603LF'  | 'CHIP'   | 'CS01003F904'(!)        = 'End of Design' | 'Comp-Approve'     | 'CS01003F904'           |'R0603_H24'| '(SMR0603AW)'                  | '10'      | '1%'    | '1/10W'  | 'DISCRETE' | 'RES CHIP 10 1/10W +-1%(0603)EF'                   | 'CHIPR0603'    | ''          | ''            | '20210916'
 '10'         | '1%'      | '1/10W'  | '0603LF'  | 'EMPTY'  | 'CS01003F904'(!)        = 'End of Design' | 'Comp-Approve'     | 'CS01003F904'           |'R0603_H24'| '(SMR0603AW)'                  | '10'      | '1%'    | '1/10W'  | 'IO'       | 'RES CHIP 10 1/10W +-1%(0603)EF'                   | 'CHIPR0603'    | ''          | ''            | '20210916'
 '2.26K'      | '1%'      | '1/16W'  | '0402LF'  | 'CHIP'   | 'CS22262FB02'(!)        = 'End of Design' | 'Comp-Approve'     | 'CS22262FB02'           |'R0402'| '(R0402-0201)'                 | '2.26K'   | '1%'    | '1/16W'  | 'DISCRETE' | 'RES CHIP 2.26K 1/16W +-1%(0402)EF'                | 'CHIPR0402'    | ''          | ''            | '20210916'
 '2.26K'      | '1%'      | '1/16W'  | '0402LF'  | 'EMPTY'  | 'CS22262FB02'(!)        = 'End of Design' | 'Comp-Approve'     | 'CS22262FB02'           |'R0402'| '(R0402-0201)'                 | '2.26K'   | '1%'    | '1/16W'  | 'IO'       | 'RES CHIP 2.26K 1/16W +-1%(0402)EF'                | 'CHIPR0402'    | ''          | ''            | '20210916'
 '499K'       | '1%'      | '1/16W'  | '0402LF'  | 'CHIP'   | 'CS44992FB04'(!)        = 'End of Design' | 'Comp-Approve'     | 'CS44992FB04'           |'R0402'| '(R0402-0201)'                 | '499K'    | '1%'    | '1/16W'  | 'DISCRETE' | 'RES CHIP 499K 1/16W +-1% (0402)EF'                | 'CHIPR0402'    | ''          | ''            | '20210916'
 '499K'       | '1%'      | '1/16W'  | '0402LF'  | 'EMPTY'  | 'CS44992FB04'(!)        = 'End of Design' | 'Comp-Approve'     | 'CS44992FB04'           |'R0402'| '(R0402-0201)'                 | '499K'    | '1%'    | '1/16W'  | 'IO'       | 'RES CHIP 499K 1/16W +-1% (0402)EF'                | 'CHIPR0402'    | ''          | ''            | '20210916'
 '2.49K'      | '0.1%'    | '1/16W'  | '0402LF'  | 'CHIP'   | 'CS22492BB00'(!)        = ''              | ''                 | 'CS22492BB00'           |'R0402'| '(R0402-0201)'                 | '2.49K'   | '0.1%'  | '1/16W'  | 'DISCRETE' | 'RES CHIP 2.49K 1/16W +-0.1%(0402)'                | 'CHIPR0402'    | ''          | ''            | '20210916'
 '2.49K'      | '0.1%'    | '1/16W'  | '0402LF'  | 'EMPTY'  | 'CS22492BB00'(!)        = ''              | ''                 | 'CS22492BB00'           |'R0402'| '(R0402-0201)'                 | '2.49K'   | '0.1%'  | '1/16W'  | 'IO'       | 'RES CHIP 2.49K 1/16W +-0.1%(0402)'                | 'CHIPR0402'    | ''          | ''            | '20210916'
 '2.43K'      | '1%'      | '1/16W'  | '0402LF'  | 'CHIP'   | 'CS22432FB01'(!)        = 'End of Design' | 'Comp-Approve'     | 'CS22432FB01'           |'R0402'| '(R0402-0201)'                 | '2.43K'   | '1%'    | '1/16W'  | 'DISCRETE' | 'RES CHIP 2.43K 1/16W +-1%(0402)EF'                | 'CHIPR0402'    | ''          | ''            | '20210916'
 '2.43K'      | '1%'      | '1/16W'  | '0402LF'  | 'EMPTY'  | 'CS22432FB01'(!)        = 'End of Design' | 'Comp-Approve'     | 'CS22432FB01'           |'R0402'| '(R0402-0201)'                 | '2.43K'   | '1%'    | '1/16W'  | 'IO'       | 'RES CHIP 2.43K 1/16W +-1%(0402)EF'                | 'CHIPR0402'    | ''          | ''            | '20210916'
 '0.040'      | '1%'      | '1/2W'   | '1206LF'  | 'CHIP'   | 'CS+0407F200'(!)        = ''              | ''                 | 'CS+0407F200'           |'R1206XG'| '(SMR1206AW)'                  | '0.040'   | '1%'    | '1/2W'   | 'DISCRETE' | 'RES CHIP 0.040 1/2W,1%(1206)'                     | 'CHIPR1206'    | ''          | ''            | '20210917'
 '0.040'      | '1%'      | '1/2W'   | '1206LF'  | 'EMPTY'  | 'CS+0407F200'(!)        = ''              | ''                 | 'CS+0407F200'           |'R1206XG'| '(SMR1206AW)'                  | '0.040'   | '1%'    | '1/2W'   | 'IO'       | 'RES CHIP 0.040 1/2W,1%(1206)'                     | 'CHIPR1206'    | ''          | ''            | '20210917'
 '0'          | '5%'      | '1/4W'   | '0603LF'  | 'CHIP'   | 'CS00006J903'(!)        = ''              | ''                 | 'CS00006J903'           |'R0603_H26'| '(SMR0603AW)'                  | '0'       | '5%'    | '1/4W'   | 'DISCRETE' | 'RES CHIP 0 1/4W +-5%(0603)ERO'                    | 'CHIPR0603'    | ''          | ''            | '20210927'
 '0'          | '5%'      | '1/4W'   | '0603LF'  | 'EMPTY'  | 'CS00006J903'(!)        = ''              | ''                 | 'CS00006J903'           |'R0603_H26'| '(SMR0603AW)'                  | '0'       | '5%'    | '1/4W'   | 'IO'       | 'RES CHIP 0 1/4W +-5%(0603)ERO'                    | 'CHIPR0603'    | ''          | ''            | '20210927'
 '0.0005'     | '1%'      | '1.5W'   | '1206LF'  | 'CHIP'   | 'CS0000EF201'(!)        = ''              | ''                 | 'CS0000EF201'           |'R1206XS'| '(SMR1206AW)'                  | '0.0005'  | '1%'    | '1.5W'   | 'DISCRETE' | 'RES CHIP 0.0005 1.5W +-1% (1206)'                 | 'CHIPR1206'    | ''          | ''            | '20210928'
 '0.0005'     | '1%'      | '1.5W'   | '1206LF'  | 'EMPTY'  | 'CS0000EF201'(!)        = ''              | ''                 | 'CS0000EF201'           |'R1206XS'| '(SMR1206AW)'                  | '0.0005'  | '1%'    | '1.5W'   | 'IO'       | 'RES CHIP 0.0005 1.5W +-1% (1206)'                 | 'CHIPR1206'    | ''          | ''            | '20210928'
 '261'        | '1%'      | '1/10W'  | '0603LF'  | 'CHIP'   | 'CS12613F902'(!)        = ''              | ''                 | 'CS12613F902'           |'R0603_H24'| '(SMR0603AW)'                  | '261'     | '1%'    | '1/10W'  | 'DISCRETE' | 'RES CHIP 261 1/10W +-1%(0603)EF'                  | 'CHIPR0603'    | ''          | ''            | '20211026'
 '261'        | '1%'      | '1/10W'  | '0603LF'  | 'EMPTY'  | 'CS12613F902'(!)        = ''              | ''                 | 'CS12613F902'           |'R0603_H24'| '(SMR0603AW)'                  | '261'     | '1%'    | '1/10W'  | 'IO'       | 'RES CHIP 261 1/10W +-1%(0603)EF'                  | 'CHIPR0603'    | ''          | ''            | '20211026'
 '49.9'       | '1%'      | '1/10W'  | '0603LF'  | 'CHIP'   | 'CS04993F909'(!)        = 'End of Design' | 'Comp-Approve'     | 'CS04993F909'           |'R0603'| '(SMR0603AW)'                  | '49.9'    | '1%'    | '1/10W'  | 'DISCRETE' | 'RES CHIP 49.9 1/10W +-1%(0603)EF'                 | 'CHIPR0603'    | ''          | ''            | '20211026'
 '49.9'       | '1%'      | '1/10W'  | '0603LF'  | 'EMPTY'  | 'CS04993F909'(!)        = 'End of Design' | 'Comp-Approve'     | 'CS04993F909'           |'R0603'| '(SMR0603AW)'                  | '49.9'    | '1%'    | '1/10W'  | 'IO'       | 'RES CHIP 49.9 1/10W +-1%(0603)EF'                 | 'CHIPR0603'    | ''          | ''            | '20211026'
 '0'          | '5%'      | '1/4W'   | '0603LF'  | 'CHIP'   | 'CS00006J900'(!)        = ''              | ''                 | 'CS00006J900'           |'R0603'| '(SMR0603AW)'                  | '0'       | '5%'    | '1/4W'   | 'DISCRETE' | 'RES CHIP 0 1/4W +-5%(0603)'                       | 'CHIPR0603'    | ''          | ''            | '20211026'
 '0'          | '5%'      | '1/4W'   | '0603LF'  | 'EMPTY'  | 'CS00006J900'(!)        = ''              | ''                 | 'CS00006J900'           |'R0603'| '(SMR0603AW)'                  | '0'       | '5%'    | '1/4W'   | 'IO'       | 'RES CHIP 0 1/4W +-5%(0603)'                       | 'CHIPR0603'    | ''          | ''            | '20211026'
 '47K'        | '0.1%'    | '1/16W'  | '0402LF'  | 'CHIP'   | 'CS34702BB05'(!)        = ''              | ''                 | 'CS34702BB05'           |'R0402'| '(R0402-0201)'                 | '47K'     | '0.1%'  | '1/16W'  | 'DISCRETE' | 'RES CHIP 47K 1/16W +-0.1%(0402)EF'                | 'CHIPR0402'    | ''          | ''            | '20211028'
 '47K'        | '0.1%'    | '1/16W'  | '0402LF'  | 'EMPTY'  | 'CS34702BB05'(!)        = ''              | ''                 | 'CS34702BB05'           |'R0402'| '(R0402-0201)'                 | '47K'     | '0.1%'  | '1/16W'  | 'IO'       | 'RES CHIP 47K 1/16W +-0.1%(0402)EF'                | 'CHIPR0402'    | ''          | ''            | '20211028'
 '24K'        | '1%'      | '1/16W'  | '0402LF'  | 'CHIP'   | 'CS32402FB03'(!)        = ''              | ''                 | 'CS32402FB03'           |'R0402'| '(R0402-0201)'                 | '24K'     | '1%'    | '1/16W'  | 'DISCRETE' | 'RES CHIP 24K 1/16W +-1%(0402)EF'                  | 'CHIPR0402'    | ''          | ''            | '20211111'
 '24K'        | '1%'      | '1/16W'  | '0402LF'  | 'EMPTY'  | 'CS32402FB03'(!)        = ''              | ''                 | 'CS32402FB03'           |'R0402'| '(R0402-0201)'                 | '24K'     | '1%'    | '1/16W'  | 'IO'       | 'RES CHIP 24K 1/16W +-1%(0402)EF'                  | 'CHIPR0402'    | ''          | ''            | '20211111'
 '18.7K'      | '1%'      | '1/16W'  | '0402LF'  | 'CHIP'   | 'CS31872FB05'(!)        = ''              | ''                 | 'CS31872FB05'           |'R0402'| '(R0402-0201)'                 | '18.7K'   | '1%'    | '1/16W'  | 'DISCRETE' | 'RES CHIP 18.7K 1/16W +-1%(0402)EF'                | 'CHIPR0402'    | ''          | ''            | '20211111'
 '18.7K'      | '1%'      | '1/16W'  | '0402LF'  | 'EMPTY'  | 'CS31872FB05'(!)        = ''              | ''                 | 'CS31872FB05'           |'R0402'| '(R0402-0201)'                 | '18.7K'   | '1%'    | '1/16W'  | 'IO'       | 'RES CHIP 18.7K 1/16W +-1%(0402)EF'                | 'CHIPR0402'    | ''          | ''            | '20211111'
 '820K'       | '1%'      | '1/16W'  | '0402LF'  | 'CHIP'   | 'CS48202FB00'(!)        = 'End of Design' | 'Comp-Approve'     | 'CS48202FB00'           |'R0402'| '(R0402-0201)'                 | '820K'    | '1%'    | '1/16W'  | 'DISCRETE' | 'RES CHIP 820K 1/16W +-1%(0402)'                   | 'CHIPR0402'    | ''          | ''            | '20211124'
 '820K'       | '1%'      | '1/16W'  | '0402LF'  | 'EMPTY'  | 'CS48202FB00'(!)        = 'End of Design' | 'Comp-Approve'     | 'CS48202FB00'           |'R0402'| '(R0402-0201)'                 | '820K'    | '1%'    | '1/16W'  | 'IO'       | 'RES CHIP 820K 1/16W +-1%(0402)'                   | 'CHIPR0402'    | ''          | ''            | '20211124'
 '36'         | '1%'      | '1/20W'  | '0201LF'  | 'CHIP'   | 'CS03601FE00'(!)        = ''              | ''                 | 'CS03601FE00'           |'R0201'| '(SMR0201AW)'                  | '36'      | '1%'    | '1/20W'  | 'DISCRETE' | 'RES CHIP 36 1/20W,+-1%(0201)'                     | 'CHIPR0201'    | ''          | ''            | '20211130'
 '36'         | '1%'      | '1/20W'  | '0201LF'  | 'EMPTY'  | 'CS03601FE00'(!)        = ''              | ''                 | 'CS03601FE00'           |'R0201'| '(SMR0201AW)'                  | '36'      | '1%'    | '1/20W'  | 'IO'       | 'RES CHIP 36 1/20W,+-1%(0201)'                     | 'CHIPR0201'    | ''          | ''            | '20211130'
 '75K'        | '0.1%'    | '1/16W'  | '0402LF'  | 'CHIP'   | 'CS37502BB01'(!)        = ''              | ''                 | 'CS37502BB01'           |'R0402'| '(R0402-0201)'                 | '75K'     | '0.1%'  | '1/16W'  | 'DISCRETE' | 'RES CHIP 75K 1/16W +-0.1%(0402)EF'                | 'CHIPR0402'    | ''          | ''            | '20211207'
 '75K'        | '0.1%'    | '1/16W'  | '0402LF'  | 'EMPTY'  | 'CS37502BB01'(!)        = ''              | ''                 | 'CS37502BB01'           |'R0402'| '(R0402-0201)'                 | '75K'     | '0.1%'  | '1/16W'  | 'IO'       | 'RES CHIP 75K 1/16W +-0.1%(0402)EF'                | 'CHIPR0402'    | ''          | ''            | '20211207'
 '2K'         | '0.1%'    | '1/16W'  | '0402LF'  | 'CHIP'   | 'CS22002BB07'(!)        = ''              | ''                 | 'CS22002BB07'           |'R0402'| '(R0402-0201)'                 | '2K'      | '0.1%'  | '1/16W'  | 'DISCRETE' | 'RES CHIP 2K 1/16W +-0.1%(0402)EF'                 | 'CHIPR0402'    | ''          | ''            | '20211207'
 '2K'         | '0.1%'    | '1/16W'  | '0402LF'  | 'EMPTY'  | 'CS22002BB07'(!)        = ''              | ''                 | 'CS22002BB07'           |'R0402'| '(R0402-0201)'                 | '2K'      | '0.1%'  | '1/16W'  | 'IO'       | 'RES CHIP 2K 1/16W +-0.1%(0402)EF'                 | 'CHIPR0402'    | ''          | ''            | '20211207'
 '2.2'        | '1%'      | '1/8W'   | '0805LF'  | 'CHIP'   | 'CS-2204FA02'(!)        = 'End of Design' | 'Comp-Approve'     | 'CS-2204FA02'           |'R0805'| '(SMR0805AW)'                  | '2.2'     | '1%'    | '1/8W'   | 'DISCRETE' | 'RES CHIP 2.2 1/8W +-1%(0805)EF'                   | 'CHIPR0805'    | ''          | ''            | '20211210'
 '2.2'        | '1%'      | '1/8W'   | '0805LF'  | 'EMPTY'  | 'CS-2204FA02'(!)        = 'End of Design' | 'Comp-Approve'     | 'CS-2204FA02'           |'R0805'| '(SMR0805AW)'                  | '2.2'     | '1%'    | '1/8W'   | 'IO'       | 'RES CHIP 2.2 1/8W +-1%(0805)EF'                   | 'CHIPR0805'    | ''          | ''            | '20211210'
 '1.65K'      | '1%'      | '1/16W'  | '0402LF'  | 'CHIP'   | 'CS21652FB05'(!)        = 'End of Design' | 'Comp-Approve'     | 'CS21652FB05'           |'R0402'| '(R0402-0201)'                 | '1.65K'   | '1%'    | '1/16W'  | 'DISCRETE' | 'RES CHIP 1.65K 1/16W +-1%(0402)EF'                | 'CHIPR0402'    | ''          | ''            | '20211214'
 '1.65K'      | '1%'      | '1/16W'  | '0402LF'  | 'EMPTY'  | 'CS21652FB05'(!)        = 'End of Design' | 'Comp-Approve'     | 'CS21652FB05'           |'R0402'| '(R0402-0201)'                 | '1.65K'   | '1%'    | '1/16W'  | 'IO'       | 'RES CHIP 1.65K 1/16W +-1%(0402)EF'                | 'CHIPR0402'    | ''          | ''            | '20211214'
 '3.83K'      | '1%'      | '1/16W'  | '0402LF'  | 'CHIP'   | 'CS23832FB04'(!)        = 'End of Design' | 'Comp-Approve'     | 'CS23832FB04'           |'R0402'| '(R0402-0201)'                 | '3.83K'   | '1%'    | '1/16W'  | 'DISCRETE' | 'RES CHIP 3.83K 1/16W +-1%(0402)EF'                | 'CHIPR0402'    | ''          | ''            | '20211214'
 '3.83K'      | '1%'      | '1/16W'  | '0402LF'  | 'EMPTY'  | 'CS23832FB04'(!)        = 'End of Design' | 'Comp-Approve'     | 'CS23832FB04'           |'R0402'| '(R0402-0201)'                 | '3.83K'   | '1%'    | '1/16W'  | 'IO'       | 'RES CHIP 3.83K 1/16W +-1%(0402)EF'                | 'CHIPR0402'    | ''          | ''            | '20211214'
 '4.99K'      | '0.1%'    | '1/16W'  | '0402LF'  | 'CHIP'   | 'CS24992BB04'(!)        = ''              | ''                 | 'CS24992BB04'           |'R0402'| '(R0402-0201)'                 | '4.99K'   | '0.1%'  | '1/16W'  | 'DISCRETE' | 'RES CHIP 4.99K 1/16W +-0.1%(0402)EF'              | 'CHIPR0402'    | ''          | ''            | '20211216'
 '4.99K'      | '0.1%'    | '1/16W'  | '0402LF'  | 'EMPTY'  | 'CS24992BB04'(!)        = ''              | ''                 | 'CS24992BB04'           |'R0402'| '(R0402-0201)'                 | '4.99K'   | '0.1%'  | '1/16W'  | 'IO'       | 'RES CHIP 4.99K 1/16W +-0.1%(0402)EF'              | 'CHIPR0402'    | ''          | ''            | '20211216'
 '9.53K'      | '1%'      | '1/16W'  | '0402LF'  | 'CHIP'   | 'CS29532FB06'(!)        = ''              | ''                 | 'CS29532FB06'           |'R0402'| '(R0402-0201)'                 | '9.53K'   | '1%'    | '1/16W'  | 'DISCRETE' | 'RES CHIP 9.53K 1/16W +-1%(0402)EF'                | 'CHIPR0402'    | ''          | ''            | '20211216'
 '9.53K'      | '1%'      | '1/16W'  | '0402LF'  | 'EMPTY'  | 'CS29532FB06'(!)        = ''              | ''                 | 'CS29532FB06'           |'R0402'| '(R0402-0201)'                 | '9.53K'   | '1%'    | '1/16W'  | 'IO'       | 'RES CHIP 9.53K 1/16W +-1%(0402)EF'                | 'CHIPR0402'    | ''          | ''            | '20211216'
 '37.4K'      | '1%'      | '1/16W'  | '0402LF'  | 'CHIP'   | 'CS33742FB05'(!)        = 'End of Design' | 'Comp-Approve'     | 'CS33742FB05'           |'R0402'| '(R0402-0201)'                 | '37.4K'   | '1%'    | '1/16W'  | 'DISCRETE' | 'RES CHIP 37.4K 1/16W +-1%(0402)EF'                | 'CHIPR0402'    | ''          | ''            | '20211216'
 '37.4K'      | '1%'      | '1/16W'  | '0402LF'  | 'EMPTY'  | 'CS33742FB05'(!)        = 'End of Design' | 'Comp-Approve'     | 'CS33742FB05'           |'R0402'| '(R0402-0201)'                 | '37.4K'   | '1%'    | '1/16W'  | 'IO'       | 'RES CHIP 37.4K 1/16W +-1%(0402)EF'                | 'CHIPR0402'    | ''          | ''            | '20211216'
 '3.01K'      | '1%'      | '1/16W'  | '0402LF'  | 'CHIP'   | 'CS23012FB04'(!)        = 'End of Design' | 'Comp-Approve'     | 'CS23012FB04'           |'R0402'| '(R0402-0201)'                 | '3.01K'   | '1%'    | '1/16W'  | 'DISCRETE' | 'RES CHIP 3.01K 1/16W +-1%(0402)EF'                | 'CHIPR0402'    | ''          | ''            | '20211222'
 '3.01K'      | '1%'      | '1/16W'  | '0402LF'  | 'EMPTY'  | 'CS23012FB04'(!)        = 'End of Design' | 'Comp-Approve'     | 'CS23012FB04'           |'R0402'| '(R0402-0201)'                 | '3.01K'   | '1%'    | '1/16W'  | 'IO'       | 'RES CHIP 3.01K 1/16W +-1%(0402)EF'                | 'CHIPR0402'    | ''          | ''            | '20211222'
 '3K'         | '1%'      | '1/16W'  | '0402LF'  | 'CHIP'   | 'CS23002FB02'(!)        = 'End of Design' | 'Comp-Approve'     | 'CS23002FB02'           |'R0402'| '(R0402-0201)'                 | '3K'      | '1%'    | '1/16W'  | 'DISCRETE' | 'RES CHIP 3K 1/16W +-1%(0402)EF'                   | 'CHIPR0402'    | ''          | ''            | '20211222'
 '3K'         | '1%'      | '1/16W'  | '0402LF'  | 'EMPTY'  | 'CS23002FB02'(!)        = 'End of Design' | 'Comp-Approve'     | 'CS23002FB02'           |'R0402'| '(R0402-0201)'                 | '3K'      | '1%'    | '1/16W'  | 'IO'       | 'RES CHIP 3K 1/16W +-1%(0402)EF'                   | 'CHIPR0402'    | ''          | ''            | '20211222'
 '8.2K'       | '1%'      | '1/16W'  | '0402LF'  | 'CHIP'   | 'CS28202FB01'(!)        = 'End of Design' | 'Comp-Approve'     | 'CS28202FB01'           |'R0402'| '(R0402-0201)'                 | '8.2K'    | '1%'    | '1/16W'  | 'DISCRETE' | 'RES CHIP 8.2K 1/16W +-1%(0402)EF'                 | 'CHIPR0402'    | ''          | ''            | '20211222'
 '8.2K'       | '1%'      | '1/16W'  | '0402LF'  | 'EMPTY'  | 'CS28202FB01'(!)        = 'End of Design' | 'Comp-Approve'     | 'CS28202FB01'           |'R0402'| '(R0402-0201)'                 | '8.2K'    | '1%'    | '1/16W'  | 'IO'       | 'RES CHIP 8.2K 1/16W +-1%(0402)EF'                 | 'CHIPR0402'    | ''          | ''            | '20211222'
 '825'        | '1%'      | '1/16W'  | '0402LF'  | 'CHIP'   | 'CS18252FB03'(!)        = 'End of Design' | 'Comp-Approve'     | 'CS18252FB03'           |'R0402'| '(R0402-0201)'                 | '825'     | '1%'    | '1/16W'  | 'DISCRETE' | 'RES CHIP 825 1/16W +-1% (0402) EF'                | 'CHIPR0402'    | ''          | ''            | '20211222'
 '825'        | '1%'      | '1/16W'  | '0402LF'  | 'EMPTY'  | 'CS18252FB03'(!)        = 'End of Design' | 'Comp-Approve'     | 'CS18252FB03'           |'R0402'| '(R0402-0201)'                 | '825'     | '1%'    | '1/16W'  | 'IO'       | 'RES CHIP 825 1/16W +-1% (0402) EF'                | 'CHIPR0402'    | ''          | ''            | '20211222'
 '2.8K'       | '1%'      | '1/16W'  | '0402LF'  | 'CHIP'   | 'CS22802FB04'(!)        = 'End of Design' | 'Comp-Approve'     | 'CS22802FB04'           |'R0402'| '(R0402-0201)'                 | '2.8K'    | '1%'    | '1/16W'  | 'DISCRETE' | 'RES CHIP 2.8K 1/16W +-1%(0402)EF'                 | 'CHIPR0402'    | ''          | ''            | '20211222'
 '2.8K'       | '1%'      | '1/16W'  | '0402LF'  | 'EMPTY'  | 'CS22802FB04'(!)        = 'End of Design' | 'Comp-Approve'     | 'CS22802FB04'           |'R0402'| '(R0402-0201)'                 | '2.8K'    | '1%'    | '1/16W'  | 'IO'       | 'RES CHIP 2.8K 1/16W +-1%(0402)EF'                 | 'CHIPR0402'    | ''          | ''            | '20211222'
 '3.3'        | '1%'      | '1/10W'  | '0603LF'  | 'CHIP'   | 'CS-3303F905'(!)        = ''              | ''                 | 'CS-3303F905'           |'R0603'| '(SMR0603AW)'                  | '3.3'     | '1%'    | '1/10W'  | 'DISCRETE' | 'RES CHIP 3.3 1/10W +-1%(0603)EF'                  | 'CHIPR0603'    | ''          | ''            | '20211224'
 '3.3'        | '1%'      | '1/10W'  | '0603LF'  | 'EMPTY'  | 'CS-3303F905'(!)        = ''              | ''                 | 'CS-3303F905'           |'R0603'| '(SMR0603AW)'                  | '3.3'     | '1%'    | '1/10W'  | 'IO'       | 'RES CHIP 3.3 1/10W +-1%(0603)EF'                  | 'CHIPR0603'    | ''          | ''            | '20211224'
 '499'        | '1%'      | '1/10W'  | '0603LF'  | 'CHIP'   | 'CS14993F901'(!)        = 'End of Design' | 'Comp-Approve'     | 'CS14993F901'           |'R0603'| '(SMR0603AW)'                  | '499'     | '1%'    | '1/10W'  | 'DISCRETE' | 'RES CHIP 499 1/10W +-1%(0603)EF'                  | 'CHIPR0603'    | ''          | ''            | '20211227'
 '499'        | '1%'      | '1/10W'  | '0603LF'  | 'EMPTY'  | 'CS14993F901'(!)        = 'End of Design' | 'Comp-Approve'     | 'CS14993F901'           |'R0603'| '(SMR0603AW)'                  | '499'     | '1%'    | '1/10W'  | 'IO'       | 'RES CHIP 499 1/10W +-1%(0603)EF'                  | 'CHIPR0603'    | ''          | ''            | '20211227'
 '48.7K'      | '1%'      | '1/16W'  | '0402LF'  | 'CHIP'   | 'CS34872FB03'(!)        = 'End of Design' | 'Comp-Approve'     | 'CS34872FB03'           |'R0402'| '(R0402-0201)'                 | '48.7K'   | '1%'    | '1/16W'  | 'DISCRETE' | 'RES CHIP 48.7K 1/16W +-1%(0402)EF'                | 'CHIPR0402'    | ''          | ''            | '20211227'
 '48.7K'      | '1%'      | '1/16W'  | '0402LF'  | 'EMPTY'  | 'CS34872FB03'(!)        = 'End of Design' | 'Comp-Approve'     | 'CS34872FB03'           |'R0402'| '(R0402-0201)'                 | '48.7K'   | '1%'    | '1/16W'  | 'IO'       | 'RES CHIP 48.7K 1/16W +-1%(0402)EF'                | 'CHIPR0402'    | ''          | ''            | '20211227'
 '1.3K'       | '1%'      | '1/16W'  | '0402LF'  | 'CHIP'   | 'CS21302FB07'(!)        = ''              | ''                 | 'CS21302FB07'           |'R0402'| '(R0402-0201)'                 | '1.3K'    | '1%'    | '1/16W'  | 'DISCRETE' | 'RES CHIP 1.3K 1/16W +-1%(0402)EF'                 | 'CHIPR0402'    | ''          | ''            | '20220106'
 '1.3K'       | '1%'      | '1/16W'  | '0402LF'  | 'EMPTY'  | 'CS21302FB07'(!)        = ''              | ''                 | 'CS21302FB07'           |'R0402'| '(R0402-0201)'                 | '1.3K'    | '1%'    | '1/16W'  | 'IO'       | 'RES CHIP 1.3K 1/16W +-1%(0402)EF'                 | 'CHIPR0402'    | ''          | ''            | '20220106'
 '499K'       | '1%'      | '1/8W'   | '0805LF'  | 'CHIP'   | 'CS44994FA04'(!)        = ''              | ''                 | 'CS44994FA04'           |'R0805_H26'| '(SMR0805AW)'                  | '499K'    | '1%'    | '1/8W'   | 'DISCRETE' | 'RES CHIP 499K 1/8W+-1%(0805)EF'                   | 'CHIPR0805'    | ''          | ''            | '20220107'
 '499K'       | '1%'      | '1/8W'   | '0805LF'  | 'EMPTY'  | 'CS44994FA04'(!)        = ''              | ''                 | 'CS44994FA04'           |'R0805_H26'| '(SMR0805AW)'                  | '499K'    | '1%'    | '1/8W'   | 'IO'       | 'RES CHIP 499K 1/8W+-1%(0805)EF'                   | 'CHIPR0805'    | ''          | ''            | '20220107'
 '1'          | '1%'      | '2W'     | '2512LF'  | 'CHIP'   | 'CS-100AFR03'(!)        = ''              | ''                 | 'CS-100AFR03'           |'R2512XU_H30'| '(SMR2512AW)'                  | '1'       | '1%'    | '2W'     | 'DISCRETE' | 'RES CHIP 1 2W +-1%(2512)EF'                       | 'CHIPR2512'    | ''          | ''            | '20220111'
 '1'          | '1%'      | '2W'     | '2512LF'  | 'EMPTY'  | 'CS-100AFR03'(!)        = ''              | ''                 | 'CS-100AFR03'           |'R2512XU_H30'| '(SMR2512AW)'                  | '1'       | '1%'    | '2W'     | 'IO'       | 'RES CHIP 1 2W +-1%(2512)EF'                       | 'CHIPR2512'    | ''          | ''            | '20220111'
 '3.01'       | '1%'      | '1/16W'  | '0402LF'  | 'CHIP'   | 'CS-3012FB00'(!)        = ''              | ''                 | 'CS-3012FB00'           |'R0402'| '(R0402-0201)'                 | '3.01'    | '1%'    | '1/16W'  | 'DISCRETE' | 'RES CHIP 3.01 1/16W +-1% (0402)EF'                | 'CHIPR0402'    | ''          | ''            | '20220111'
 '3.01'       | '1%'      | '1/16W'  | '0402LF'  | 'EMPTY'  | 'CS-3012FB00'(!)        = ''              | ''                 | 'CS-3012FB00'           |'R0402'| '(R0402-0201)'                 | '3.01'    | '1%'    | '1/16W'  | 'IO'       | 'RES CHIP 3.01 1/16W +-1% (0402)EF'                | 'CHIPR0402'    | ''          | ''            | '20220111'
 '4.99'       | '1%'      | '1/16W'  | '0402LF'  | 'CHIP'   | 'CS-4992FB02'(!)        = 'End of Design' | 'Comp-Approve'     | 'CS-4992FB02'           |'R0402'| '(R0402-0201)'                 | '4.99'    | '1%'    | '1/16W'  | 'DISCRETE' | 'RES CHIP 4.99 1/16W +-1%(0402)EF'                 | 'CHIPR0402'    | ''          | ''            | '20220111'
 '4.99'       | '1%'      | '1/16W'  | '0402LF'  | 'EMPTY'  | 'CS-4992FB02'(!)        = 'End of Design' | 'Comp-Approve'     | 'CS-4992FB02'           |'R0402'| '(R0402-0201)'                 | '4.99'    | '1%'    | '1/16W'  | 'IO'       | 'RES CHIP 4.99 1/16W +-1%(0402)EF'                 | 'CHIPR0402'    | ''          | ''            | '20220111'
 '1.07K'      | '1%'      | '1/16W'  | '0402LF'  | 'CHIP'   | 'CS21072FB04'(!)        = ''              | ''                 | 'CS21072FB04'           |'R0402'| '(R0402-0201)'                 | '1.07K'   | '1%'    | '1/16W'  | 'DISCRETE' | 'RES CHIP 1.07K 1/16W +-1%(0402)EF'                | 'CHIPR0402'    | ''          | ''            | '20220118'
 '1.07K'      | '1%'      | '1/16W'  | '0402LF'  | 'EMPTY'  | 'CS21072FB04'(!)        = ''              | ''                 | 'CS21072FB04'           |'R0402'| '(R0402-0201)'                 | '1.07K'   | '1%'    | '1/16W'  | 'IO'       | 'RES CHIP 1.07K 1/16W +-1%(0402)EF'                | 'CHIPR0402'    | ''          | ''            | '20220118'
 '390K'       | '1%'      | '1/16W'  | '0402LF'  | 'CHIP'   | 'CS43902FB01'(!)        = ''              | ''                 | 'CS43902FB01'           |'R0402'| '(R0402-0201)'                 | '390K'    | '1%'    | '1/16W'  | 'DISCRETE' | 'RES CHIP 390K 1/16W +-1%(0402)EF'                 | 'CHIPR0402'    | ''          | ''            | '20220207'
 '390K'       | '1%'      | '1/16W'  | '0402LF'  | 'EMPTY'  | 'CS43902FB01'(!)        = ''              | ''                 | 'CS43902FB01'           |'R0402'| '(R0402-0201)'                 | '390K'    | '1%'    | '1/16W'  | 'IO'       | 'RES CHIP 390K 1/16W +-1%(0402)EF'                 | 'CHIPR0402'    | ''          | ''            | '20220207'
 '1.96K'      | '1%'      | '1/16W'  | '0402LF'  | 'CHIP'   | 'CS21962FB05'(!)        = ''              | ''                 | 'CS21962FB05'           |'R0402'| '(R0402-0201)'                 | '1.96K'   | '1%'    | '1/16W'  | 'DISCRETE' | 'RES CHIP 1.96K 1/16W +-1%(0402)EF'                | 'CHIPR0402'    | ''          | ''            | '20220208'
 '1.96K'      | '1%'      | '1/16W'  | '0402LF'  | 'EMPTY'  | 'CS21962FB05'(!)        = ''              | ''                 | 'CS21962FB05'           |'R0402'| '(R0402-0201)'                 | '1.96K'   | '1%'    | '1/16W'  | 'IO'       | 'RES CHIP 1.96K 1/16W +-1%(0402)EF'                | 'CHIPR0402'    | ''          | ''            | '20220208'
 '3.09K'      | '1%'      | '1/16W'  | '0402LF'  | 'CHIP'   | 'CS23092FB04'(!)        = ''              | ''                 | 'CS23092FB04'           |'R0402'| '(R0402-0201)'                 | '3.09K'   | '1%'    | '1/16W'  | 'DISCRETE' | 'RES CHIP 3.09K 1/16W +-1%(0402)EF'                | 'CHIPR0402'    | ''          | ''            | '20220209'
 '3.09K'      | '1%'      | '1/16W'  | '0402LF'  | 'EMPTY'  | 'CS23092FB04'(!)        = ''              | ''                 | 'CS23092FB04'           |'R0402'| '(R0402-0201)'                 | '3.09K'   | '1%'    | '1/16W'  | 'IO'       | 'RES CHIP 3.09K 1/16W +-1%(0402)EF'                | 'CHIPR0402'    | ''          | ''            | '20220209'
 '8.66K'      | '1%'      | '1/16W'  | '0402LF'  | 'CHIP'   | 'CS28662FB02'(!)        = 'End of Design' | 'Comp-Approve'     | 'CS28662FB02'           |'R0402'| '(R0402-0201)'                 | '8.66K'   | '1%'    | '1/16W'  | 'DISCRETE' | 'RES CHIP 8.66K 1/16W +-1%(0402)EF'                | 'CHIPR0402'    | ''          | ''            | '20220216'
 '8.66K'      | '1%'      | '1/16W'  | '0402LF'  | 'EMPTY'  | 'CS28662FB02'(!)        = 'End of Design' | 'Comp-Approve'     | 'CS28662FB02'           |'R0402'| '(R0402-0201)'                 | '8.66K'   | '1%'    | '1/16W'  | 'IO'       | 'RES CHIP 8.66K 1/16W +-1%(0402)EF'                | 'CHIPR0402'    | ''          | ''            | '20220216'
 '4.7'        | '5%'      | '1W'     | '2512LF'  | 'CHIP'   | 'CS-4708JR01'(!)        = ''              | ''                 | 'CS-4708JR01'           |'R2512XAA'| '(SMR2512AW)'                  | '4.7'     | '5%'    | '1W'     | 'DISCRETE' | 'RES CHIP 4.7 1W +-5%(2512)SR'                     | 'CHIPR2512'    | ''          | ''            | '20220225'
 '4.7'        | '5%'      | '1W'     | '2512LF'  | 'EMPTY'  | 'CS-4708JR01'(!)        = ''              | ''                 | 'CS-4708JR01'           |'R2512XAA'| '(SMR2512AW)'                  | '4.7'     | '5%'    | '1W'     | 'IO'       | 'RES CHIP 4.7 1W +-5%(2512)SR'                     | 'CHIPR2512'    | ''          | ''            | '20220225'
 '51'         | '5%'      | '1/8W'   | '0805LF'  | 'CHIP'   | 'CS05104JA01'(!)        = ''              | ''                 | 'CS05104JA01'           |'R0805_H26'| '(SMR0805AW)'                  | '51'      | '5%'    | '1/8W'   | 'DISCRETE' | 'RES CHIP 51 1/8W +-5%(0805)EF'                    | 'CHIPR0805'    | ''          | ''            | '20220301'
 '51'         | '5%'      | '1/8W'   | '0805LF'  | 'EMPTY'  | 'CS05104JA01'(!)        = ''              | ''                 | 'CS05104JA01'           |'R0805_H26'| '(SMR0805AW)'                  | '51'      | '5%'    | '1/8W'   | 'IO'       | 'RES CHIP 51 1/8W +-5%(0805)EF'                    | 'CHIPR0805'    | ''          | ''            | '20220301'
 '1'          | '5%'      | '1W'     | '2512LF'  | 'CHIP'   | 'CS-1008JR00'(!)        = ''              | ''                 | 'CS-1008JR00'           |'R2512XU_H30'| '(SMR2512AW)'                  | '1'       | '5%'    | '1W'     | 'DISCRETE' | 'RES CHIP 1 1W +-5%(2512)SR'                       | 'CHIPR2512'    | ''          | ''            | '20220301'
 '1'          | '5%'      | '1W'     | '2512LF'  | 'EMPTY'  | 'CS-1008JR00'(!)        = ''              | ''                 | 'CS-1008JR00'           |'R2512XU_H30'| '(SMR2512AW)'                  | '1'       | '5%'    | '1W'     | 'IO'       | 'RES CHIP 1 1W +-5%(2512)SR'                       | 'CHIPR2512'    | ''          | ''            | '20220301'
 '0'          | ''        | '1/16W'  | '0402LF'  | 'CHIP'   | 'CS00002TB03'(!)        = ''              | ''                 | 'CS00002TB03'           |'R0402'| '(R0402-0201)'                 | '0'       | ''      | '1/16W'  | 'DISCRETE' | 'RES CHIP 0 1/16W (0402)EF'                        | 'CHIPR0402'    | ''          | ''            | '20220301'
 '0'          | ''        | '1/16W'  | '0402LF'  | 'EMPTY'  | 'CS00002TB03'(!)        = ''              | ''                 | 'CS00002TB03'           |'R0402'| '(R0402-0201)'                 | '0'       | ''      | '1/16W'  | 'IO'       | 'RES CHIP 0 1/16W (0402)EF'                        | 'CHIPR0402'    | ''          | ''            | '20220301'
 '38.3K'      | '0.1%'    | '1/16W'  | '0402LF'  | 'CHIP'   | 'CS33832BB00'(!)        = ''              | ''                 | 'CS33832BB00'           |'R0402'| '(R0402-0201)'                 | '38.3K'   | '0.1%'  | '1/16W'  | 'DISCRETE' | 'RES CHIP 38.3K 1/16W  +-0.1%(0402)'               | 'CHIPR0402'    | ''          | ''            | '20220316'
 '38.3K'      | '0.1%'    | '1/16W'  | '0402LF'  | 'EMPTY'  | 'CS33832BB00'(!)        = ''              | ''                 | 'CS33832BB00'           |'R0402'| '(R0402-0201)'                 | '38.3K'   | '0.1%'  | '1/16W'  | 'IO'       | 'RES CHIP 38.3K 1/16W  +-0.1%(0402)'               | 'CHIPR0402'    | ''          | ''            | '20220316'
 '110'        | '1%'      | '1/16W'  | '0402LF'  | 'CHIP'   | 'CS11102FB03'(!)        = ''              | ''                 | 'CS11102FB03'           |'R0402'| '(R0402-0201)'                 | '110'     | '1%'    | '1/16W'  | 'DISCRETE' | 'RES CHIP 110 1/16W +-1%(0402)EF'                  | 'CHIPR0402'    | ''          | ''            | '20220316'
 '110'        | '1%'      | '1/16W'  | '0402LF'  | 'EMPTY'  | 'CS11102FB03'(!)        = ''              | ''                 | 'CS11102FB03'           |'R0402'| '(R0402-0201)'                 | '110'     | '1%'    | '1/16W'  | 'IO'       | 'RES CHIP 110 1/16W +-1%(0402)EF'                  | 'CHIPR0402'    | ''          | ''            | '20220316'
 '3.32K'      | '1%'      | '1/16W'  | '0402LF'  | 'CHIP'   | 'CS23322FB05'(!)        = 'End of Design' | 'Comp-Approve'     | 'CS23322FB05'           |'R0402'| '(R0402-0201)'                 | '3.32K'   | '1%'    | '1/16W'  | 'DISCRETE' | 'RES CHIP 3.32K 1/16W +-1%(0402)EF'                | 'CHIPR0402'    | ''          | ''            | '20220316'
 '3.32K'      | '1%'      | '1/16W'  | '0402LF'  | 'EMPTY'  | 'CS23322FB05'(!)        = 'End of Design' | 'Comp-Approve'     | 'CS23322FB05'           |'R0402'| '(R0402-0201)'                 | '3.32K'   | '1%'    | '1/16W'  | 'IO'       | 'RES CHIP 3.32K 1/16W +-1%(0402)EF'                | 'CHIPR0402'    | ''          | ''            | '20220316'
 '0.03'       | '1%'      | '1/2W'   | '0805LF'  | 'CHIP'   | 'CS+0307FA00'(!)        = ''              | ''                 | 'CS+0307FA00'           |'R0805'| '(SMR0805AW)'                  | '0.03'    | '1%'    | '1/2W'   | 'DISCRETE' | 'RES CHIP 0.03 1/2W 1%(0805)'                      | 'CHIPR0805'    | ''          | ''            | '20220316'
 '0.03'       | '1%'      | '1/2W'   | '0805LF'  | 'EMPTY'  | 'CS+0307FA00'(!)        = ''              | ''                 | 'CS+0307FA00'           |'R0805'| '(SMR0805AW)'                  | '0.03'    | '1%'    | '1/2W'   | 'IO'       | 'RES CHIP 0.03 1/2W 1%(0805)'                      | 'CHIPR0805'    | ''          | ''            | '20220316'
 '0'          | ''        | '1/8W'   | '0402LF'  | 'CHIP'   | 'CS00004TB04'(!)        = ''              | ''                 | 'CS00004TB04'           |'R0402_H20'| '(R0402-0201_H20)'             | '0'       | ''      | '1/8W'   | 'DISCRETE' | 'RES CHIP 0 OHM 1/8W JUMPER (0402)'                | 'CHIPR0402'    | ''          | ''            | '20220316'
 '0'          | ''        | '1/8W'   | '0402LF'  | 'EMPTY'  | 'CS00004TB04'(!)        = ''              | ''                 | 'CS00004TB04'           |'R0402_H20'| '(R0402-0201_H20)'             | '0'       | ''      | '1/8W'   | 'IO'       | 'RES CHIP 0 OHM 1/8W JUMPER (0402)'                | 'CHIPR0402'    | ''          | ''            | '20220316'
 '10.7K'      | '0.1%'    | '1/16W'  | '0402LF'  | 'CHIP'   | 'CS31072BB03'(!)        = ''              | ''                 | 'CS31072BB03'           |'R0402'| '(R0402-0201)'                 | '10.7K'   | '0.1%'  | '1/16W'  | 'DISCRETE' | 'RES CHIP 10.7K 1/16W +-0.1%(0402)EF'              | 'CHIPR0402'    | ''          | ''            | '20220316'
 '10.7K'      | '0.1%'    | '1/16W'  | '0402LF'  | 'EMPTY'  | 'CS31072BB03'(!)        = ''              | ''                 | 'CS31072BB03'           |'R0402'| '(R0402-0201)'                 | '10.7K'   | '0.1%'  | '1/16W'  | 'IO'       | 'RES CHIP 10.7K 1/16W +-0.1%(0402)EF'              | 'CHIPR0402'    | ''          | ''            | '20220316'
 '38.3K'      | '0.1%'    | '1/16W'  | '0402LF'  | 'CHIP'   | 'CS33832BB06'(!)        = ''              | ''                 | 'CS33832BB06'           |'R0402'| '(R0402-0201)'                 | '38.3K'   | '0.1%'  | '1/16W'  | 'DISCRETE' | 'RES CHIP 38.3K 1/16W +-0.1%(0402)EF'              | 'CHIPR0402'    | ''          | ''            | '20220316'
 '38.3K'      | '0.1%'    | '1/16W'  | '0402LF'  | 'EMPTY'  | 'CS33832BB06'(!)        = ''              | ''                 | 'CS33832BB06'           |'R0402'| '(R0402-0201)'                 | '38.3K'   | '0.1%'  | '1/16W'  | 'IO'       | 'RES CHIP 38.3K 1/16W +-0.1%(0402)EF'              | 'CHIPR0402'    | ''          | ''            | '20220316'
 '11.3K'      | '0.1%'    | '1/16W'  | '0402LF'  | 'CHIP'   | 'CS31132BB02'(!)        = ''              | ''                 | 'CS31132BB02'           |'R0402'| '(R0402-0201)'                 | '11.3K'   | '0.1%'  | '1/16W'  | 'DISCRETE' | 'RES CHIP 11.3K 1/16W +-0.1%(0402)EF'              | 'CHIPR0402'    | ''          | ''            | '20220316'
 '11.3K'      | '0.1%'    | '1/16W'  | '0402LF'  | 'EMPTY'  | 'CS31132BB02'(!)        = ''              | ''                 | 'CS31132BB02'           |'R0402'| '(R0402-0201)'                 | '11.3K'   | '0.1%'  | '1/16W'  | 'IO'       | 'RES CHIP 11.3K 1/16W +-0.1%(0402)EF'              | 'CHIPR0402'    | ''          | ''            | '20220316'
 '243'        | '1%'      | '1/4W'   | '1206LF'  | 'CHIP'   | 'CS12436F201'(!)        = ''              | ''                 | 'CS12436F201'           |'R1206XN'| '(SMR1206AW)'                  | '243'     | '1%'    | '1/4W'   | 'DISCRETE' | 'RES CHIP 243 1/4W +-1%(1206)EF'                   | 'CHIPR1206'    | ''          | ''            | '20220322'
 '243'        | '1%'      | '1/4W'   | '1206LF'  | 'EMPTY'  | 'CS12436F201'(!)        = ''              | ''                 | 'CS12436F201'           |'R1206XN'| '(SMR1206AW)'                  | '243'     | '1%'    | '1/4W'   | 'IO'       | 'RES CHIP 243 1/4W +-1%(1206)EF'                   | 'CHIPR1206'    | ''          | ''            | '20220322'
 '634'        | '1%'      | '1/16W'  | '0402LF'  | 'CHIP'   | 'CS16342FB01'(!)        = 'End of Design' | 'Comp-Approve'     | 'CS16342FB01'           |'R0402'| '(R0402-0201)'                 | '634'     | '1%'    | '1/16W'  | 'DISCRETE' | 'RES CHIP 634 1/16W +-1%(0402)EF'                  | 'CHIPR0402'    | ''          | ''            | '20220406'
 '634'        | '1%'      | '1/16W'  | '0402LF'  | 'EMPTY'  | 'CS16342FB01'(!)        = 'End of Design' | 'Comp-Approve'     | 'CS16342FB01'           |'R0402'| '(R0402-0201)'                 | '634'     | '1%'    | '1/16W'  | 'IO'       | 'RES CHIP 634 1/16W +-1%(0402)EF'                  | 'CHIPR0402'    | ''          | ''            | '20220406'
 '0'          | '1%'      | '1/10W'  | '0603LF'  | 'CHIP'   | 'CS00003F905'(!)        = ''              | ''                 | 'CS00003F905'           |'R0603'| '(SMR0603AW)'                  | '0'       | '1%'    | '1/10W'  | 'DISCRETE' | 'RES CHIP 0 1/10W +-1% (0603)EF'                   | 'CHIPR0603'    | ''          | ''            | '20220407'
 '0'          | '1%'      | '1/10W'  | '0603LF'  | 'EMPTY'  | 'CS00003F905'(!)        = ''              | ''                 | 'CS00003F905'           |'R0603'| '(SMR0603AW)'                  | '0'       | '1%'    | '1/10W'  | 'IO'       | 'RES CHIP 0 1/10W +-1% (0603)EF'                   | 'CHIPR0603'    | ''          | ''            | '20220407'
 '487'        | '1%'      | '1/16W'  | '0402LF'  | 'CHIP'   | 'CS14872FB01'(!)        = ''              | ''                 | 'CS14872FB01'           |'R0402'| '(R0402-0201)'                 | '487'     | '1%'    | '1/16W'  | 'DISCRETE' | 'RES CHIP 487 1/16W +-1%(0402) EF'                 | 'CHIPR0402'    | ''          | ''            | '20220407'
 '487'        | '1%'      | '1/16W'  | '0402LF'  | 'EMPTY'  | 'CS14872FB01'(!)        = ''              | ''                 | 'CS14872FB01'           |'R0402'| '(R0402-0201)'                 | '487'     | '1%'    | '1/16W'  | 'IO'       | 'RES CHIP 487 1/16W +-1%(0402) EF'                 | 'CHIPR0402'    | ''          | ''            | '20220407'
 '5.62K'      | '1%'      | '1/16W'  | '0402LF'  | 'CHIP'   | 'CS25622FB04'(!)        = ''              | ''                 | 'CS25622FB04'           |'R0402'| '(R0402-0201)'                 | '5.62K'   | '1%'    | '1/16W'  | 'DISCRETE' | 'RES CHIP 5.62K 1/16W +-1%(0402)EF'                | 'CHIPR0402'    | ''          | ''            | '20220408'
 '5.62K'      | '1%'      | '1/16W'  | '0402LF'  | 'EMPTY'  | 'CS25622FB04'(!)        = ''              | ''                 | 'CS25622FB04'           |'R0402'| '(R0402-0201)'                 | '5.62K'   | '1%'    | '1/16W'  | 'IO'       | 'RES CHIP 5.62K 1/16W +-1%(0402)EF'                | 'CHIPR0402'    | ''          | ''            | '20220408'
 '20K'        | '1%'      | '1/4W'   | '1206LF'  | 'CHIP'   | 'CS32006F205'(!)        = ''              | ''                 | 'CS32006F205'           |'R1206XN'| '(SMR1206AW)'                  | '20K'     | '1%'    | '1/4W'   | 'DISCRETE' | 'RES CHIP 20K 1/4W +-1%(1206)EF'                   | 'CHIPR1206'    | ''          | ''            | '20220408'
 '20K'        | '1%'      | '1/4W'   | '1206LF'  | 'EMPTY'  | 'CS32006F205'(!)        = ''              | ''                 | 'CS32006F205'           |'R1206XN'| '(SMR1206AW)'                  | '20K'     | '1%'    | '1/4W'   | 'IO'       | 'RES CHIP 20K 1/4W +-1%(1206)EF'                   | 'CHIPR1206'    | ''          | ''            | '20220408'
 '32.4K'      | '1%'      | '1/16W'  | '0402LF'  | 'CHIP'   | 'CS33242FB03'(!)        = 'End of Design' | 'Comp-Approve'     | 'CS33242FB03'           |'R0402'| '(R0402-0201)'                 | '32.4K'   | '1%'    | '1/16W'  | 'DISCRETE' | 'RES CHIP 32.4K 1/16W +-1%(0402)EF'                | 'CHIPR0402'    | ''          | ''            | '20220413'
 '32.4K'      | '1%'      | '1/16W'  | '0402LF'  | 'EMPTY'  | 'CS33242FB03'(!)        = 'End of Design' | 'Comp-Approve'     | 'CS33242FB03'           |'R0402'| '(R0402-0201)'                 | '32.4K'   | '1%'    | '1/16W'  | 'IO'       | 'RES CHIP 32.4K 1/16W +-1%(0402)EF'                | 'CHIPR0402'    | ''          | ''            | '20220413'
 '6.19K'      | '1%'      | '1/10W'  | '0603LF'  | 'CHIP'   | 'CS26193F901'(!)        = ''              | ''                 | 'CS26193F901'           |'R0603'| '(SMR0603AW)'                  | '6.19K'   | '1%'    | '1/10W'  | 'DISCRETE' | 'RES CHIP 6.19K 1/10W +-1%(0603)EF'                | 'CHIPR0603'    | ''          | ''            | '20220421'
 '6.19K'      | '1%'      | '1/10W'  | '0603LF'  | 'EMPTY'  | 'CS26193F901'(!)        = ''              | ''                 | 'CS26193F901'           |'R0603'| '(SMR0603AW)'                  | '6.19K'   | '1%'    | '1/10W'  | 'IO'       | 'RES CHIP 6.19K 1/10W +-1%(0603)EF'                | 'CHIPR0603'    | ''          | ''            | '20220421'
 '68.1'       | '1%'      | '1/16W'  | '0402LF'  | 'CHIP'   | 'CS06812FB03'(!)        = 'End of Design' | 'Comp-Approve'     | 'CS06812FB03'           |'R0402'| '(R0402-0201)'                 | '68.1'    | '1%'    | '1/16W'  | 'DISCRETE' | 'RES CHIP 68.1 1/16W +-1%(0402)EF'                 | 'CHIPR0402'    | ''          | ''            | '20220421'
 '68.1'       | '1%'      | '1/16W'  | '0402LF'  | 'EMPTY'  | 'CS06812FB03'(!)        = 'End of Design' | 'Comp-Approve'     | 'CS06812FB03'           |'R0402'| '(R0402-0201)'                 | '68.1'    | '1%'    | '1/16W'  | 'IO'       | 'RES CHIP 68.1 1/16W +-1%(0402)EF'                 | 'CHIPR0402'    | ''          | ''            | '20220421'
 '10.5K'      | '1%'      | '1/16W'  | '0402LF'  | 'CHIP'   | 'CS31052FB03'(!)        = ''              | ''                 | 'CS31052FB03'           |'R0402'| '(R0402-0201)'                 | '10.5K'   | '1%'    | '1/16W'  | 'DISCRETE' | 'RES CHIP 10.5K 1/16W +-1%(0402)EF'                | 'CHIPR0402'    | ''          | ''            | '20220426'
 '10.5K'      | '1%'      | '1/16W'  | '0402LF'  | 'EMPTY'  | 'CS31052FB03'(!)        = ''              | ''                 | 'CS31052FB03'           |'R0402'| '(R0402-0201)'                 | '10.5K'   | '1%'    | '1/16W'  | 'IO'       | 'RES CHIP 10.5K 1/16W +-1%(0402)EF'                | 'CHIPR0402'    | ''          | ''            | '20220426'
 '124K'       | '1%'      | '1/16W'  | '0402LF'  | 'CHIP'   | 'CS41242FB04'(!)        = ''              | ''                 | 'CS41242FB04'           |'R0402'| '(R0402-0201)'                 | '124K'    | '1%'    | '1/16W'  | 'DISCRETE' | 'RES CHIP 124K 1/16W +-1%(0402)EF'                 | 'CHIPR0402'    | ''          | ''            | '20220510'
 '124K'       | '1%'      | '1/16W'  | '0402LF'  | 'EMPTY'  | 'CS41242FB04'(!)        = ''              | ''                 | 'CS41242FB04'           |'R0402'| '(R0402-0201)'                 | '124K'    | '1%'    | '1/16W'  | 'IO'       | 'RES CHIP 124K 1/16W +-1%(0402)EF'                 | 'CHIPR0402'    | ''          | ''            | '20220510'
 '0.1'        | '1%'      | '2W'     | '2512LF'  | 'CHIP'   | 'CS+100AFR00'(!)        = ''              | ''                 | 'CS+100AFR00'           |'R2512XAB'| '(SMR2512AW)'                  | '0.1'     | '1%'    | '2W'     | 'DISCRETE' | 'RES CHIP 0.1 2W +-1%(2512)'                       | 'CHIPR2512'    | ''          | ''            | '20220510'
 '0.1'        | '1%'      | '2W'     | '2512LF'  | 'EMPTY'  | 'CS+100AFR00'(!)        = ''              | ''                 | 'CS+100AFR00'           |'R2512XAB'| '(SMR2512AW)'                  | '0.1'     | '1%'    | '2W'     | 'IO'       | 'RES CHIP 0.1 2W +-1%(2512)'                       | 'CHIPR2512'    | ''          | ''            | '20220510'
 '348K'       | '1%'      | '1/4W'   | '1206LF'  | 'CHIP'   | 'CS43486F201'(!)        = ''              | ''                 | 'CS43486F201'           |'R1206XB'| '(SMR1206AW)'                  | '348K'    | '1%'    | '1/4W'   | 'DISCRETE' | 'RES CHIP 348K 1/4W +-1%(1206)'                    | 'CHIPR1206'    | ''          | ''            | '20220510'
 '348K'       | '1%'      | '1/4W'   | '1206LF'  | 'EMPTY'  | 'CS43486F201'(!)        = ''              | ''                 | 'CS43486F201'           |'R1206XB'| '(SMR1206AW)'                  | '348K'    | '1%'    | '1/4W'   | 'IO'       | 'RES CHIP 348K 1/4W +-1%(1206)'                    | 'CHIPR1206'    | ''          | ''            | '20220510'
 '191K'       | '1%'      | '1/4W'   | '1206LF'  | 'CHIP'   | 'CS41916F200'(!)        = ''              | ''                 | 'CS41916F200'           |'R1206XB'| '(SMR1206AW)'                  | '191K'    | '1%'    | '1/4W'   | 'DISCRETE' | 'RES CHIP 191K 1/4W +-1% (1206)'                   | 'CHIPR1206'    | ''          | ''            | '20220510'
 '191K'       | '1%'      | '1/4W'   | '1206LF'  | 'EMPTY'  | 'CS41916F200'(!)        = ''              | ''                 | 'CS41916F200'           |'R1206XB'| '(SMR1206AW)'                  | '191K'    | '1%'    | '1/4W'   | 'IO'       | 'RES CHIP 191K 1/4W +-1% (1206)'                   | 'CHIPR1206'    | ''          | ''            | '20220510'
 '6.34K'      | '1%'      | '1/16W'  | '0402LF'  | 'CHIP'   | 'CS26342FB02'(!)        = 'End of Design' | 'Comp-Approve'     | 'CS26342FB02'           |'R0402'| '(R0402-0201)'                 | '6.34K'   | '1%'    | '1/16W'  | 'DISCRETE' | 'RES CHIP 6.34K 1/16W +-1%(0402)EF'                | 'CHIPR0402'    | ''          | ''            | '20220510'
 '6.34K'      | '1%'      | '1/16W'  | '0402LF'  | 'EMPTY'  | 'CS26342FB02'(!)        = 'End of Design' | 'Comp-Approve'     | 'CS26342FB02'           |'R0402'| '(R0402-0201)'                 | '6.34K'   | '1%'    | '1/16W'  | 'IO'       | 'RES CHIP 6.34K 1/16W +-1%(0402)EF'                | 'CHIPR0402'    | ''          | ''            | '20220510'
 '7.5'        | '1%'      | '1/16W'  | '0402LF'  | 'CHIP'   | 'CS-7502FB02'(!)        = ''              | ''                 | 'CS-7502FB02'           |'R0402'| '(R0402-0201)'                 | '7.5'     | '1%'    | '1/16W'  | 'DISCRETE' | 'RES CHIP 7.5 1/16W +-1%(0402)EF'                  | 'CHIPR0402'    | ''          | ''            | '20220512'
 '7.5'        | '1%'      | '1/16W'  | '0402LF'  | 'EMPTY'  | 'CS-7502FB02'(!)        = ''              | ''                 | 'CS-7502FB02'           |'R0402'| '(R0402-0201)'                 | '7.5'     | '1%'    | '1/16W'  | 'IO'       | 'RES CHIP 7.5 1/16W +-1%(0402)EF'                  | 'CHIPR0402'    | ''          | ''            | '20220512'
 '4.7'        | '5%'      | '1/10W'  | '0603LF'  | 'CHIP'   | 'CS-4703J917'(!)        = ''              | ''                 | 'CS-4703J917'           |'R0603'| '(SMR0603AW)'                  | '4.7'     | '5%'    | '1/10W'  | 'DISCRETE' | 'RES CHIP 4.7 1/10W +-5%(0603)'                    | 'CHIPR0603'    | ''          | ''            | '20220519'
 '4.7'        | '5%'      | '1/10W'  | '0603LF'  | 'EMPTY'  | 'CS-4703J917'(!)        = ''              | ''                 | 'CS-4703J917'           |'R0603'| '(SMR0603AW)'                  | '4.7'     | '5%'    | '1/10W'  | 'IO'       | 'RES CHIP 4.7 1/10W +-5%(0603)'                    | 'CHIPR0603'    | ''          | ''            | '20220519'
 '47K'        | '1%'      | '1/4W'   | '1206LF'  | 'CHIP'   | 'CS34706F200'(!)        = ''              | ''                 | 'CS34706F200'           |'R1206XM'| '(SMR1206AW)'                  | '47K'     | '1%'    | '1/4W'   | 'DISCRETE' | 'RES CHIP 47K 1/4W 1%(1206)'                       | 'CHIPR1206'    | ''          | ''            | '20220520'
 '47K'        | '1%'      | '1/4W'   | '1206LF'  | 'EMPTY'  | 'CS34706F200'(!)        = ''              | ''                 | 'CS34706F200'           |'R1206XM'| '(SMR1206AW)'                  | '47K'     | '1%'    | '1/4W'   | 'IO'       | 'RES CHIP 47K 1/4W 1%(1206)'                       | 'CHIPR1206'    | ''          | ''            | '20220520'
 '0.005'      | '1%'      | '1W'     | '1206LF'  | 'CHIP'   | 'CS+0058F202'(!)        = 'End of Design' | 'Comp-Approve'     | 'CS+0058F202'           |'R1206XG'| '(SMR1206AW)'                  | '0.005'   | '1%'    | '1W'     | 'DISCRETE' | 'RES CHIP 0.005 1W +-1%(1206)EF'                   | 'CHIPR1206'    | ''          | ''            | '20220524'
 '0.005'      | '1%'      | '1W'     | '1206LF'  | 'EMPTY'  | 'CS+0058F202'(!)        = 'End of Design' | 'Comp-Approve'     | 'CS+0058F202'           |'R1206XG'| '(SMR1206AW)'                  | '0.005'   | '1%'    | '1W'     | 'IO'       | 'RES CHIP 0.005 1W +-1%(1206)EF'                   | 'CHIPR1206'    | ''          | ''            | '20220524'
 '237K'       | '1%'      | '1/16W'  | '0402LF'  | 'CHIP'   | 'CS42372FB04'(!)        = ''              | ''                 | 'CS42372FB04'           |'R0402'| '(R0402-0201)'                 | '237K'    | '1%'    | '1/16W'  | 'DISCRETE' | 'RES CHIP 237K 1/16W +-1% (0402)EF'                | 'CHIPR0402'    | ''          | ''            | '20220606'
 '237K'       | '1%'      | '1/16W'  | '0402LF'  | 'EMPTY'  | 'CS42372FB04'(!)        = ''              | ''                 | 'CS42372FB04'           |'R0402'| '(R0402-0201)'                 | '237K'    | '1%'    | '1/16W'  | 'IO'       | 'RES CHIP 237K 1/16W +-1% (0402)EF'                | 'CHIPR0402'    | ''          | ''            | '20220606'
 '56.2K'      | '0.1%'    | '1/16W'  | '0402LF'  | 'CHIP'   | 'CS35622BB04'(!)        = ''              | ''                 | 'CS35622BB04'           |'R0402'| '(R0402-0201)'                 | '56.2K'   | '0.1%'  | '1/16W'  | 'DISCRETE' | 'RES CHIP 56.2K 1/16W +-0.1%(0402)YGO'             | 'CHIPR0402'    | ''          | ''            | '20220608'
 '56.2K'      | '0.1%'    | '1/16W'  | '0402LF'  | 'EMPTY'  | 'CS35622BB04'(!)        = ''              | ''                 | 'CS35622BB04'           |'R0402'| '(R0402-0201)'                 | '56.2K'   | '0.1%'  | '1/16W'  | 'IO'       | 'RES CHIP 56.2K 1/16W +-0.1%(0402)YGO'             | 'CHIPR0402'    | ''          | ''            | '20220608'
 '12.4K'      | '1%'      | '1/16W'  | '0402LF'  | 'CHIP'   | 'CS31242FB09'(!)        = ''              | ''                 | 'CS31242FB09'           |'R0402'| '(R0402-0201)'                 | '12.4K'   | '1%'    | '1/16W'  | 'DISCRETE' | 'RES CHIP 12.4K 1/16W +-1% (0402)YGO'              | 'CHIPR0402'    | ''          | ''            | '20220608'
 '12.4K'      | '1%'      | '1/16W'  | '0402LF'  | 'EMPTY'  | 'CS31242FB09'(!)        = ''              | ''                 | 'CS31242FB09'           |'R0402'| '(R0402-0201)'                 | '12.4K'   | '1%'    | '1/16W'  | 'IO'       | 'RES CHIP 12.4K 1/16W +-1% (0402)YGO'              | 'CHIPR0402'    | ''          | ''            | '20220608'
 '20K'        | '0.1%'    | '1/16W'  | '0402LF'  | 'CHIP'   | 'CS32002BB10'(!)        = ''              | ''                 | 'CS32002BB10'           |'R0402'| '(R0402-0201)'                 | '20K'     | '0.1%'  | '1/16W'  | 'DISCRETE' | 'RES CHIP 20K 1/16W +-0.1%(0402)YGO'               | 'CHIPR0402'    | ''          | ''            | '20220608'
 '20K'        | '0.1%'    | '1/16W'  | '0402LF'  | 'EMPTY'  | 'CS32002BB10'(!)        = ''              | ''                 | 'CS32002BB10'           |'R0402'| '(R0402-0201)'                 | '20K'     | '0.1%'  | '1/16W'  | 'IO'       | 'RES CHIP 20K 1/16W +-0.1%(0402)YGO'               | 'CHIPR0402'    | ''          | ''            | '20220608'
 '10K'        | '1%'      | '1/16W'  | '0402LF'  | 'CHIP'   | 'CS31002FB10'(!)        = ''              | ''                 | 'CS31002FB10'           |'R0402'| '(R0402-0201)'                 | '10K'     | '1%'    | '1/16W'  | 'DISCRETE' | 'RES CHIP 10K(1%,1/16W,0402)YGO'                   | 'CHIPR0402'    | ''          | ''            | '20220608'
 '10K'        | '1%'      | '1/16W'  | '0402LF'  | 'EMPTY'  | 'CS31002FB10'(!)        = ''              | ''                 | 'CS31002FB10'           |'R0402'| '(R0402-0201)'                 | '10K'     | '1%'    | '1/16W'  | 'IO'       | 'RES CHIP 10K(1%,1/16W,0402)YGO'                   | 'CHIPR0402'    | ''          | ''            | '20220608'
 '5.36K'      | '1%'      | '1/16W'  | '0402LF'  | 'CHIP'   | 'CS25362FB06'(!)        = ''              | ''                 | 'CS25362FB06'           |'R0402'| '(R0402-0201)'                 | '5.36K'   | '1%'    | '1/16W'  | 'DISCRETE' | 'RES CHIP 5.36K 1/16W +-1% (0402)YGO'              | 'CHIPR0402'    | ''          | ''            | '20220608'
 '5.36K'      | '1%'      | '1/16W'  | '0402LF'  | 'EMPTY'  | 'CS25362FB06'(!)        = ''              | ''                 | 'CS25362FB06'           |'R0402'| '(R0402-0201)'                 | '5.36K'   | '1%'    | '1/16W'  | 'IO'       | 'RES CHIP 5.36K 1/16W +-1% (0402)YGO'              | 'CHIPR0402'    | ''          | ''            | '20220608'
 '10.7K'      | '0.1%'    | '1/16W'  | '0402LF'  | 'CHIP'   | 'CS31072BB00'(!)        = ''              | ''                 | 'CS31072BB00'           |'R0402'| '(R0402-0201)'                 | '10.7K'   | '0.1%'  | '1/16W'  | 'DISCRETE' | 'RES CHIP 10.7K 1/16W +-0.1%(0402)'                | 'CHIPR0402'    | ''          | ''            | '20220610'
 '10.7K'      | '0.1%'    | '1/16W'  | '0402LF'  | 'EMPTY'  | 'CS31072BB00'(!)        = ''              | ''                 | 'CS31072BB00'           |'R0402'| '(R0402-0201)'                 | '10.7K'   | '0.1%'  | '1/16W'  | 'IO'       | 'RES CHIP 10.7K 1/16W +-0.1%(0402)'                | 'CHIPR0402'    | ''          | ''            | '20220610'
 '1.91K'      | '1%'      | '1/16W'  | '0402LF'  | 'CHIP'   | 'CS21912FB13'(!)        = 'End of Design' | 'Comp-Approve'     | 'CS21912FB13'           |'R0402'| '(R0402-0201)'                 | '1.91K'   | '1%'    | '1/16W'  | 'DISCRETE' | 'RES CHIP 1.91K 1/16W +-1%(0402)'                  | 'CHIPR0402'    | ''          | ''            | '20220610'
 '1.91K'      | '1%'      | '1/16W'  | '0402LF'  | 'EMPTY'  | 'CS21912FB13'(!)        = 'End of Design' | 'Comp-Approve'     | 'CS21912FB13'           |'R0402'| '(R0402-0201)'                 | '1.91K'   | '1%'    | '1/16W'  | 'IO'       | 'RES CHIP 1.91K 1/16W +-1%(0402)'                  | 'CHIPR0402'    | ''          | ''            | '20220610'
 '20M'        | '1%'      | '1/16W'  | '0402LF'  | 'CHIP'   | 'CS62002FB01'(!)        = ''              | ''                 | 'CS62002FB01'           |'R0402'| '(R0402-0201)'                 | '20M'     | '1%'    | '1/16W'  | 'DISCRETE' | 'RES CHIP 20M 1/16W +-1%(0402)EF'                  | 'CHIPR0402'    | ''          | ''            | '20220613'
 '20M'        | '1%'      | '1/16W'  | '0402LF'  | 'EMPTY'  | 'CS62002FB01'(!)        = ''              | ''                 | 'CS62002FB01'           |'R0402'| '(R0402-0201)'                 | '20M'     | '1%'    | '1/16W'  | 'IO'       | 'RES CHIP 20M 1/16W +-1%(0402)EF'                  | 'CHIPR0402'    | ''          | ''            | '20220613'
 '30K'        | '1%'      | '1/16W'  | '0402LF'  | 'CHIP'   | 'CS33002FB02'(!)        = 'End of Design' | 'Comp-Approve'     | 'CS33002FB02'           |'R0402'| '(R0402-0201)'                 | '30K'     | '1%'    | '1/16W'  | 'DISCRETE' | 'RES CHIP 30K 1/16W +-1%(0402)EF'                  | 'CHIPR0402'    | ''          | ''            | '20220616'
 '30K'        | '1%'      | '1/16W'  | '0402LF'  | 'EMPTY'  | 'CS33002FB02'(!)        = 'End of Design' | 'Comp-Approve'     | 'CS33002FB02'           |'R0402'| '(R0402-0201)'                 | '30K'     | '1%'    | '1/16W'  | 'IO'       | 'RES CHIP 30K 1/16W +-1%(0402)EF'                  | 'CHIPR0402'    | ''          | ''            | '20220616'
 '13.7K'      | '1%'      | '1/16W'  | '0402LF'  | 'CHIP'   | 'CS31372FB03'(!)        = 'End of Design' | 'Comp-Approve'     | 'CS31372FB03'           |'R0402'| '(R0402-0201)'                 | '13.7K'   | '1%'    | '1/16W'  | 'DISCRETE' | 'RES CHIP 13.7K 1/16W +-1%(0402)EF'                | 'CHIPR0402'    | ''          | ''            | '20220622'
 '13.7K'      | '1%'      | '1/16W'  | '0402LF'  | 'EMPTY'  | 'CS31372FB03'(!)        = 'End of Design' | 'Comp-Approve'     | 'CS31372FB03'           |'R0402'| '(R0402-0201)'                 | '13.7K'   | '1%'    | '1/16W'  | 'IO'       | 'RES CHIP 13.7K 1/16W +-1%(0402)EF'                | 'CHIPR0402'    | ''          | ''            | '20220622'
 '16.9K'      | '1%'      | '1/16W'  | '0402LF'  | 'CHIP'   | 'CS31692FB13'(!)        = ''              | ''                 | 'CS31692FB13'           |'R0402'| '(R0402-0201)'                 | '16.9K'   | '1%'    | '1/16W'  | 'DISCRETE' | 'RES CHIP 16.9K 1/16W +-1% (0402)WTC'              | 'CHIPR0402'    | ''          | ''            | '20220624'
 '16.9K'      | '1%'      | '1/16W'  | '0402LF'  | 'EMPTY'  | 'CS31692FB13'(!)        = ''              | ''                 | 'CS31692FB13'           |'R0402'| '(R0402-0201)'                 | '16.9K'   | '1%'    | '1/16W'  | 'IO'       | 'RES CHIP 16.9K 1/16W +-1% (0402)WTC'              | 'CHIPR0402'    | ''          | ''            | '20220624'
 '16.9K'      | '1%'      | '1/16W'  | '0402LF'  | 'CHIP'   | 'CS31692FB14'(!)        = ''              | ''                 | 'CS31692FB14'           |'R0402'| '(R0402-0201)'                 | '16.9K'   | '1%'    | '1/16W'  | 'DISCRETE' | 'RES CHIP 16.9K 1/16W +-1% (0402)YGO'              | 'CHIPR0402'    | ''          | ''            | '20220624'
 '16.9K'      | '1%'      | '1/16W'  | '0402LF'  | 'EMPTY'  | 'CS31692FB14'(!)        = ''              | ''                 | 'CS31692FB14'           |'R0402'| '(R0402-0201)'                 | '16.9K'   | '1%'    | '1/16W'  | 'IO'       | 'RES CHIP 16.9K 1/16W +-1% (0402)YGO'              | 'CHIPR0402'    | ''          | ''            | '20220624'
 '120K'       | '1%'      | '1/16W'  | '0402LF'  | 'CHIP'   | 'CS41202FB15'(!)        = ''              | ''                 | 'CS41202FB15'           |'R0402'| '(R0402-0201)'                 | '120K'    | '1%'    | '1/16W'  | 'DISCRETE' | 'RES CHIP 120K 1/16W +-1%( 0402)CYN'               | 'CHIPR0402'    | ''          | ''            | '20220624'
 '120K'       | '1%'      | '1/16W'  | '0402LF'  | 'EMPTY'  | 'CS41202FB15'(!)        = ''              | ''                 | 'CS41202FB15'           |'R0402'| '(R0402-0201)'                 | '120K'    | '1%'    | '1/16W'  | 'IO'       | 'RES CHIP 120K 1/16W +-1%( 0402)CYN'               | 'CHIPR0402'    | ''          | ''            | '20220624'
 '120K'       | '1%'      | '1/16W'  | '0402LF'  | 'CHIP'   | 'CS41202FB16'(!)        = ''              | ''                 | 'CS41202FB16'           |'R0402'| '(R0402-0201)'                 | '120K'    | '1%'    | '1/16W'  | 'DISCRETE' | 'RES CHIP 120K 1/16W +-1%( 0402)YGO'               | 'CHIPR0402'    | ''          | ''            | '20220624'
 '120K'       | '1%'      | '1/16W'  | '0402LF'  | 'EMPTY'  | 'CS41202FB16'(!)        = ''              | ''                 | 'CS41202FB16'           |'R0402'| '(R0402-0201)'                 | '120K'    | '1%'    | '1/16W'  | 'IO'       | 'RES CHIP 120K 1/16W +-1%( 0402)YGO'               | 'CHIPR0402'    | ''          | ''            | '20220624'
 '0'          | '1%'      | '1/2W'   | '1206LF'  | 'CHIP'   | 'CS00007F201'(!)        = ''              | ''                 | 'CS00007F201'           |'R1206XI'| '(SMR1206AW)'                  | '0'       | '1%'    | '1/2W'   | 'DISCRETE' | 'RES CHIP 0 1/2W +-1%(1206)WTC'                    | 'CHIPR1206'    | ''          | ''            | '20220624'
 '0'          | '1%'      | '1/2W'   | '1206LF'  | 'EMPTY'  | 'CS00007F201'(!)        = ''              | ''                 | 'CS00007F201'           |'R1206XI'| '(SMR1206AW)'                  | '0'       | '1%'    | '1/2W'   | 'IO'       | 'RES CHIP 0 1/2W +-1%(1206)WTC'                    | 'CHIPR1206'    | ''          | ''            | '20220624'
 '0'          | '1%'      | '1/2W'   | '1206LF'  | 'CHIP'   | 'CS00007F202'(!)        = ''              | ''                 | 'CS00007F202'           |'R1206XF'| '(SMR1206AW)'                  | '0'       | '1%'    | '1/2W'   | 'DISCRETE' | 'RES CHIP 0 1/2W +-1%(1206)YGO'                    | 'CHIPR1206'    | ''          | ''            | '20220624'
 '0'          | '1%'      | '1/2W'   | '1206LF'  | 'EMPTY'  | 'CS00007F202'(!)        = ''              | ''                 | 'CS00007F202'           |'R1206XF'| '(SMR1206AW)'                  | '0'       | '1%'    | '1/2W'   | 'IO'       | 'RES CHIP 0 1/2W +-1%(1206)YGO'                    | 'CHIPR1206'    | ''          | ''            | '20220624'
 '127'        | '1%'      | '1/16W'  | '0402LF'  | 'CHIP'   | 'CS11272FB21'(!)        = 'End of Design' | 'Comp-Approve'     | 'CS11272FB21'           |'R0402'| '(R0402-0201)'                 | '127'     | '1%'    | '1/16W'  | 'DISCRETE' | 'RES CHIP 127 1/16W +-1%(0402)'                    | 'CHIPR0402'    | ''          | ''            | '20220704'
 '127'        | '1%'      | '1/16W'  | '0402LF'  | 'EMPTY'  | 'CS11272FB21'(!)        = 'End of Design' | 'Comp-Approve'     | 'CS11272FB21'           |'R0402'| '(R0402-0201)'                 | '127'     | '1%'    | '1/16W'  | 'IO'       | 'RES CHIP 127 1/16W +-1%(0402)'                    | 'CHIPR0402'    | ''          | ''            | '20220704'
 '0.001'      | '1%'      | '2W'     | '2512LF'  | 'CHIP'   | 'CS+001AFR12'(!)        = ''              | ''                 | 'CS+001AFR12'           |'R2512XG'| '(SMR2512AW)'                  | '0.001'   | '1%'    | '2W'     | 'DISCRETE' | 'RES CHIP 0.001 2W +-1%(2512)RLC'                  | 'CHIPR2512'    | ''          | ''            | '20220704'
 '0.001'      | '1%'      | '2W'     | '2512LF'  | 'EMPTY'  | 'CS+001AFR12'(!)        = ''              | ''                 | 'CS+001AFR12'           |'R2512XG'| '(SMR2512AW)'                  | '0.001'   | '1%'    | '2W'     | 'IO'       | 'RES CHIP 0.001 2W +-1%(2512)RLC'                  | 'CHIPR2512'    | ''          | ''            | '20220704'
 '7.5M'       | '1%'      | '1/16W'  | '0402LF'  | 'CHIP'   | 'CS57502FB00'(!)        = ''              | ''                 | 'CS57502FB00'           |'R0402'| '(R0402-0201)'                 | '7.5M'    | '1%'    | '1/16W'  | 'DISCRETE' | 'RES CHIP 7.5M 1/16W +-1%(0402)'                   | 'CHIPR0402'    | ''          | ''            | '20220704'
 '7.5M'       | '1%'      | '1/16W'  | '0402LF'  | 'EMPTY'  | 'CS57502FB00'(!)        = ''              | ''                 | 'CS57502FB00'           |'R0402'| '(R0402-0201)'                 | '7.5M'    | '1%'    | '1/16W'  | 'IO'       | 'RES CHIP 7.5M 1/16W +-1%(0402)'                   | 'CHIPR0402'    | ''          | ''            | '20220704'
 '619K'       | '1%'      | '1/8W'   | '0805LF'  | 'CHIP'   | 'CS46194FA00'(!)        = ''              | ''                 | 'CS46194FA00'           |'R0805'| '(SMR0805AW)'                  | '619K'    | '1%'    | '1/8W'   | 'DISCRETE' | 'RES CHIP 619K 1/8W +-1%(0805)'                    | 'CHIPR0805'    | ''          | ''            | '20220715'
 '619K'       | '1%'      | '1/8W'   | '0805LF'  | 'EMPTY'  | 'CS46194FA00'(!)        = ''              | ''                 | 'CS46194FA00'           |'R0805'| '(SMR0805AW)'                  | '619K'    | '1%'    | '1/8W'   | 'IO'       | 'RES CHIP 619K 1/8W +-1%(0805)'                    | 'CHIPR0805'    | ''          | ''            | '20220715'
 '97.6K'      | '1%'      | '1/8W'   | '0805LF'  | 'CHIP'   | 'CS39764FA00'(!)        = ''              | ''                 | 'CS39764FA00'           |'R0805'| '(SMR0805AW)'                  | '97.6K'   | '1%'    | '1/8W'   | 'DISCRETE' | 'RES CHIP 97.6K 1/8W +-1%(0805)'                   | 'CHIPR0805'    | ''          | ''            | '20220715'
 '97.6K'      | '1%'      | '1/8W'   | '0805LF'  | 'EMPTY'  | 'CS39764FA00'(!)        = ''              | ''                 | 'CS39764FA00'           |'R0805'| '(SMR0805AW)'                  | '97.6K'   | '1%'    | '1/8W'   | 'IO'       | 'RES CHIP 97.6K 1/8W +-1%(0805)'                   | 'CHIPR0805'    | ''          | ''            | '20220715'
 '16K'        | '1%'      | '1/16W'  | '0402LF'  | 'CHIP'   | 'CS31602FB01'(!)        = 'End of Design' | 'Comp-Approve'     | 'CS31602FB01'           |'R0402'| '(R0402-0201)'                 | '16K'     | '1%'    | '1/16W'  | 'DISCRETE' | 'RES CHIP 16K 1/16W +-1%(0402)EF'                  | 'CHIPR0402'    | ''          | ''            | '20220802'
 '16K'        | '1%'      | '1/16W'  | '0402LF'  | 'EMPTY'  | 'CS31602FB01'(!)        = 'End of Design' | 'Comp-Approve'     | 'CS31602FB01'           |'R0402'| '(R0402-0201)'                 | '16K'     | '1%'    | '1/16W'  | 'IO'       | 'RES CHIP 16K 1/16W +-1%(0402)EF'                  | 'CHIPR0402'    | ''          | ''            | '20220802'
 '374K'       | '1%'      | '1/16W'  | '0402LF'  | 'CHIP'   | 'CS43742FB00'(!)        = 'End of Design' | 'Comp-Approve'     | 'CS43742FB00'           |'R0402'| '(R0402-0201)'                 | '374K'    | '1%'    | '1/16W'  | 'DISCRETE' | 'RES CHIP 374K 1/16W +-1%(0402)'                   | 'CHIPR0402'    | ''          | ''            | '20220803'
 '374K'       | '1%'      | '1/16W'  | '0402LF'  | 'EMPTY'  | 'CS43742FB00'(!)        = 'End of Design' | 'Comp-Approve'     | 'CS43742FB00'           |'R0402'| '(R0402-0201)'                 | '374K'    | '1%'    | '1/16W'  | 'IO'       | 'RES CHIP 374K 1/16W +-1%(0402)'                   | 'CHIPR0402'    | ''          | ''            | '20220803'
 '10K'        | '1%'      | '1/20W'  | '0201LF'  | 'CHIP'   | 'CS31001FE16'(!)        = ''              | ''                 | 'CS31001FE16'           |'R0201'| '(SMR0201AW)'                  | '10K'     | '1%'    | '1/20W'  | 'DISCRETE' | 'RES CHIP 10K 1/20W +-1%(0201)YGO'                 | 'CHIPR0201'    | ''          | ''            | '20220816'
 '10K'        | '1%'      | '1/20W'  | '0201LF'  | 'EMPTY'  | 'CS31001FE16'(!)        = ''              | ''                 | 'CS31001FE16'           |'R0201'| '(SMR0201AW)'                  | '10K'     | '1%'    | '1/20W'  | 'IO'       | 'RES CHIP 10K 1/20W +-1%(0201)YGO'                 | 'CHIPR0201'    | ''          | ''            | '20220816'
 '0.03'       | '1%'      | '1/2W'   | '0805LF'  | 'CHIP'   | 'CS+0307FA02'(!)        = ''              | ''                 | 'CS+0307FA02'           |'R0805_H26'| '(SMR0805AW)'                  | '0.03'    | '1%'    | '1/2W'   | 'DISCRETE' | 'RES CHIP 0.03 1/2W 1%(0805)H0.55'                 | 'CHIPR0805'    | ''          | ''            | '20220818'
 '0.03'       | '1%'      | '1/2W'   | '0805LF'  | 'EMPTY'  | 'CS+0307FA02'(!)        = ''              | ''                 | 'CS+0307FA02'           |'R0805_H26'| '(SMR0805AW)'                  | '0.03'    | '1%'    | '1/2W'   | 'IO'       | 'RES CHIP 0.03 1/2W 1%(0805)H0.55'                 | 'CHIPR0805'    | ''          | ''            | '20220818'
 '470'        | '1%'      | '1/20W'  | '0201LF'  | 'CHIP'   | 'CS14701FE10'(!)        = ''              | ''                 | 'CS14701FE10'           |'R0201'| '(SMR0201AW)'                  | '470'     | '1%'    | '1/20W'  | 'DISCRETE' | 'RES CHIP 470 1/20W +-1% (0201)YGO'                | 'CHIPR0201'    | ''          | ''            | '20220818'
 '470'        | '1%'      | '1/20W'  | '0201LF'  | 'EMPTY'  | 'CS14701FE10'(!)        = ''              | ''                 | 'CS14701FE10'           |'R0201'| '(SMR0201AW)'                  | '470'     | '1%'    | '1/20W'  | 'IO'       | 'RES CHIP 470 1/20W +-1% (0201)YGO'                | 'CHIPR0201'    | ''          | ''            | '20220818'
 '0'          | ''        | '1/16W'  | '0402LF'  | 'CHIP'   | 'CS00002TB04'(!)        = ''              | ''                 | 'CS00002TB04'           |'R0402'| '(R0402-0201)'                 | '0'       | ''      | '1/16W'  | 'DISCRETE' | 'RES CHIP 0 1/16W(0402)WTC'                        | 'CHIPR0402'    | ''          | ''            | '20220824'
 '0'          | ''        | '1/16W'  | '0402LF'  | 'EMPTY'  | 'CS00002TB04'(!)        = ''              | ''                 | 'CS00002TB04'           |'R0402'| '(R0402-0201)'                 | '0'       | ''      | '1/16W'  | 'IO'       | 'RES CHIP 0 1/16W(0402)WTC'                        | 'CHIPR0402'    | ''          | ''            | '20220824'
 '0.2'        | '1%'      | '1/16W'  | '0402LF'  | 'CHIP'   | 'CS+2002FB00'(!)        = ''              | ''                 | 'CS+2002FB00'           |'R0402'| '(R0402-0201)'                 | '0.2'     | '1%'    | '1/16W'  | 'DISCRETE' | 'RES CHIP 0.2 1/16W +-1%(0402)'                    | 'CHIPR0402'    | ''          | ''            | '20220829'
 '0.2'        | '1%'      | '1/16W'  | '0402LF'  | 'EMPTY'  | 'CS+2002FB00'(!)        = ''              | ''                 | 'CS+2002FB00'           |'R0402'| '(R0402-0201)'                 | '0.2'     | '1%'    | '1/16W'  | 'IO'       | 'RES CHIP 0.2 1/16W +-1%(0402)'                    | 'CHIPR0402'    | ''          | ''            | '20220829'
 '56.2K'      | '1%'      | '1/10W'  | '0603LF'  | 'CHIP'   | 'CS35623F924'(!)        = ''              | ''                 | 'CS35623F924'           |'R0603'| '(SMR0603AW)'                  | '56.2K'   | '1%'    | '1/10W'  | 'DISCRETE' | 'RESISTOR CHIP 56.2K,1/10W,+-1%(0603)'             | 'CHIPR0603'    | ''          | ''            | '20220829'
 '56.2K'      | '1%'      | '1/10W'  | '0603LF'  | 'EMPTY'  | 'CS35623F924'(!)        = ''              | ''                 | 'CS35623F924'           |'R0603'| '(SMR0603AW)'                  | '56.2K'   | '1%'    | '1/10W'  | 'IO'       | 'RESISTOR CHIP 56.2K,1/10W,+-1%(0603)'             | 'CHIPR0603'    | ''          | ''            | '20220829'
 '42.2K'      | '1%'      | '1/16W'  | '0402LF'  | 'CHIP'   | 'CS34222FB06'(!)        = ''              | ''                 | 'CS34222FB06'           |'R0402'| '(R0402-0201)'                 | '42.2K'   | '1%'    | '1/16W'  | 'DISCRETE' | 'RES CHIP 42.2K 1/16W +-1%(0402)EF'                | 'CHIPR0402'    | ''          | ''            | '20220905'
 '42.2K'      | '1%'      | '1/16W'  | '0402LF'  | 'EMPTY'  | 'CS34222FB06'(!)        = ''              | ''                 | 'CS34222FB06'           |'R0402'| '(R0402-0201)'                 | '42.2K'   | '1%'    | '1/16W'  | 'IO'       | 'RES CHIP 42.2K 1/16W +-1%(0402)EF'                | 'CHIPR0402'    | ''          | ''            | '20220905'
 '2.94K'      | '1%'      | '1/16W'  | '0402LF'  | 'CHIP'   | 'CS22942FB03'(!)        = 'End of Design' | 'Comp-Approve'     | 'CS22942FB03'           |'R0402'| '(R0402-0201)'                 | '2.94K'   | '1%'    | '1/16W'  | 'DISCRETE' | 'RES CHIP 2.94K 1/16W +-1%(0402)EF'                | 'CHIPR0402'    | ''          | ''            | '20220927'
 '2.94K'      | '1%'      | '1/16W'  | '0402LF'  | 'EMPTY'  | 'CS22942FB03'(!)        = 'End of Design' | 'Comp-Approve'     | 'CS22942FB03'           |'R0402'| '(R0402-0201)'                 | '2.94K'   | '1%'    | '1/16W'  | 'IO'       | 'RES CHIP 2.94K 1/16W +-1%(0402)EF'                | 'CHIPR0402'    | ''          | ''            | '20220927'
 '45.3K'      | '0.1%'    | '1/16W'  | '0402LF'  | 'CHIP'   | 'CS34532BB01'(!)        = ''              | ''                 | 'CS34532BB01'           |'R0402'| '(R0402-0201)'                 | '45.3K'   | '0.1%'  | '1/16W'  | 'DISCRETE' | 'RES CHIP 45.3K 1/16W +-0.1%(0402)'                | 'CHIPR0402'    | ''          | ''            | '20220928'
 '45.3K'      | '0.1%'    | '1/16W'  | '0402LF'  | 'EMPTY'  | 'CS34532BB01'(!)        = ''              | ''                 | 'CS34532BB01'           |'R0402'| '(R0402-0201)'                 | '45.3K'   | '0.1%'  | '1/16W'  | 'IO'       | 'RES CHIP 45.3K 1/16W +-0.1%(0402)'                | 'CHIPR0402'    | ''          | ''            | '20220928'
 '383K'       | '1%'      | '1/16W'  | '0402LF'  | 'CHIP'   | 'CS43832FB00'(!)        = 'End of Design' | 'Comp-Approve'     | 'CS43832FB00'           |'R0402'| '(R0402-0201)'                 | '383K'    | '1%'    | '1/16W'  | 'DISCRETE' | 'RES CHIP 383K 1/16W +-1% (0402)'                  | 'CHIPR0402'    | ''          | ''            | '20220929'
 '383K'       | '1%'      | '1/16W'  | '0402LF'  | 'EMPTY'  | 'CS43832FB00'(!)        = 'End of Design' | 'Comp-Approve'     | 'CS43832FB00'           |'R0402'| '(R0402-0201)'                 | '383K'    | '1%'    | '1/16W'  | 'IO'       | 'RES CHIP 383K 1/16W +-1% (0402)'                  | 'CHIPR0402'    | ''          | ''            | '20220929'
 '5.1'        | '1%'      | '1/8W'   | '0805LF'  | 'CHIP'   | 'CS-5104FA21'(!)        = ''              | ''                 | 'CS-5104FA21'           |'R0805_H26'| '(SMR0805AW)'                  | '5.1'     | '1%'    | '1/8W'   | 'DISCRETE' | 'RES CHIP 5.1 1/8W +-1%(0805)'                     | 'CHIPR0805'    | ''          | ''            | '20221003'
 '5.1'        | '1%'      | '1/8W'   | '0805LF'  | 'EMPTY'  | 'CS-5104FA21'(!)        = ''              | ''                 | 'CS-5104FA21'           |'R0805_H26'| '(SMR0805AW)'                  | '5.1'     | '1%'    | '1/8W'   | 'IO'       | 'RES CHIP 5.1 1/8W +-1%(0805)'                     | 'CHIPR0805'    | ''          | ''            | '20221003'
 '5.6'        | '1%'      | '1/16W'  | '0402LF'  | 'CHIP'   | 'CS-5602FB00'(!)        = 'End of Design' | 'Comp-Approve'     | 'CS-5602FB00'           |'R0402'| '(R0402-0201)'                 | '5.6'     | '1%'    | '1/16W'  | 'DISCRETE' | 'RES CHIP 5.6 1/16W 1%(0402)'                      | 'CHIPR0402'    | ''          | ''            | '20221007'
 '5.6'        | '1%'      | '1/16W'  | '0402LF'  | 'EMPTY'  | 'CS-5602FB00'(!)        = 'End of Design' | 'Comp-Approve'     | 'CS-5602FB00'           |'R0402'| '(R0402-0201)'                 | '5.6'     | '1%'    | '1/16W'  | 'IO'       | 'RES CHIP 5.6 1/16W 1%(0402)'                      | 'CHIPR0402'    | ''          | ''            | '20221007'
 '3.83K'      | '0.1%'    | '1/16W'  | '0402LF'  | 'CHIP'   | 'CS23832BB01'(!)        = ''              | ''                 | 'CS23832BB01'           |'R0402'| '(R0402-0201)'                 | '3.83K'   | '0.1%'  | '1/16W'  | 'DISCRETE' | 'RES CHIP 3.83K 1/16W +-0.1% (0402)'               | 'CHIPR0402'    | ''          | ''            | '20221011'
 '3.83K'      | '0.1%'    | '1/16W'  | '0402LF'  | 'EMPTY'  | 'CS23832BB01'(!)        = ''              | ''                 | 'CS23832BB01'           |'R0402'| '(R0402-0201)'                 | '3.83K'   | '0.1%'  | '1/16W'  | 'IO'       | 'RES CHIP 3.83K 1/16W +-0.1% (0402)'               | 'CHIPR0402'    | ''          | ''            | '20221011'
 '0'          | '5%'      | '1/16W'  | '0402LF'  | 'CHIP'   | 'CS00002JB15'(!)        = ''              | ''                 | 'CS00002JB15'           |'R0402'| '(R0402-0201)'                 | '0'       | '5%'    | '1/16W'  | 'DISCRETE' | 'RES CHIP 0(5%,1/16W,0402)YGO'                     | 'CHIPR0402'    | ''          | ''            | '20221017'
 '0'          | '5%'      | '1/16W'  | '0402LF'  | 'EMPTY'  | 'CS00002JB15'(!)        = ''              | ''                 | 'CS00002JB15'           |'R0402'| '(R0402-0201)'                 | '0'       | '5%'    | '1/16W'  | 'IO'       | 'RES CHIP 0(5%,1/16W,0402)YGO'                     | 'CHIPR0402'    | ''          | ''            | '20221017'
 '1K'         | '5%'      | '1/16W'  | '0402LF'  | 'CHIP'   | 'CS21002JB25'(!)        = ''              | ''                 | 'CS21002JB25'           |'R0402'| '(R0402-0201)'                 | '1K'      | '5%'    | '1/16W'  | 'DISCRETE' | 'RES CHIP 1K 1/16W 5%(0402) WTC'                   | 'CHIPR0402'    | ''          | ''            | '20221017'
 '1K'         | '5%'      | '1/16W'  | '0402LF'  | 'EMPTY'  | 'CS21002JB25'(!)        = ''              | ''                 | 'CS21002JB25'           |'R0402'| '(R0402-0201)'                 | '1K'      | '5%'    | '1/16W'  | 'IO'       | 'RES CHIP 1K 1/16W 5%(0402) WTC'                   | 'CHIPR0402'    | ''          | ''            | '20221017'
 '4.7K'       | '5%'      | '1/16W'  | '0402LF'  | 'CHIP'   | 'CS24702JB18'(!)        = ''              | ''                 | 'CS24702JB18'           |'R0402'| '(R0402-0201)'                 | '4.7K'    | '5%'    | '1/16W'  | 'DISCRETE' | 'RES CHIP 4.7K 1/16W +-5% (0402)WTC'               | 'CHIPR0402'    | ''          | ''            | '20221017'
 '4.7K'       | '5%'      | '1/16W'  | '0402LF'  | 'EMPTY'  | 'CS24702JB18'(!)        = ''              | ''                 | 'CS24702JB18'           |'R0402'| '(R0402-0201)'                 | '4.7K'    | '5%'    | '1/16W'  | 'IO'       | 'RES CHIP 4.7K 1/16W +-5% (0402)WTC'               | 'CHIPR0402'    | ''          | ''            | '20221017'
 '10'         | '1%'      | '1/16W'  | '0402LF'  | 'CHIP'   | 'CS01002FB29'(!)        = ''              | ''                 | 'CS01002FB29'           |'R0402'| '(R0402-0201)'                 | '10'      | '1%'    | '1/16W'  | 'DISCRETE' | 'RES CHIP 10 1/16W +-1%(0402)CYN'                  | 'CHIPR0402'    | ''          | ''            | '20221017'
 '10'         | '1%'      | '1/16W'  | '0402LF'  | 'EMPTY'  | 'CS01002FB29'(!)        = ''              | ''                 | 'CS01002FB29'           |'R0402'| '(R0402-0201)'                 | '10'      | '1%'    | '1/16W'  | 'IO'       | 'RES CHIP 10 1/16W +-1%(0402)CYN'                  | 'CHIPR0402'    | ''          | ''            | '20221017'
 '10'         | '1%'      | '1/16W'  | '0402LF'  | 'CHIP'   | 'CS01002FB28'(!)        = ''              | ''                 | 'CS01002FB28'           |'R0402'| '(R0402-0201)'                 | '10'      | '1%'    | '1/16W'  | 'DISCRETE' | 'RES CHIP 10 1/16W +-1%(0402)WTC'                  | 'CHIPR0402'    | ''          | ''            | '20221017'
 '10'         | '1%'      | '1/16W'  | '0402LF'  | 'EMPTY'  | 'CS01002FB28'(!)        = ''              | ''                 | 'CS01002FB28'           |'R0402'| '(R0402-0201)'                 | '10'      | '1%'    | '1/16W'  | 'IO'       | 'RES CHIP 10 1/16W +-1%(0402)WTC'                  | 'CHIPR0402'    | ''          | ''            | '20221017'
 '1K'         | '1%'      | '1/16W'  | '0402LF'  | 'CHIP'   | 'CS21002FB27'(!)        = ''              | ''                 | 'CS21002FB27'           |'R0402'| '(R0402-0201)'                 | '1K'      | '1%'    | '1/16W'  | 'DISCRETE' | 'RES CHIP 1K 1/16W +-1% (0402)WTC'                 | 'CHIPR0402'    | ''          | ''            | '20221017'
 '1K'         | '1%'      | '1/16W'  | '0402LF'  | 'EMPTY'  | 'CS21002FB27'(!)        = ''              | ''                 | 'CS21002FB27'           |'R0402'| '(R0402-0201)'                 | '1K'      | '1%'    | '1/16W'  | 'IO'       | 'RES CHIP 1K 1/16W +-1% (0402)WTC'                 | 'CHIPR0402'    | ''          | ''            | '20221017'
 '6.81K'      | '1%'      | '1/16W'  | '0402LF'  | 'CHIP'   | 'CS26812FB10'(!)        = ''              | ''                 | 'CS26812FB10'           |'R0402'| '(R0402-0201)'                 | '6.81K'   | '1%'    | '1/16W'  | 'DISCRETE' | 'RES CHIP 6.81K 1/16W +-1% (0402)WTC'              | 'CHIPR0402'    | ''          | ''            | '20221017'
 '6.81K'      | '1%'      | '1/16W'  | '0402LF'  | 'EMPTY'  | 'CS26812FB10'(!)        = ''              | ''                 | 'CS26812FB10'           |'R0402'| '(R0402-0201)'                 | '6.81K'   | '1%'    | '1/16W'  | 'IO'       | 'RES CHIP 6.81K 1/16W +-1% (0402)WTC'              | 'CHIPR0402'    | ''          | ''            | '20221017'
 '13K'        | '1%'      | '1/16W'  | '0402LF'  | 'CHIP'   | 'CS31302FB10'(!)        = ''              | ''                 | 'CS31302FB10'           |'R0402'| '(R0402-0201)'                 | '13K'     | '1%'    | '1/16W'  | 'DISCRETE' | 'RES CHIP 13K 1/16W +-1%( 0402)WTC'                | 'CHIPR0402'    | ''          | ''            | '20221017'
 '13K'        | '1%'      | '1/16W'  | '0402LF'  | 'EMPTY'  | 'CS31302FB10'(!)        = ''              | ''                 | 'CS31302FB10'           |'R0402'| '(R0402-0201)'                 | '13K'     | '1%'    | '1/16W'  | 'IO'       | 'RES CHIP 13K 1/16W +-1%( 0402)WTC'                | 'CHIPR0402'    | ''          | ''            | '20221017'
 '100K'       | '1%'      | '1/16W'  | '0402LF'  | 'CHIP'   | 'CS41002FB14'(!)        = ''              | ''                 | 'CS41002FB14'           |'R0402'| '(R0402-0201)'                 | '100K'    | '1%'    | '1/16W'  | 'DISCRETE' | 'RES CHIP 100K(1%,1/16W,0402)WTC'                  | 'CHIPR0402'    | ''          | ''            | '20221017'
 '100K'       | '1%'      | '1/16W'  | '0402LF'  | 'EMPTY'  | 'CS41002FB14'(!)        = ''              | ''                 | 'CS41002FB14'           |'R0402'| '(R0402-0201)'                 | '100K'    | '1%'    | '1/16W'  | 'IO'       | 'RES CHIP 100K(1%,1/16W,0402)WTC'                  | 'CHIPR0402'    | ''          | ''            | '20221017'
 '33'         | '5%'      | '1/16W'  | '0402LF'  | 'CHIP'   | 'CS03302JB22'(!)        = ''              | ''                 | 'CS03302JB22'           |'R0402'| '(R0402-0201)'                 | '33'      | '5%'    | '1/16W'  | 'DISCRETE' | 'RES CHIP 33 1/16W +-5% (0402)WTC'                 | 'CHIPR0402'    | ''          | ''            | '20221017'
 '33'         | '5%'      | '1/16W'  | '0402LF'  | 'EMPTY'  | 'CS03302JB22'(!)        = ''              | ''                 | 'CS03302JB22'           |'R0402'| '(R0402-0201)'                 | '33'      | '5%'    | '1/16W'  | 'IO'       | 'RES CHIP 33 1/16W +-5% (0402)WTC'                 | 'CHIPR0402'    | ''          | ''            | '20221017'
 '60.4K'      | '1%'      | '1/16W'  | '0402LF'  | 'CHIP'   | 'CS36042FB11'(!)        = ''              | ''                 | 'CS36042FB11'           |'R0402'| '(R0402-0201)'                 | '60.4K'   | '1%'    | '1/16W'  | 'DISCRETE' | 'RES CHIP 60.4K 1/16W +-1%(0402)WTC'               | 'CHIPR0402'    | ''          | ''            | '20221017'
 '60.4K'      | '1%'      | '1/16W'  | '0402LF'  | 'EMPTY'  | 'CS36042FB11'(!)        = ''              | ''                 | 'CS36042FB11'           |'R0402'| '(R0402-0201)'                 | '60.4K'   | '1%'    | '1/16W'  | 'IO'       | 'RES CHIP 60.4K 1/16W +-1%(0402)WTC'               | 'CHIPR0402'    | ''          | ''            | '20221017'
 '6.81K'      | '1%'      | '1/16W'  | '0402LF'  | 'CHIP'   | 'CS26812FB11'(!)        = ''              | ''                 | 'CS26812FB11'           |'R0402'| '(R0402-0201)'                 | '6.81K'   | '1%'    | '1/16W'  | 'DISCRETE' | 'RES CHIP 6.81K 1/16W +-1% (0402)YGO'              | 'CHIPR0402'    | ''          | ''            | '20221017'
 '6.81K'      | '1%'      | '1/16W'  | '0402LF'  | 'EMPTY'  | 'CS26812FB11'(!)        = ''              | ''                 | 'CS26812FB11'           |'R0402'| '(R0402-0201)'                 | '6.81K'   | '1%'    | '1/16W'  | 'IO'       | 'RES CHIP 6.81K 1/16W +-1% (0402)YGO'              | 'CHIPR0402'    | ''          | ''            | '20221017'
 '13K'        | '1%'      | '1/16W'  | '0402LF'  | 'CHIP'   | 'CS31302FB09'(!)        = ''              | ''                 | 'CS31302FB09'           |'R0402'| '(R0402-0201)'                 | '13K'     | '1%'    | '1/16W'  | 'DISCRETE' | 'RES CHIP 13K 1/16W +-1%( 0402)YGO'                | 'CHIPR0402'    | ''          | ''            | '20221017'
 '13K'        | '1%'      | '1/16W'  | '0402LF'  | 'EMPTY'  | 'CS31302FB09'(!)        = ''              | ''                 | 'CS31302FB09'           |'R0402'| '(R0402-0201)'                 | '13K'     | '1%'    | '1/16W'  | 'IO'       | 'RES CHIP 13K 1/16W +-1%( 0402)YGO'                | 'CHIPR0402'    | ''          | ''            | '20221017'
 '48.7K'      | '1%'      | '1/16W'  | '0402LF'  | 'CHIP'   | 'CS34872FB13'(!)        = ''              | ''                 | 'CS34872FB13'           |'R0402'| '(R0402-0201)'                 | '48.7K'   | '1%'    | '1/16W'  | 'DISCRETE' | 'RES CHIP 48.7K 1/16W +-1% (0402)YGO'              | 'CHIPR0402'    | ''          | ''            | '20221017'
 '48.7K'      | '1%'      | '1/16W'  | '0402LF'  | 'EMPTY'  | 'CS34872FB13'(!)        = ''              | ''                 | 'CS34872FB13'           |'R0402'| '(R0402-0201)'                 | '48.7K'   | '1%'    | '1/16W'  | 'IO'       | 'RES CHIP 48.7K 1/16W +-1% (0402)YGO'              | 'CHIPR0402'    | ''          | ''            | '20221017'
 '54.9K'      | '1%'      | '1/16W'  | '0402LF'  | 'CHIP'   | 'CS35492FB12'(!)        = ''              | ''                 | 'CS35492FB12'           |'R0402'| '(R0402-0201)'                 | '54.9K'   | '1%'    | '1/16W'  | 'DISCRETE' | 'RES CHIP 54.9K 1/16W +-1%(0402)YGO'               | 'CHIPR0402'    | ''          | ''            | '20221017'
 '54.9K'      | '1%'      | '1/16W'  | '0402LF'  | 'EMPTY'  | 'CS35492FB12'(!)        = ''              | ''                 | 'CS35492FB12'           |'R0402'| '(R0402-0201)'                 | '54.9K'   | '1%'    | '1/16W'  | 'IO'       | 'RES CHIP 54.9K 1/16W +-1%(0402)YGO'               | 'CHIPR0402'    | ''          | ''            | '20221017'
 '0'          | '5%'      | '1/8W'   | '0805LF'  | 'CHIP'   | 'CS00004JA09'(!)        = ''              | ''                 | 'CS00004JA09'           |'R0805'| '(SMR0805AW)'                  | '0'       | '5%'    | '1/8W'   | 'DISCRETE' | 'RES CHIP 0 1/8W +-5%(0805)YGO'                    | 'CHIPR0805'    | ''          | ''            | '20221017'
 '0'          | '5%'      | '1/8W'   | '0805LF'  | 'EMPTY'  | 'CS00004JA09'(!)        = ''              | ''                 | 'CS00004JA09'           |'R0805'| '(SMR0805AW)'                  | '0'       | '5%'    | '1/8W'   | 'IO'       | 'RES CHIP 0 1/8W +-5%(0805)YGO'                    | 'CHIPR0805'    | ''          | ''            | '20221017'
 '10'         | '1%'      | '1/10W'  | '0603LF'  | 'CHIP'   | 'CS01003F912'(!)        = ''              | ''                 | 'CS01003F912'           |'R0603'| '(SMR0603AW)'                  | '10'      | '1%'    | '1/10W'  | 'DISCRETE' | 'RES CHIP 10 1/10W +-1%(0603)YGO'                  | 'CHIPR0603'    | ''          | ''            | '20221017'
 '10'         | '1%'      | '1/10W'  | '0603LF'  | 'EMPTY'  | 'CS01003F912'(!)        = ''              | ''                 | 'CS01003F912'           |'R0603'| '(SMR0603AW)'                  | '10'      | '1%'    | '1/10W'  | 'IO'       | 'RES CHIP 10 1/10W +-1%(0603)YGO'                  | 'CHIPR0603'    | ''          | ''            | '20221017'
 '33'         | '5%'      | '1/16W'  | '0402LF'  | 'CHIP'   | 'CS03302JB23'(!)        = ''              | ''                 | 'CS03302JB23'           |'R0402'| '(R0402-0201)'                 | '33'      | '5%'    | '1/16W'  | 'DISCRETE' | 'RES CHIP 33 1/16W +-5% (0402)YGO'                 | 'CHIPR0402'    | ''          | ''            | '20221017'
 '33'         | '5%'      | '1/16W'  | '0402LF'  | 'EMPTY'  | 'CS03302JB23'(!)        = ''              | ''                 | 'CS03302JB23'           |'R0402'| '(R0402-0201)'                 | '33'      | '5%'    | '1/16W'  | 'IO'       | 'RES CHIP 33 1/16W +-5% (0402)YGO'                 | 'CHIPR0402'    | ''          | ''            | '20221017'
 '60.4K'      | '1%'      | '1/16W'  | '0402LF'  | 'CHIP'   | 'CS36042FB09'(!)        = ''              | ''                 | 'CS36042FB09'           |'R0402'| '(R0402-0201)'                 | '60.4K'   | '1%'    | '1/16W'  | 'DISCRETE' | 'RES CHIP 60.4K 1/16W +-1%(0402)YGO'               | 'CHIPR0402'    | ''          | ''            | '20221017'
 '60.4K'      | '1%'      | '1/16W'  | '0402LF'  | 'EMPTY'  | 'CS36042FB09'(!)        = ''              | ''                 | 'CS36042FB09'           |'R0402'| '(R0402-0201)'                 | '60.4K'   | '1%'    | '1/16W'  | 'IO'       | 'RES CHIP 60.4K 1/16W +-1%(0402)YGO'               | 'CHIPR0402'    | ''          | ''            | '20221017'
 '0'          | ''        | '1/8W'   | '0805LF'  | 'CHIP'   | 'CS00004TA05'(!)        = ''              | ''                 | 'CS00004TA05'           |'R0805_H26'| '(SMR0805AW)'                  | '0'       | ''      | '1/8W'   | 'DISCRETE' | 'RES CHIP 0 1/8W(0805)WTC'                         | 'CHIPR0805'    | ''          | ''            | '20221018'
 '0'          | ''        | '1/8W'   | '0805LF'  | 'EMPTY'  | 'CS00004TA05'(!)        = ''              | ''                 | 'CS00004TA05'           |'R0805_H26'| '(SMR0805AW)'                  | '0'       | ''      | '1/8W'   | 'IO'       | 'RES CHIP 0 1/8W(0805)WTC'                         | 'CHIPR0805'    | ''          | ''            | '20221018'
 '330'        | '1%'      | '1/10W'  | '0603LF'  | 'CHIP'   | 'CS13303F906'(!)        = ''              | ''                 | 'CS13303F906'           |'R0603_H24'| '(SMR0603AW)'                  | '330'     | '1%'    | '1/10W'  | 'DISCRETE' | 'RES CHIP 330 1/10W +-1%(0603)WTC'                 | 'CHIPR0603'    | ''          | ''            | '20221018'
 '330'        | '1%'      | '1/10W'  | '0603LF'  | 'EMPTY'  | 'CS13303F906'(!)        = ''              | ''                 | 'CS13303F906'           |'R0603_H24'| '(SMR0603AW)'                  | '330'     | '1%'    | '1/10W'  | 'IO'       | 'RES CHIP 330 1/10W +-1%(0603)WTC'                 | 'CHIPR0603'    | ''          | ''            | '20221018'
 '10M'        | '5%'      | '1/16W'  | '0402LF'  | 'CHIP'   | 'CS61002JB17'(!)        = ''              | ''                 | 'CS61002JB17'           |'R0402'| '(R0402-0201)'                 | '10M'     | '5%'    | '1/16W'  | 'DISCRETE' | 'RES CHIP 10M 1/16W +-5% (0402)WTC'                | 'CHIPR0402'    | ''          | ''            | '20221019'
 '10M'        | '5%'      | '1/16W'  | '0402LF'  | 'EMPTY'  | 'CS61002JB17'(!)        = ''              | ''                 | 'CS61002JB17'           |'R0402'| '(R0402-0201)'                 | '10M'     | '5%'    | '1/16W'  | 'IO'       | 'RES CHIP 10M 1/16W +-5% (0402)WTC'                | 'CHIPR0402'    | ''          | ''            | '20221019'
 '49.9'       | '1%'      | '1/16W'  | '0402LF'  | 'CHIP'   | 'CS04992FB23'(!)        = ''              | ''                 | 'CS04992FB23'           |'R0402'| '(R0402-0201)'                 | '49.9'    | '1%'    | '1/16W'  | 'DISCRETE' | 'RES CHIP 49.9 1/16W +-1% (0402)WTC'               | 'CHIPR0402'    | ''          | ''            | '20221019'
 '49.9'       | '1%'      | '1/16W'  | '0402LF'  | 'EMPTY'  | 'CS04992FB23'(!)        = ''              | ''                 | 'CS04992FB23'           |'R0402'| '(R0402-0201)'                 | '49.9'    | '1%'    | '1/16W'  | 'IO'       | 'RES CHIP 49.9 1/16W +-1% (0402)WTC'               | 'CHIPR0402'    | ''          | ''            | '20221019'
 '1'          | '1%'      | '1/16W'  | '0402LF'  | 'CHIP'   | 'CS-1002FB26'(!)        = ''              | ''                 | 'CS-1002FB26'           |'R0402'| '(R0402-0201)'                 | '1'       | '1%'    | '1/16W'  | 'DISCRETE' | 'RES CHIP 1 1/16W +-1%(0402)WTC'                   | 'CHIPR0402'    | ''          | ''            | '20221019'
 '1'          | '1%'      | '1/16W'  | '0402LF'  | 'EMPTY'  | 'CS-1002FB26'(!)        = ''              | ''                 | 'CS-1002FB26'           |'R0402'| '(R0402-0201)'                 | '1'       | '1%'    | '1/16W'  | 'IO'       | 'RES CHIP 1 1/16W +-1%(0402)WTC'                   | 'CHIPR0402'    | ''          | ''            | '20221019'
 '4.53K'      | '1%'      | '1/16W'  | '0402LF'  | 'CHIP'   | 'CS24532FB06'(!)        = ''              | ''                 | 'CS24532FB06'           |'R0402'| '(R0402-0201)'                 | '4.53K'   | '1%'    | '1/16W'  | 'DISCRETE' | 'RES CHIP 4.53K 1/16W +-1%(0402)WTC'               | 'CHIPR0402'    | ''          | ''            | '20221019'
 '4.53K'      | '1%'      | '1/16W'  | '0402LF'  | 'EMPTY'  | 'CS24532FB06'(!)        = ''              | ''                 | 'CS24532FB06'           |'R0402'| '(R0402-0201)'                 | '4.53K'   | '1%'    | '1/16W'  | 'IO'       | 'RES CHIP 4.53K 1/16W +-1%(0402)WTC'               | 'CHIPR0402'    | ''          | ''            | '20221019'
 '10K'        | '1%'      | '1/16W'  | '0402LF'  | 'CHIP'   | 'CS31002FB20'(!)        = ''              | ''                 | 'CS31002FB20'           |'R0402'| '(R0402-0201)'                 | '10K'     | '1%'    | '1/16W'  | 'DISCRETE' | 'RES CHIP 10K 1/16W +-1%(0402)WTC'                 | 'CHIPR0402'    | ''          | ''            | '20221019'
 '10K'        | '1%'      | '1/16W'  | '0402LF'  | 'EMPTY'  | 'CS31002FB20'(!)        = ''              | ''                 | 'CS31002FB20'           |'R0402'| '(R0402-0201)'                 | '10K'     | '1%'    | '1/16W'  | 'IO'       | 'RES CHIP 10K 1/16W +-1%(0402)WTC'                 | 'CHIPR0402'    | ''          | ''            | '20221019'
 '24.9K'      | '1%'      | '1/16W'  | '0402LF'  | 'CHIP'   | 'CS32492FB13'(!)        = ''              | ''                 | 'CS32492FB13'           |'R0402'| '(R0402-0201)'                 | '24.9K'   | '1%'    | '1/16W'  | 'DISCRETE' | 'RES CHIP 24.9K 1/16W +-1%(0402)WTC'               | 'CHIPR0402'    | ''          | ''            | '20221019'
 '24.9K'      | '1%'      | '1/16W'  | '0402LF'  | 'EMPTY'  | 'CS32492FB13'(!)        = ''              | ''                 | 'CS32492FB13'           |'R0402'| '(R0402-0201)'                 | '24.9K'   | '1%'    | '1/16W'  | 'IO'       | 'RES CHIP 24.9K 1/16W +-1%(0402)WTC'               | 'CHIPR0402'    | ''          | ''            | '20221019'
 '40.2K'      | '1%'      | '1/16W'  | '0402LF'  | 'CHIP'   | 'CS34022FB14'(!)        = ''              | ''                 | 'CS34022FB14'           |'R0402'| '(R0402-0201)'                 | '40.2K'   | '1%'    | '1/16W'  | 'DISCRETE' | 'RES CHIP 40.2K 1/16W +-1%(0402)WTC'               | 'CHIPR0402'    | ''          | ''            | '20221019'
 '40.2K'      | '1%'      | '1/16W'  | '0402LF'  | 'EMPTY'  | 'CS34022FB14'(!)        = ''              | ''                 | 'CS34022FB14'           |'R0402'| '(R0402-0201)'                 | '40.2K'   | '1%'    | '1/16W'  | 'IO'       | 'RES CHIP 40.2K 1/16W +-1%(0402)WTC'               | 'CHIPR0402'    | ''          | ''            | '20221019'
 '1.13K'      | '1%'      | '1/16W'  | '0402LF'  | 'CHIP'   | 'CS21132FB03'(!)        = ''              | ''                 | 'CS21132FB03'           |'R0402'| '(R0402-0201)'                 | '1.13K'   | '1%'    | '1/16W'  | 'DISCRETE' | 'RES CHIP 1.13K 1/16W +-1% (0402)YGO'              | 'CHIPR0402'    | ''          | ''            | '20221019'
 '1.13K'      | '1%'      | '1/16W'  | '0402LF'  | 'EMPTY'  | 'CS21132FB03'(!)        = ''              | ''                 | 'CS21132FB03'           |'R0402'| '(R0402-0201)'                 | '1.13K'   | '1%'    | '1/16W'  | 'IO'       | 'RES CHIP 1.13K 1/16W +-1% (0402)YGO'              | 'CHIPR0402'    | ''          | ''            | '20221019'
 '1'          | '1%'      | '1/16W'  | '0402LF'  | 'CHIP'   | 'CS-1002FB06'(!)        = ''              | ''                 | 'CS-1002FB06'           |'R0402'| '(R0402-0201)'                 | '1'       | '1%'    | '1/16W'  | 'DISCRETE' | 'RES CHIP 1(+-1%,1/16W,0402)YGO'                   | 'CHIPR0402'    | ''          | ''            | '20221019'
 '1'          | '1%'      | '1/16W'  | '0402LF'  | 'EMPTY'  | 'CS-1002FB06'(!)        = ''              | ''                 | 'CS-1002FB06'           |'R0402'| '(R0402-0201)'                 | '1'       | '1%'    | '1/16W'  | 'IO'       | 'RES CHIP 1(+-1%,1/16W,0402)YGO'                   | 'CHIPR0402'    | ''          | ''            | '20221019'
 '4.53K'      | '1%'      | '1/16W'  | '0402LF'  | 'CHIP'   | 'CS24532FB07'(!)        = ''              | ''                 | 'CS24532FB07'           |'R0402'| '(R0402-0201)'                 | '4.53K'   | '1%'    | '1/16W'  | 'DISCRETE' | 'RES CHIP 4.53K 1/16W +-1%(0402)YGO'               | 'CHIPR0402'    | ''          | ''            | '20221019'
 '4.53K'      | '1%'      | '1/16W'  | '0402LF'  | 'EMPTY'  | 'CS24532FB07'(!)        = ''              | ''                 | 'CS24532FB07'           |'R0402'| '(R0402-0201)'                 | '4.53K'   | '1%'    | '1/16W'  | 'IO'       | 'RES CHIP 4.53K 1/16W +-1%(0402)YGO'               | 'CHIPR0402'    | ''          | ''            | '20221019'
 '11.8K'      | '1%'      | '1/16W'  | '0402LF'  | 'CHIP'   | 'CS31182FB10'(!)        = ''              | ''                 | 'CS31182FB10'           |'R0402'| '(R0402-0201)'                 | '11.8K'   | '1%'    | '1/16W'  | 'DISCRETE' | 'RES CHIP 11.8K 1/16W +-1% (0402)YGO'              | 'CHIPR0402'    | ''          | ''            | '20221019'
 '11.8K'      | '1%'      | '1/16W'  | '0402LF'  | 'EMPTY'  | 'CS31182FB10'(!)        = ''              | ''                 | 'CS31182FB10'           |'R0402'| '(R0402-0201)'                 | '11.8K'   | '1%'    | '1/16W'  | 'IO'       | 'RES CHIP 11.8K 1/16W +-1% (0402)YGO'              | 'CHIPR0402'    | ''          | ''            | '20221019'
 '24.9K'      | '1%'      | '1/16W'  | '0402LF'  | 'CHIP'   | 'CS32492FB12'(!)        = ''              | ''                 | 'CS32492FB12'           |'R0402'| '(R0402-0201)'                 | '24.9K'   | '1%'    | '1/16W'  | 'DISCRETE' | 'RES CHIP 24.9K 1/16W +-1%(0402)YGO'               | 'CHIPR0402'    | ''          | ''            | '20221019'
 '24.9K'      | '1%'      | '1/16W'  | '0402LF'  | 'EMPTY'  | 'CS32492FB12'(!)        = ''              | ''                 | 'CS32492FB12'           |'R0402'| '(R0402-0201)'                 | '24.9K'   | '1%'    | '1/16W'  | 'IO'       | 'RES CHIP 24.9K 1/16W +-1%(0402)YGO'               | 'CHIPR0402'    | ''          | ''            | '20221019'
 '40.2K'      | '1%'      | '1/16W'  | '0402LF'  | 'CHIP'   | 'CS34022FB13'(!)        = ''              | ''                 | 'CS34022FB13'           |'R0402'| '(R0402-0201)'                 | '40.2K'   | '1%'    | '1/16W'  | 'DISCRETE' | 'RES CHIP 40.2K 1/16W +-1% (0402)YGO'              | 'CHIPR0402'    | ''          | ''            | '20221019'
 '40.2K'      | '1%'      | '1/16W'  | '0402LF'  | 'EMPTY'  | 'CS34022FB13'(!)        = ''              | ''                 | 'CS34022FB13'           |'R0402'| '(R0402-0201)'                 | '40.2K'   | '1%'    | '1/16W'  | 'IO'       | 'RES CHIP 40.2K 1/16W +-1% (0402)YGO'              | 'CHIPR0402'    | ''          | ''            | '20221019'
 '80.6K'      | '1%'      | '1/16W'  | '0402LF'  | 'CHIP'   | 'CS38062FB13'(!)        = ''              | ''                 | 'CS38062FB13'           |'R0402'| '(R0402-0201)'                 | '80.6K'   | '1%'    | '1/16W'  | 'DISCRETE' | 'RES CHIP 80.6K 1/16W +-1% (0402)YGO'              | 'CHIPR0402'    | ''          | ''            | '20221019'
 '80.6K'      | '1%'      | '1/16W'  | '0402LF'  | 'EMPTY'  | 'CS38062FB13'(!)        = ''              | ''                 | 'CS38062FB13'           |'R0402'| '(R0402-0201)'                 | '80.6K'   | '1%'    | '1/16W'  | 'IO'       | 'RES CHIP 80.6K 1/16W +-1% (0402)YGO'              | 'CHIPR0402'    | ''          | ''            | '20221019'
 '15'         | '1%'      | '1/16W'  | '0402LF'  | 'CHIP'   | 'CS01502FB08'(!)        = ''              | ''                 | 'CS01502FB08'           |'R0402'| '(R0402-0201)'                 | '15'      | '1%'    | '1/16W'  | 'DISCRETE' | 'RES CHIP 15 1/16W +-1% (0402)YGO'                 | 'CHIPR0402'    | ''          | ''            | '20221019'
 '15'         | '1%'      | '1/16W'  | '0402LF'  | 'EMPTY'  | 'CS01502FB08'(!)        = ''              | ''                 | 'CS01502FB08'           |'R0402'| '(R0402-0201)'                 | '15'      | '1%'    | '1/16W'  | 'IO'       | 'RES CHIP 15 1/16W +-1% (0402)YGO'                 | 'CHIPR0402'    | ''          | ''            | '20221019'
 '10M'        | '5%'      | '1/16W'  | '0402LF'  | 'CHIP'   | 'CS61002JB16'(!)        = ''              | ''                 | 'CS61002JB16'           |'R0402'| '(R0402-0201)'                 | '10M'     | '5%'    | '1/16W'  | 'DISCRETE' | 'RES CHIP 10M 1/16W +-5% (0402)YGO'                | 'CHIPR0402'    | ''          | ''            | '20221019'
 '10M'        | '5%'      | '1/16W'  | '0402LF'  | 'EMPTY'  | 'CS61002JB16'(!)        = ''              | ''                 | 'CS61002JB16'           |'R0402'| '(R0402-0201)'                 | '10M'     | '5%'    | '1/16W'  | 'IO'       | 'RES CHIP 10M 1/16W +-5% (0402)YGO'                | 'CHIPR0402'    | ''          | ''            | '20221019'
 '49.9'       | '1%'      | '1/10W'  | '0603LF'  | 'CHIP'   | 'CS04993F918'(!)        = ''              | ''                 | 'CS04993F918'           |'R0603'| '(SMR0603AW)'                  | '49.9'    | '1%'    | '1/10W'  | 'DISCRETE' | 'RES CHIP 49.9 1/10W +-1%(0603)YGO'                | 'CHIPR0603'    | ''          | ''            | '20221019'
 '49.9'       | '1%'      | '1/10W'  | '0603LF'  | 'EMPTY'  | 'CS04993F918'(!)        = ''              | ''                 | 'CS04993F918'           |'R0603'| '(SMR0603AW)'                  | '49.9'    | '1%'    | '1/10W'  | 'IO'       | 'RES CHIP 49.9 1/10W +-1%(0603)YGO'                | 'CHIPR0603'    | ''          | ''            | '20221019'
 '330'        | '1%'      | '1/10W'  | '0603LF'  | 'CHIP'   | 'CS13303F903'(!)        = ''              | ''                 | 'CS13303F903'           |'R0603'| '(SMR0603AW)'                  | '330'     | '1%'    | '1/10W'  | 'DISCRETE' | 'RES CHIP 330 1/10W +-1%(0603)YGO'                 | 'CHIPR0603'    | ''          | ''            | '20221019'
 '330'        | '1%'      | '1/10W'  | '0603LF'  | 'EMPTY'  | 'CS13303F903'(!)        = ''              | ''                 | 'CS13303F903'           |'R0603'| '(SMR0603AW)'                  | '330'     | '1%'    | '1/10W'  | 'IO'       | 'RES CHIP 330 1/10W +-1%(0603)YGO'                 | 'CHIPR0603'    | ''          | ''            | '20221019'
 '5.6'        | '1%'      | '1/16W'  | '0402LF'  | 'CHIP'   | 'CS-5602FB01'(!)        = ''              | ''                 | 'CS-5602FB01'           |'R0402'| '(R0402-0201)'                 | '5.6'     | '1%'    | '1/16W'  | 'DISCRETE' | 'RES CHIP 5.6 1/16W 1%(0402)EF'                    | 'CHIPR0402'    | ''          | ''            | '20221018'
 '5.6'        | '1%'      | '1/16W'  | '0402LF'  | 'EMPTY'  | 'CS-5602FB01'(!)        = ''              | ''                 | 'CS-5602FB01'           |'R0402'| '(R0402-0201)'                 | '5.6'     | '1%'    | '1/16W'  | 'IO'       | 'RES CHIP 5.6 1/16W 1%(0402)EF'                    | 'CHIPR0402'    | ''          | ''            | '20221018'
 '10K'        | '5%'      | '1/16W'  | '0402LF'  | 'CHIP'   | 'CS31002JB26'(!)        = ''              | ''                 | 'CS31002JB26'           |'R0402'| '(R0402-0201)'                 | '10K'     | '5%'    | '1/16W'  | 'DISCRETE' | 'RES CHIP 10K 1/16W 5%(0402)WTC'                   | 'CHIPR0402'    | ''          | ''            | '20221021'
 '10K'        | '5%'      | '1/16W'  | '0402LF'  | 'EMPTY'  | 'CS31002JB26'(!)        = ''              | ''                 | 'CS31002JB26'           |'R0402'| '(R0402-0201)'                 | '10K'     | '5%'    | '1/16W'  | 'IO'       | 'RES CHIP 10K 1/16W 5%(0402)WTC'                   | 'CHIPR0402'    | ''          | ''            | '20221021'
 '11K'        | '1%'      | '1/16W'  | '0402LF'  | 'CHIP'   | 'CS31102FB16'(!)        = ''              | ''                 | 'CS31102FB16'           |'R0402'| '(R0402-0201)'                 | '11K'     | '1%'    | '1/16W'  | 'DISCRETE' | 'RES CHIP 11K 1/16W +-1% (0402)WTC'                | 'CHIPR0402'    | ''          | ''            | '20221021'
 '11K'        | '1%'      | '1/16W'  | '0402LF'  | 'EMPTY'  | 'CS31102FB16'(!)        = ''              | ''                 | 'CS31102FB16'           |'R0402'| '(R0402-0201)'                 | '11K'     | '1%'    | '1/16W'  | 'IO'       | 'RES CHIP 11K 1/16W +-1% (0402)WTC'                | 'CHIPR0402'    | ''          | ''            | '20221021'
 '562K'       | '1%'      | '1/16W'  | '0402LF'  | 'CHIP'   | 'CS45622FB13'(!)        = ''              | ''                 | 'CS45622FB13'           |'R0402'| '(R0402-0201)'                 | '562K'    | '1%'    | '1/16W'  | 'DISCRETE' | 'RES CHIP 562K 1/16W +-1%(0402)WTC'                | 'CHIPR0402'    | ''          | ''            | '20221021'
 '562K'       | '1%'      | '1/16W'  | '0402LF'  | 'EMPTY'  | 'CS45622FB13'(!)        = ''              | ''                 | 'CS45622FB13'           |'R0402'| '(R0402-0201)'                 | '562K'    | '1%'    | '1/16W'  | 'IO'       | 'RES CHIP 562K 1/16W +-1%(0402)WTC'                | 'CHIPR0402'    | ''          | ''            | '20221021'
 '1M'         | '5%'      | '1/16W'  | '0402LF'  | 'CHIP'   | 'CS51002JB10'(!)        = ''              | ''                 | 'CS51002JB10'           |'R0402'| '(R0402-0201)'                 | '1M'      | '5%'    | '1/16W'  | 'DISCRETE' | 'RES CHIP 1M 1/16W +-5% (0402)WTC'                 | 'CHIPR0402'    | ''          | ''            | '20221021'
 '1M'         | '5%'      | '1/16W'  | '0402LF'  | 'EMPTY'  | 'CS51002JB10'(!)        = ''              | ''                 | 'CS51002JB10'           |'R0402'| '(R0402-0201)'                 | '1M'      | '5%'    | '1/16W'  | 'IO'       | 'RES CHIP 1M 1/16W +-5% (0402)WTC'                 | 'CHIPR0402'    | ''          | ''            | '20221021'
 '100'        | '1%'      | '1/16W'  | '0402LF'  | 'CHIP'   | 'CS11002FB29'(!)        = ''              | ''                 | 'CS11002FB29'           |'R0402'| '(R0402-0201)'                 | '100'     | '1%'    | '1/16W'  | 'DISCRETE' | 'RES CHIP 100 1/16W +-1%(0402)WTC'                 | 'CHIPR0402'    | ''          | ''            | '20221021'
 '100'        | '1%'      | '1/16W'  | '0402LF'  | 'EMPTY'  | 'CS11002FB29'(!)        = ''              | ''                 | 'CS11002FB29'           |'R0402'| '(R0402-0201)'                 | '100'     | '1%'    | '1/16W'  | 'IO'       | 'RES CHIP 100 1/16W +-1%(0402)WTC'                 | 'CHIPR0402'    | ''          | ''            | '20221021'
 '220'        | '5%'      | '1/16W'  | '0402LF'  | 'CHIP'   | 'CS12202JB11'(!)        = ''              | ''                 | 'CS12202JB11'           |'R0402'| '(R0402-0201)'                 | '220'     | '5%'    | '1/16W'  | 'DISCRETE' | 'RES CHIP 220 1/16W +-5%(0402)WTC'                 | 'CHIPR0402'    | ''          | ''            | '20221021'
 '220'        | '5%'      | '1/16W'  | '0402LF'  | 'EMPTY'  | 'CS12202JB11'(!)        = ''              | ''                 | 'CS12202JB11'           |'R0402'| '(R0402-0201)'                 | '220'     | '5%'    | '1/16W'  | 'IO'       | 'RES CHIP 220 1/16W +-5%(0402)WTC'                 | 'CHIPR0402'    | ''          | ''            | '20221021'
 '2.7K'       | '5%'      | '1/16W'  | '0402LF'  | 'CHIP'   | 'CS22702JB09'(!)        = ''              | ''                 | 'CS22702JB09'           |'R0402'| '(R0402-0201)'                 | '2.7K'    | '5%'    | '1/16W'  | 'DISCRETE' | 'RES CHIP 2.7K 1/16W +-5%(0402)WTC'                | 'CHIPR0402'    | ''          | ''            | '20221021'
 '2.7K'       | '5%'      | '1/16W'  | '0402LF'  | 'EMPTY'  | 'CS22702JB09'(!)        = ''              | ''                 | 'CS22702JB09'           |'R0402'| '(R0402-0201)'                 | '2.7K'    | '5%'    | '1/16W'  | 'IO'       | 'RES CHIP 2.7K 1/16W +-5%(0402)WTC'                | 'CHIPR0402'    | ''          | ''            | '20221021'
 '100'        | '5%'      | '1/16W'  | '0402LF'  | 'CHIP'   | 'CS11002JB19'(!)        = ''              | ''                 | 'CS11002JB19'           |'R0402'| '(R0402-0201)'                 | '100'     | '5%'    | '1/16W'  | 'DISCRETE' | 'RES CHIP 100 1/16W +-5%(0402)EF YGO'              | 'CHIPR0402'    | ''          | ''            | '20221024'
 '100'        | '5%'      | '1/16W'  | '0402LF'  | 'EMPTY'  | 'CS11002JB19'(!)        = ''              | ''                 | 'CS11002JB19'           |'R0402'| '(R0402-0201)'                 | '100'     | '5%'    | '1/16W'  | 'IO'       | 'RES CHIP 100 1/16W +-5%(0402)EF YGO'              | 'CHIPR0402'    | ''          | ''            | '20221024'
 '100'        | '5%'      | '1/16W'  | '0402LF'  | 'CHIP'   | 'CS11002JB18'(!)        = ''              | ''                 | 'CS11002JB18'           |'R0402'| '(R0402-0201)'                 | '100'     | '5%'    | '1/16W'  | 'DISCRETE' | 'RES CHIP 100 1/16W +-5%(0402)EF WTC'              | 'CHIPR0402'    | ''          | ''            | '20221024'
 '100'        | '5%'      | '1/16W'  | '0402LF'  | 'EMPTY'  | 'CS11002JB18'(!)        = ''              | ''                 | 'CS11002JB18'           |'R0402'| '(R0402-0201)'                 | '100'     | '5%'    | '1/16W'  | 'IO'       | 'RES CHIP 100 1/16W +-5%(0402)EF WTC'              | 'CHIPR0402'    | ''          | ''            | '20221024'
 '22'         | '1%'      | '1/16W'  | '0402LF'  | 'CHIP'   | 'CS02202FB10'(!)        = ''              | ''                 | 'CS02202FB10'           |'R0402'| '(R0402-0201)'                 | '22'      | '1%'    | '1/16W'  | 'DISCRETE' | 'RES CHIP 22 1/16W +-1%(0402)WTC'                  | 'CHIPR0402'    | ''          | ''            | '20221024'
 '22'         | '1%'      | '1/16W'  | '0402LF'  | 'EMPTY'  | 'CS02202FB10'(!)        = ''              | ''                 | 'CS02202FB10'           |'R0402'| '(R0402-0201)'                 | '22'      | '1%'    | '1/16W'  | 'IO'       | 'RES CHIP 22 1/16W +-1%(0402)WTC'                  | 'CHIPR0402'    | ''          | ''            | '20221024'
 '22'         | '1%'      | '1/16W'  | '0402LF'  | 'CHIP'   | 'CS02202FB11'(!)        = ''              | ''                 | 'CS02202FB11'           |'R0402'| '(R0402-0201)'                 | '22'      | '1%'    | '1/16W'  | 'DISCRETE' | 'RES CHIP 22 1/16W +-1%(0402)YGO'                  | 'CHIPR0402'    | ''          | ''            | '20221024'
 '22'         | '1%'      | '1/16W'  | '0402LF'  | 'EMPTY'  | 'CS02202FB11'(!)        = ''              | ''                 | 'CS02202FB11'           |'R0402'| '(R0402-0201)'                 | '22'      | '1%'    | '1/16W'  | 'IO'       | 'RES CHIP 22 1/16W +-1%(0402)YGO'                  | 'CHIPR0402'    | ''          | ''            | '20221024'
 '69.8K'      | '1%'      | '1/16W'  | '0402LF'  | 'CHIP'   | 'CS36982FB10'(!)        = ''              | ''                 | 'CS36982FB10'           |'R0402'| '(R0402-0201)'                 | '69.8K'   | '1%'    | '1/16W'  | 'DISCRETE' | 'RES CHIP 69.8K 1/16W +-1% (0402)YGO'              | 'CHIPR0402'    | ''          | ''            | '20221024'
 '69.8K'      | '1%'      | '1/16W'  | '0402LF'  | 'EMPTY'  | 'CS36982FB10'(!)        = ''              | ''                 | 'CS36982FB10'           |'R0402'| '(R0402-0201)'                 | '69.8K'   | '1%'    | '1/16W'  | 'IO'       | 'RES CHIP 69.8K 1/16W +-1% (0402)YGO'              | 'CHIPR0402'    | ''          | ''            | '20221024'
 '47.5K'      | '1%'      | '1/16W'  | '0402LF'  | 'CHIP'   | 'CS34752FB11'(!)        = ''              | ''                 | 'CS34752FB11'           |'R0402'| '(R0402-0201)'                 | '47.5K'   | '1%'    | '1/16W'  | 'DISCRETE' | 'RES CHIP 47.5K 1/16W +-1% (0402)WTC'              | 'CHIPR0402'    | ''          | ''            | '20221025'
 '47.5K'      | '1%'      | '1/16W'  | '0402LF'  | 'EMPTY'  | 'CS34752FB11'(!)        = ''              | ''                 | 'CS34752FB11'           |'R0402'| '(R0402-0201)'                 | '47.5K'   | '1%'    | '1/16W'  | 'IO'       | 'RES CHIP 47.5K 1/16W +-1% (0402)WTC'              | 'CHIPR0402'    | ''          | ''            | '20221025'
 '10.5K'      | '1%'      | '1/16W'  | '0402LF'  | 'CHIP'   | 'CS31052FB07'(!)        = ''              | ''                 | 'CS31052FB07'           |'R0402'| '(R0402-0201)'                 | '10.5K'   | '1%'    | '1/16W'  | 'DISCRETE' | 'RES CHIP 10.5K 1/16W +-1%( 0402)YGO'              | 'CHIPR0402'    | ''          | ''            | '20221025'
 '10.5K'      | '1%'      | '1/16W'  | '0402LF'  | 'EMPTY'  | 'CS31052FB07'(!)        = ''              | ''                 | 'CS31052FB07'           |'R0402'| '(R0402-0201)'                 | '10.5K'   | '1%'    | '1/16W'  | 'IO'       | 'RES CHIP 10.5K 1/16W +-1%( 0402)YGO'              | 'CHIPR0402'    | ''          | ''            | '20221025'
 '1'          | '5%'      | '1/16W'  | '0402LF'  | 'CHIP'   | 'CS-1002JB16'(!)        = ''              | ''                 | 'CS-1002JB16'           |'R0402'| '(R0402-0201)'                 | '1'       | '5%'    | '1/16W'  | 'DISCRETE' | 'RES CHIP 1 1/16W +-5%(0402)WTC'                   | 'CHIPR0402'    | ''          | ''            | '20221025'
 '1'          | '5%'      | '1/16W'  | '0402LF'  | 'EMPTY'  | 'CS-1002JB16'(!)        = ''              | ''                 | 'CS-1002JB16'           |'R0402'| '(R0402-0201)'                 | '1'       | '5%'    | '1/16W'  | 'IO'       | 'RES CHIP 1 1/16W +-5%(0402)WTC'                   | 'CHIPR0402'    | ''          | ''            | '20221025'
 '1K'         | '5%'      | '1/16W'  | '0402LF'  | 'CHIP'   | 'CS21002JB27'(!)        = ''              | ''                 | 'CS21002JB27'           |'R0402'| '(R0402-0201)'                 | '1K'      | '5%'    | '1/16W'  | 'DISCRETE' | 'RES CHIP 1K 1/16W 5%(0402) YGO'                   | 'CHIPR0402'    | ''          | ''            | '20221017'
 '1K'         | '5%'      | '1/16W'  | '0402LF'  | 'EMPTY'  | 'CS21002JB27'(!)        = ''              | ''                 | 'CS21002JB27'           |'R0402'| '(R0402-0201)'                 | '1K'      | '5%'    | '1/16W'  | 'IO'       | 'RES CHIP 1K 1/16W 5%(0402) YGO'                   | 'CHIPR0402'    | ''          | ''            | '20221017'
 '4.7K'       | '5%'      | '1/16W'  | '0402LF'  | 'CHIP'   | 'CS24702JB19'(!)        = ''              | ''                 | 'CS24702JB19'           |'R0402'| '(R0402-0201)'                 | '4.7K'    | '5%'    | '1/16W'  | 'DISCRETE' | 'RES CHIP 4.7K 1/16W +-5% (0402)YGO'               | 'CHIPR0402'    | ''          | ''            | '20221103'
 '4.7K'       | '5%'      | '1/16W'  | '0402LF'  | 'EMPTY'  | 'CS24702JB19'(!)        = ''              | ''                 | 'CS24702JB19'           |'R0402'| '(R0402-0201)'                 | '4.7K'    | '5%'    | '1/16W'  | 'IO'       | 'RES CHIP 4.7K 1/16W +-5% (0402)YGO'               | 'CHIPR0402'    | ''          | ''            | '20221103'
 '1K'         | '1%'      | '1/16W'  | '0402LF'  | 'CHIP'   | 'CS21002FB28'(!)        = ''              | ''                 | 'CS21002FB28'           |'R0402'| '(R0402-0201)'                 | '1K'      | '1%'    | '1/16W'  | 'DISCRETE' | 'RES CHIP 1K 1/16W +-1% (0402)YGO'                 | 'CHIPR0402'    | ''          | ''            | '20221103'
 '1K'         | '1%'      | '1/16W'  | '0402LF'  | 'EMPTY'  | 'CS21002FB28'(!)        = ''              | ''                 | 'CS21002FB28'           |'R0402'| '(R0402-0201)'                 | '1K'      | '1%'    | '1/16W'  | 'IO'       | 'RES CHIP 1K 1/16W +-1% (0402)YGO'                 | 'CHIPR0402'    | ''          | ''            | '20221103'
 '10K'        | '1%'      | '1/16W'  | '0402LF'  | 'CHIP'   | 'CS31002FB28'(!)        = ''              | ''                 | 'CS31002FB28'           |'R0402'| '(R0402-0201)'                 | '10K'     | '1%'    | '1/16W'  | 'DISCRETE' | 'RES CHIP 10K 1/16W +-1% (0402)YGO'                | 'CHIPR0402'    | ''          | ''            | '20221103'
 '10K'        | '1%'      | '1/16W'  | '0402LF'  | 'EMPTY'  | 'CS31002FB28'(!)        = ''              | ''                 | 'CS31002FB28'           |'R0402'| '(R0402-0201)'                 | '10K'     | '1%'    | '1/16W'  | 'IO'       | 'RES CHIP 10K 1/16W +-1% (0402)YGO'                | 'CHIPR0402'    | ''          | ''            | '20221103'
 '15.4K'      | '1%'      | '1/16W'  | '0402LF'  | 'CHIP'   | 'CS31542FB10'(!)        = ''              | ''                 | 'CS31542FB10'           |'R0402'| '(R0402-0201)'                 | '15.4K'   | '1%'    | '1/16W'  | 'DISCRETE' | 'RES CHIP 15.4K 1/16W +-1%(0402)WTC'               | 'CHIPR0402'    | ''          | ''            | '20221114'
 '15.4K'      | '1%'      | '1/16W'  | '0402LF'  | 'EMPTY'  | 'CS31542FB10'(!)        = ''              | ''                 | 'CS31542FB10'           |'R0402'| '(R0402-0201)'                 | '15.4K'   | '1%'    | '1/16W'  | 'IO'       | 'RES CHIP 15.4K 1/16W +-1%(0402)WTC'               | 'CHIPR0402'    | ''          | ''            | '20221114'
 '20M'        | '5%'      | '1/16W'  | '0402LF'  | 'CHIP'   | 'CS62002JB03'(!)        = ''              | ''                 | 'CS62002JB03'           |'R0402'| '(R0402-0201)'                 | '20M'     | '5%'    | '1/16W'  | 'DISCRETE' | 'RES CHIP 20M 1/16W +-5%(0402)WTC'                 | 'CHIPR0402'    | ''          | ''            | '20221114'
 '20M'        | '5%'      | '1/16W'  | '0402LF'  | 'EMPTY'  | 'CS62002JB03'(!)        = ''              | ''                 | 'CS62002JB03'           |'R0402'| '(R0402-0201)'                 | '20M'     | '5%'    | '1/16W'  | 'IO'       | 'RES CHIP 20M 1/16W +-5%(0402)WTC'                 | 'CHIPR0402'    | ''          | ''            | '20221114'
 '2K'         | '5%'      | '1/16W'  | '0402LF'  | 'CHIP'   | 'CS22002JB09'(!)        = ''              | ''                 | 'CS22002JB09'           |'R0402'| '(R0402-0201)'                 | '2K'      | '5%'    | '1/16W'  | 'DISCRETE' | 'RES CHIP 2K 1/16W +-5% 0402)WTC'                  | 'CHIPR0402'    | ''          | ''            | '20221114'
 '2K'         | '5%'      | '1/16W'  | '0402LF'  | 'EMPTY'  | 'CS22002JB09'(!)        = ''              | ''                 | 'CS22002JB09'           |'R0402'| '(R0402-0201)'                 | '2K'      | '5%'    | '1/16W'  | 'IO'       | 'RES CHIP 2K 1/16W +-5% 0402)WTC'                  | 'CHIPR0402'    | ''          | ''            | '20221114'
 '8.2K'       | '5%'      | '1/16W'  | '0402LF'  | 'CHIP'   | 'CS28202JB10'(!)        = ''              | ''                 | 'CS28202JB10'           |'R0402'| '(R0402-0201)'                 | '8.2K'    | '5%'    | '1/16W'  | 'DISCRETE' | 'RES CHIP 8.2K 1/16W +-5% (0402)WTC'               | 'CHIPR0402'    | ''          | ''            | '20221114'
 '8.2K'       | '5%'      | '1/16W'  | '0402LF'  | 'EMPTY'  | 'CS28202JB10'(!)        = ''              | ''                 | 'CS28202JB10'           |'R0402'| '(R0402-0201)'                 | '8.2K'    | '5%'    | '1/16W'  | 'IO'       | 'RES CHIP 8.2K 1/16W +-5% (0402)WTC'               | 'CHIPR0402'    | ''          | ''            | '20221114'
 '12.1K'      | '1%'      | '1/16W'  | '0402LF'  | 'CHIP'   | 'CS31212FB12'(!)        = ''              | ''                 | 'CS31212FB12'           |'R0402'| '(R0402-0201)'                 | '12.1K'   | '1%'    | '1/16W'  | 'DISCRETE' | 'RES CHIP 12.1K 1/16W +-1%(0402)WTC'               | 'CHIPR0402'    | ''          | ''            | '20221114'
 '12.1K'      | '1%'      | '1/16W'  | '0402LF'  | 'EMPTY'  | 'CS31212FB12'(!)        = ''              | ''                 | 'CS31212FB12'           |'R0402'| '(R0402-0201)'                 | '12.1K'   | '1%'    | '1/16W'  | 'IO'       | 'RES CHIP 12.1K 1/16W +-1%(0402)WTC'               | 'CHIPR0402'    | ''          | ''            | '20221114'
 '20K'        | '1%'      | '1/16W'  | '0402LF'  | 'CHIP'   | 'CS32002FB25'(!)        = ''              | ''                 | 'CS32002FB25'           |'R0402'| '(R0402-0201)'                 | '20K'     | '1%'    | '1/16W'  | 'DISCRETE' | 'RES CHIP 20K 1/16W +-1%(0402)WTC'                 | 'CHIPR0402'    | ''          | ''            | '20221114'
 '20K'        | '1%'      | '1/16W'  | '0402LF'  | 'EMPTY'  | 'CS32002FB25'(!)        = ''              | ''                 | 'CS32002FB25'           |'R0402'| '(R0402-0201)'                 | '20K'     | '1%'    | '1/16W'  | 'IO'       | 'RES CHIP 20K 1/16W +-1%(0402)WTC'                 | 'CHIPR0402'    | ''          | ''            | '20221114'
 '25.5K'      | '1%'      | '1/16W'  | '0402LF'  | 'CHIP'   | 'CS32552FB13'(!)        = ''              | ''                 | 'CS32552FB13'           |'R0402'| '(R0402-0201)'                 | '25.5K'   | '1%'    | '1/16W'  | 'DISCRETE' | 'RES CHIP 25.5K 1/16W +-1%(0402)WTC'               | 'CHIPR0402'    | ''          | ''            | '20221114'
 '25.5K'      | '1%'      | '1/16W'  | '0402LF'  | 'EMPTY'  | 'CS32552FB13'(!)        = ''              | ''                 | 'CS32552FB13'           |'R0402'| '(R0402-0201)'                 | '25.5K'   | '1%'    | '1/16W'  | 'IO'       | 'RES CHIP 25.5K 1/16W +-1%(0402)WTC'               | 'CHIPR0402'    | ''          | ''            | '20221114'
 '86.6K'      | '1%'      | '1/16W'  | '0402LF'  | 'CHIP'   | 'CS38662FB07'(!)        = ''              | ''                 | 'CS38662FB07'           |'R0402'| '(R0402-0201)'                 | '86.6K'   | '1%'    | '1/16W'  | 'DISCRETE' | 'RES CHIP 86.6K 1/16W +-1% (0402)WTC'              | 'CHIPR0402'    | ''          | ''            | '20221114'
 '86.6K'      | '1%'      | '1/16W'  | '0402LF'  | 'EMPTY'  | 'CS38662FB07'(!)        = ''              | ''                 | 'CS38662FB07'           |'R0402'| '(R0402-0201)'                 | '86.6K'   | '1%'    | '1/16W'  | 'IO'       | 'RES CHIP 86.6K 1/16W +-1% (0402)WTC'              | 'CHIPR0402'    | ''          | ''            | '20221114'
 '1'          | '1%'      | '1/10W'  | '0603LF'  | 'CHIP'   | 'CS-1003F907'(!)        = ''              | ''                 | 'CS-1003F907'           |'R0603_H24'| '(SMR0603AW)'                  | '1'       | '1%'    | '1/10W'  | 'DISCRETE' | 'RES CHIP 1 1/10W +-1%(0603)WTC'                   | 'CHIPR0603'    | ''          | ''            | '20221114'
 '1'          | '1%'      | '1/10W'  | '0603LF'  | 'EMPTY'  | 'CS-1003F907'(!)        = ''              | ''                 | 'CS-1003F907'           |'R0603_H24'| '(SMR0603AW)'                  | '1'       | '1%'    | '1/10W'  | 'IO'       | 'RES CHIP 1 1/10W +-1%(0603)WTC'                   | 'CHIPR0603'    | ''          | ''            | '20221114'
 '2.2K'       | '5%'      | '1/16W'  | '0402LF'  | 'CHIP'   | 'CS22202JB26'(!)        = ''              | ''                 | 'CS22202JB26'           |'R0402'| '(R0402-0201)'                 | '2.2K'    | '5%'    | '1/16W'  | 'DISCRETE' | 'RES CHIP 2.2K 1/16W +-5%(0402)WTC'                | 'CHIPR0402'    | ''          | ''            | '20221115'
 '2.2K'       | '5%'      | '1/16W'  | '0402LF'  | 'EMPTY'  | 'CS22202JB26'(!)        = ''              | ''                 | 'CS22202JB26'           |'R0402'| '(R0402-0201)'                 | '2.2K'    | '5%'    | '1/16W'  | 'IO'       | 'RES CHIP 2.2K 1/16W +-5%(0402)WTC'                | 'CHIPR0402'    | ''          | ''            | '20221115'
 '12.7K'      | '1%'      | '1/16W'  | '0402LF'  | 'CHIP'   | 'CS31272FB11'(!)        = ''              | ''                 | 'CS31272FB11'           |'R0402'| '(R0402-0201)'                 | '12.7K'   | '1%'    | '1/16W'  | 'DISCRETE' | 'RES CHIP 12.7K 1/16W +-1% (0402)WTC'              | 'CHIPR0402'    | ''          | ''            | '20221125'
 '12.7K'      | '1%'      | '1/16W'  | '0402LF'  | 'EMPTY'  | 'CS31272FB11'(!)        = ''              | ''                 | 'CS31272FB11'           |'R0402'| '(R0402-0201)'                 | '12.7K'   | '1%'    | '1/16W'  | 'IO'       | 'RES CHIP 12.7K 1/16W +-1% (0402)WTC'              | 'CHIPR0402'    | ''          | ''            | '20221125'
 '82K'        | '1%'      | '1/16W'  | '0402LF'  | 'CHIP'   | 'CS38202FB05'(!)        = ''              | ''                 | 'CS38202FB05'           |'R0402'| '(R0402-0201)'                 | '82K'     | '1%'    | '1/16W'  | 'DISCRETE' | 'RES CHIP 82K  1/16W +-1% (0402)WTC'               | 'CHIPR0402'    | ''          | ''            | '20221125'
 '82K'        | '1%'      | '1/16W'  | '0402LF'  | 'EMPTY'  | 'CS38202FB05'(!)        = ''              | ''                 | 'CS38202FB05'           |'R0402'| '(R0402-0201)'                 | '82K'     | '1%'    | '1/16W'  | 'IO'       | 'RES CHIP 82K  1/16W +-1% (0402)WTC'               | 'CHIPR0402'    | ''          | ''            | '20221125'
 '3.3K'       | '5%'      | '1/16W'  | '0402LF'  | 'CHIP'   | 'CS23302JB11'(!)        = ''              | ''                 | 'CS23302JB11'           |'R0402'| '(R0402-0201)'                 | '3.3K'    | '5%'    | '1/16W'  | 'DISCRETE' | 'RES CHIP 3.3K 1/16W +-5%(0402)WTC'                | 'CHIPR0402'    | ''          | ''            | '20221125'
 '3.3K'       | '5%'      | '1/16W'  | '0402LF'  | 'EMPTY'  | 'CS23302JB11'(!)        = ''              | ''                 | 'CS23302JB11'           |'R0402'| '(R0402-0201)'                 | '3.3K'    | '5%'    | '1/16W'  | 'IO'       | 'RES CHIP 3.3K 1/16W +-5%(0402)WTC'                | 'CHIPR0402'    | ''          | ''            | '20221125'
 '3.9K'       | '1%'      | '1/16W'  | '0402LF'  | 'CHIP'   | 'CS23902FB09'(!)        = ''              | ''                 | 'CS23902FB09'           |'R0402'| '(R0402-0201)'                 | '3.9K'    | '1%'    | '1/16W'  | 'DISCRETE' | 'RES CHIP 3.9K 1/16W+-1%(0402)WTC'                 | 'CHIPR0402'    | ''          | ''            | '20221125'
 '3.9K'       | '1%'      | '1/16W'  | '0402LF'  | 'EMPTY'  | 'CS23902FB09'(!)        = ''              | ''                 | 'CS23902FB09'           |'R0402'| '(R0402-0201)'                 | '3.9K'    | '1%'    | '1/16W'  | 'IO'       | 'RES CHIP 3.9K 1/16W+-1%(0402)WTC'                 | 'CHIPR0402'    | ''          | ''            | '20221125'
 '8.06K'      | '1%'      | '1/16W'  | '0402LF'  | 'CHIP'   | 'CS28062FB13'(!)        = ''              | ''                 | 'CS28062FB13'           |'R0402'| '(R0402-0201)'                 | '8.06K'   | '1%'    | '1/16W'  | 'DISCRETE' | 'RES CHIP 8.06K 1/16W +-1%(0402)WTC'               | 'CHIPR0402'    | ''          | ''            | '20221125'
 '8.06K'      | '1%'      | '1/16W'  | '0402LF'  | 'EMPTY'  | 'CS28062FB13'(!)        = ''              | ''                 | 'CS28062FB13'           |'R0402'| '(R0402-0201)'                 | '8.06K'   | '1%'    | '1/16W'  | 'IO'       | 'RES CHIP 8.06K 1/16W +-1%(0402)WTC'               | 'CHIPR0402'    | ''          | ''            | '20221125'
 '8.25K'      | '1%'      | '1/16W'  | '0402LF'  | 'CHIP'   | 'CS28252FB13'(!)        = ''              | ''                 | 'CS28252FB13'           |'R0402'| '(R0402-0201)'                 | '8.25K'   | '1%'    | '1/16W'  | 'DISCRETE' | 'RES CHIP 8.25K 1/16W+-1%(0402)WTC'                | 'CHIPR0402'    | ''          | ''            | '20221125'
 '8.25K'      | '1%'      | '1/16W'  | '0402LF'  | 'EMPTY'  | 'CS28252FB13'(!)        = ''              | ''                 | 'CS28252FB13'           |'R0402'| '(R0402-0201)'                 | '8.25K'   | '1%'    | '1/16W'  | 'IO'       | 'RES CHIP 8.25K 1/16W+-1%(0402)WTC'                | 'CHIPR0402'    | ''          | ''            | '20221125'
 '9.09K'      | '1%'      | '1/16W'  | '0402LF'  | 'CHIP'   | 'CS29092FB11'(!)        = ''              | ''                 | 'CS29092FB11'           |'R0402'| '(R0402-0201)'                 | '9.09K'   | '1%'    | '1/16W'  | 'DISCRETE' | 'RES CHIP 9.09K 1/16W +-1%(0402)WTC'               | 'CHIPR0402'    | ''          | ''            | '20221125'
 '9.09K'      | '1%'      | '1/16W'  | '0402LF'  | 'EMPTY'  | 'CS29092FB11'(!)        = ''              | ''                 | 'CS29092FB11'           |'R0402'| '(R0402-0201)'                 | '9.09K'   | '1%'    | '1/16W'  | 'IO'       | 'RES CHIP 9.09K 1/16W +-1%(0402)WTC'               | 'CHIPR0402'    | ''          | ''            | '20221125'
 '9.31K'      | '1%'      | '1/16W'  | '0402LF'  | 'CHIP'   | 'CS29312FB09'(!)        = ''              | ''                 | 'CS29312FB09'           |'R0402'| '(R0402-0201)'                 | '9.31K'   | '1%'    | '1/16W'  | 'DISCRETE' | 'RES CHIP 9.31K 1/16W +-1%(0402)WTC'               | 'CHIPR0402'    | ''          | ''            | '20221125'
 '9.31K'      | '1%'      | '1/16W'  | '0402LF'  | 'EMPTY'  | 'CS29312FB09'(!)        = ''              | ''                 | 'CS29312FB09'           |'R0402'| '(R0402-0201)'                 | '9.31K'   | '1%'    | '1/16W'  | 'IO'       | 'RES CHIP 9.31K 1/16W +-1%(0402)WTC'               | 'CHIPR0402'    | ''          | ''            | '20221125'
 '11.5K'      | '1%'      | '1/16W'  | '0402LF'  | 'CHIP'   | 'CS31152FB12'(!)        = ''              | ''                 | 'CS31152FB12'           |'R0402'| '(R0402-0201)'                 | '11.5K'   | '1%'    | '1/16W'  | 'DISCRETE' | 'RES CHIP 11.5K 1/16W +-1%( 0402)WTC'              | 'CHIPR0402'    | ''          | ''            | '20221125'
 '11.5K'      | '1%'      | '1/16W'  | '0402LF'  | 'EMPTY'  | 'CS31152FB12'(!)        = ''              | ''                 | 'CS31152FB12'           |'R0402'| '(R0402-0201)'                 | '11.5K'   | '1%'    | '1/16W'  | 'IO'       | 'RES CHIP 11.5K 1/16W +-1%( 0402)WTC'              | 'CHIPR0402'    | ''          | ''            | '20221125'
 '56K'        | '1%'      | '1/16W'  | '0402LF'  | 'CHIP'   | 'CS35602FB07'(!)        = ''              | ''                 | 'CS35602FB07'           |'R0402'| '(R0402-0201)'                 | '56K'     | '1%'    | '1/16W'  | 'DISCRETE' | 'RES CHIP 56K 1/16W +-1%(0402)WTC'                 | 'CHIPR0402'    | ''          | ''            | '20221125'
 '56K'        | '1%'      | '1/16W'  | '0402LF'  | 'EMPTY'  | 'CS35602FB07'(!)        = ''              | ''                 | 'CS35602FB07'           |'R0402'| '(R0402-0201)'                 | '56K'     | '1%'    | '1/16W'  | 'IO'       | 'RES CHIP 56K 1/16W +-1%(0402)WTC'                 | 'CHIPR0402'    | ''          | ''            | '20221125'
 '68.1K'      | '1%'      | '1/16W'  | '0402LF'  | 'CHIP'   | 'CS36812FB09'(!)        = ''              | ''                 | 'CS36812FB09'           |'R0402'| '(R0402-0201)'                 | '68.1K'   | '1%'    | '1/16W'  | 'DISCRETE' | 'RES CHIP 68.1K 1/16W +-1%(0402)WTC'               | 'CHIPR0402'    | ''          | ''            | '20221125'
 '68.1K'      | '1%'      | '1/16W'  | '0402LF'  | 'EMPTY'  | 'CS36812FB09'(!)        = ''              | ''                 | 'CS36812FB09'           |'R0402'| '(R0402-0201)'                 | '68.1K'   | '1%'    | '1/16W'  | 'IO'       | 'RES CHIP 68.1K 1/16W +-1%(0402)WTC'               | 'CHIPR0402'    | ''          | ''            | '20221125'
 '4.99K'      | '1%'      | '1/16W'  | '0402LF'  | 'CHIP'   | 'CS24992FB17'(!)        = ''              | ''                 | 'CS24992FB17'           |'R0402'| '(R0402-0201)'                 | '4.99K'   | '1%'    | '1/16W'  | 'DISCRETE' | 'RES CHIP 4.99K 1/16W +-1% (0402)WTC'              | 'CHIPR0402'    | ''          | ''            | '20221125'
 '4.99K'      | '1%'      | '1/16W'  | '0402LF'  | 'EMPTY'  | 'CS24992FB17'(!)        = ''              | ''                 | 'CS24992FB17'           |'R0402'| '(R0402-0201)'                 | '4.99K'   | '1%'    | '1/16W'  | 'IO'       | 'RES CHIP 4.99K 1/16W +-1% (0402)WTC'              | 'CHIPR0402'    | ''          | ''            | '20221125'
 '402'        | '1%'      | '1/16W'  | '0402LF'  | 'CHIP'   | 'CS14022FB14'(!)        = ''              | ''                 | 'CS14022FB14'           |'R0402'| '(R0402-0201)'                 | '402'     | '1%'    | '1/16W'  | 'DISCRETE' | 'RES CHIP 402 1/16W +-1%( 0402)WTC'                | 'CHIPR0402'    | ''          | ''            | '20221129'
 '402'        | '1%'      | '1/16W'  | '0402LF'  | 'EMPTY'  | 'CS14022FB14'(!)        = ''              | ''                 | 'CS14022FB14'           |'R0402'| '(R0402-0201)'                 | '402'     | '1%'    | '1/16W'  | 'IO'       | 'RES CHIP 402 1/16W +-1%( 0402)WTC'                | 'CHIPR0402'    | ''          | ''            | '20221129'
 '150K'       | '1%'      | '1/16W'  | '0402LF'  | 'CHIP'   | 'CS41502FB16'(!)        = ''              | ''                 | 'CS41502FB16'           |'R0402'| '(R0402-0201)'                 | '150K'    | '1%'    | '1/16W'  | 'DISCRETE' | 'RES CHIP 150K 1/16W +-1%(0402)WTC'                | 'CHIPR0402'    | ''          | ''            | '20221129'
 '150K'       | '1%'      | '1/16W'  | '0402LF'  | 'EMPTY'  | 'CS41502FB16'(!)        = ''              | ''                 | 'CS41502FB16'           |'R0402'| '(R0402-0201)'                 | '150K'    | '1%'    | '1/16W'  | 'IO'       | 'RES CHIP 150K 1/16W +-1%(0402)WTC'                | 'CHIPR0402'    | ''          | ''            | '20221129'
 '442'        | '1%'      | '1/16W'  | '0402LF'  | 'CHIP'   | 'CS14422FB03'(!)        = ''              | ''                 | 'CS14422FB03'           |'R0402'| '(R0402-0201)'                 | '442'     | '1%'    | '1/16W'  | 'DISCRETE' | 'RES CHIP 442 1/16W +-1% (0402)YGO'                | 'CHIPR0402'    | ''          | ''            | '20221129'
 '442'        | '1%'      | '1/16W'  | '0402LF'  | 'EMPTY'  | 'CS14422FB03'(!)        = ''              | ''                 | 'CS14422FB03'           |'R0402'| '(R0402-0201)'                 | '442'     | '1%'    | '1/16W'  | 'IO'       | 'RES CHIP 442 1/16W +-1% (0402)YGO'                | 'CHIPR0402'    | ''          | ''            | '20221129'
 '2K'         | '1%'      | '1/16W'  | '0402LF'  | 'CHIP'   | 'CS22002FB15'(!)        = ''              | ''                 | 'CS22002FB15'           |'R0402'| '(R0402-0201)'                 | '2K'      | '1%'    | '1/16W'  | 'DISCRETE' | 'RES CHIP 2K 1/16W +-1%(0402)WTC'                  | 'CHIPR0402'    | ''          | ''            | '20221129'
 '2K'         | '1%'      | '1/16W'  | '0402LF'  | 'EMPTY'  | 'CS22002FB15'(!)        = ''              | ''                 | 'CS22002FB15'           |'R0402'| '(R0402-0201)'                 | '2K'      | '1%'    | '1/16W'  | 'IO'       | 'RES CHIP 2K 1/16W +-1%(0402)WTC'                  | 'CHIPR0402'    | ''          | ''            | '20221129'
 '0.003'      | '1%'      | '3W'     | '2512LF'  | 'CHIP'   | 'CS+003DFR04'(!)        = ''              | ''                 | 'CS+003DFR04'           |'R2512XF'| '(SMR2512AW)'                  | '0.003'   | '1%'    | '3W'     | 'DISCRETE' | 'RES CHIP 0.003 3W +-1%(2512)TAI'                  | 'CHIPR2512'    | ''          | ''            | '20221201'
 '0.003'      | '1%'      | '3W'     | '2512LF'  | 'EMPTY'  | 'CS+003DFR04'(!)        = ''              | ''                 | 'CS+003DFR04'           |'R2512XF'| '(SMR2512AW)'                  | '0.003'   | '1%'    | '3W'     | 'IO'       | 'RES CHIP 0.003 3W +-1%(2512)TAI'                  | 'CHIPR2512'    | ''          | ''            | '20221201'
 '200'        | '1%'      | '1/20W'  | '0201LF'  | 'CHIP'   | 'CS12001FE12'(!)        = ''              | ''                 | 'CS12001FE12'           |'R0201'| '(SMR0201AW)'                  | '200'     | '1%'    | '1/20W'  | 'DISCRETE' | 'RES CHIP 200 1/20W +-1%(0201)EF'                  | 'CHIPR0201'    | ''          | ''            | '20221202'
 '200'        | '1%'      | '1/20W'  | '0201LF'  | 'EMPTY'  | 'CS12001FE12'(!)        = ''              | ''                 | 'CS12001FE12'           |'R0201'| '(SMR0201AW)'                  | '200'     | '1%'    | '1/20W'  | 'IO'       | 'RES CHIP 200 1/20W +-1%(0201)EF'                  | 'CHIPR0201'    | ''          | ''            | '20221202'
 '33.2'       | '1%'      | '1/20W'  | '0201LF'  | 'CHIP'   | 'CS03321FE09'(!)        = ''              | ''                 | 'CS03321FE09'           |'R0201'| '(SMR0201AW)'                  | '33.2'    | '1%'    | '1/20W'  | 'DISCRETE' | 'RES CHIP 33.2 1/20W +-1%(0201)EF'                 | 'CHIPR0201'    | ''          | ''            | '20221202'
 '33.2'       | '1%'      | '1/20W'  | '0201LF'  | 'EMPTY'  | 'CS03321FE09'(!)        = ''              | ''                 | 'CS03321FE09'           |'R0201'| '(SMR0201AW)'                  | '33.2'    | '1%'    | '1/20W'  | 'IO'       | 'RES CHIP 33.2 1/20W +-1%(0201)EF'                 | 'CHIPR0201'    | ''          | ''            | '20221202'
 '0.002'      | '1%'      | '3W'     | '2512LF'  | 'CHIP'   | 'CS+002DFR08'(!)        = ''              | ''                 | 'CS+002DFR08'           |'R2512XJ'| '(SMR2512AW)'                  | '0.002'   | '1%'    | '3W'     | 'DISCRETE' | 'RES CHIP 0.002 3W +-1%(2512)RLC'                  | 'CHIPR2512'    | ''          | ''            | '20221215'
 '0.002'      | '1%'      | '3W'     | '2512LF'  | 'EMPTY'  | 'CS+002DFR08'(!)        = ''              | ''                 | 'CS+002DFR08'           |'R2512XJ'| '(SMR2512AW)'                  | '0.002'   | '1%'    | '3W'     | 'IO'       | 'RES CHIP 0.002 3W +-1%(2512)RLC'                  | 'CHIPR2512'    | ''          | ''            | '20221215'
 '0.002'      | '1%'      | '3W'     | '2512LF'  | 'CHIP'   | 'CS+002DFR09'(!)        = ''              | ''                 | 'CS+002DFR09'           |'R2512XF'| '(SMR2512AW)'                  | '0.002'   | '1%'    | '3W'     | 'DISCRETE' | 'RES CHIP 0.002 3W +-1%(2512)TAI'                  | 'CHIPR2512'    | ''          | ''            | '20221215'
 '0.002'      | '1%'      | '3W'     | '2512LF'  | 'EMPTY'  | 'CS+002DFR09'(!)        = ''              | ''                 | 'CS+002DFR09'           |'R2512XF'| '(SMR2512AW)'                  | '0.002'   | '1%'    | '3W'     | 'IO'       | 'RES CHIP 0.002 3W +-1%(2512)TAI'                  | 'CHIPR2512'    | ''          | ''            | '20221215'
 '0.002'      | '1%'      | '3W'     | '2512LF'  | 'CHIP'   | 'CS+002DFR10'(!)        = ''              | ''                 | 'CS+002DFR10'           |'R2512XAC'| '(SMR2512AW)'                  | '0.002'   | '1%'    | '3W'     | 'DISCRETE' | 'RES CHIP 0.002 3W +-1%(2512)ERO'                  | 'CHIPR2512'    | ''          | ''            | '20221215'
 '0.002'      | '1%'      | '3W'     | '2512LF'  | 'EMPTY'  | 'CS+002DFR10'(!)        = ''              | ''                 | 'CS+002DFR10'           |'R2512XAC'| '(SMR2512AW)'                  | '0.002'   | '1%'    | '3W'     | 'IO'       | 'RES CHIP 0.002 3W +-1%(2512)ERO'                  | 'CHIPR2512'    | ''          | ''            | '20221215'
 '0.003'      | '1%'      | '3W'     | '2512LF'  | 'CHIP'   | 'CS+003DFR05'(!)        = ''              | ''                 | 'CS+003DFR05'           |'R2512XAD'| '(SMR2512AW)'                  | '0.003'   | '1%'    | '3W'     | 'DISCRETE' | 'RES CHIP 0.003 3W +-1%(2512)ERO'                  | 'CHIPR2512'    | ''          | ''            | '20221216'
 '0.003'      | '1%'      | '3W'     | '2512LF'  | 'EMPTY'  | 'CS+003DFR05'(!)        = ''              | ''                 | 'CS+003DFR05'           |'R2512XAD'| '(SMR2512AW)'                  | '0.003'   | '1%'    | '3W'     | 'IO'       | 'RES CHIP 0.003 3W +-1%(2512)ERO'                  | 'CHIPR2512'    | ''          | ''            | '20221216'
 '56K'        | '0.1%'    | '1/16W'  | '0402LF'  | 'CHIP'   | 'CS35602BB01'(!)        = 'End of Design' | 'Comp-Approve'     | 'CS35602BB01'           |'R0402'| '(R0402-0201)'                 | '56K'     | '0.1%'  | '1/16W'  | 'DISCRETE' | 'RES CHIP 56K 1/16W +-0.1%(0402)EF'                | 'CHIPR0402'    | ''          | ''            | '20221214'
 '56K'        | '0.1%'    | '1/16W'  | '0402LF'  | 'EMPTY'  | 'CS35602BB01'(!)        = 'End of Design' | 'Comp-Approve'     | 'CS35602BB01'           |'R0402'| '(R0402-0201)'                 | '56K'     | '0.1%'  | '1/16W'  | 'IO'       | 'RES CHIP 56K 1/16W +-0.1%(0402)EF'                | 'CHIPR0402'    | ''          | ''            | '20221214'
 '549'        | '1%'      | '1/16W'  | '0402LF'  | 'CHIP'   | 'CS15492FB09'(!)        = ''              | ''                 | 'CS15492FB09'           |'R0402'| '(R0402-0201)'                 | '549'     | '1%'    | '1/16W'  | 'DISCRETE' | 'RES CHIP 549 1/16W +-1%(0402)WTC'                 | 'CHIPR0402'    | ''          | ''            | '20221219'
 '549'        | '1%'      | '1/16W'  | '0402LF'  | 'EMPTY'  | 'CS15492FB09'(!)        = ''              | ''                 | 'CS15492FB09'           |'R0402'| '(R0402-0201)'                 | '549'     | '1%'    | '1/16W'  | 'IO'       | 'RES CHIP 549 1/16W +-1%(0402)WTC'                 | 'CHIPR0402'    | ''          | ''            | '20221219'
 '14.7K'      | '1%'      | '1/16W'  | '0402LF'  | 'CHIP'   | 'CS31472FB02'(!)        = 'End of Design' | 'Comp-Approve'     | 'CS31472FB02'           |'R0402'| '(R0402-0201)'                 | '14.7K'   | '1%'    | '1/16W'  | 'DISCRETE' | 'RES CHIP 14.7K 1/16W +-1%(0402)EF'                | 'CHIPR0402'    | ''          | ''            | '20221220'
 '14.7K'      | '1%'      | '1/16W'  | '0402LF'  | 'EMPTY'  | 'CS31472FB02'(!)        = 'End of Design' | 'Comp-Approve'     | 'CS31472FB02'           |'R0402'| '(R0402-0201)'                 | '14.7K'   | '1%'    | '1/16W'  | 'IO'       | 'RES CHIP 14.7K 1/16W +-1%(0402)EF'                | 'CHIPR0402'    | ''          | ''            | '20221220'
 '1.05K'      | '1%'      | '1/16W'  | '0402LF'  | 'CHIP'   | 'CS21052FB06'(!)        = ''              | ''                 | 'CS21052FB06'           |'R0402'| '(R0402-0201)'                 | '1.05K'   | '1%'    | '1/16W'  | 'DISCRETE' | 'RES CHIP 1.05K 1/16W +-1%(0402)EF'                | 'CHIPR0402'    | ''          | ''            | '20221221'
 '1.05K'      | '1%'      | '1/16W'  | '0402LF'  | 'EMPTY'  | 'CS21052FB06'(!)        = ''              | ''                 | 'CS21052FB06'           |'R0402'| '(R0402-0201)'                 | '1.05K'   | '1%'    | '1/16W'  | 'IO'       | 'RES CHIP 1.05K 1/16W +-1%(0402)EF'                | 'CHIPR0402'    | ''          | ''            | '20221221'
 '27'         | '1%'      | '1/16W'  | '0402LF'  | 'CHIP'   | 'CS02702FB01'(!)        = ''              | ''                 | 'CS02702FB01'           |'R0402'| '(R0402-0201)'                 | '27'      | '1%'    | '1/16W'  | 'DISCRETE' | 'RES CHIP 27 1/16W +-1%(0402)EF'                   | 'CHIPR0402'    | ''          | ''            | '20221222'
 '27'         | '1%'      | '1/16W'  | '0402LF'  | 'EMPTY'  | 'CS02702FB01'(!)        = ''              | ''                 | 'CS02702FB01'           |'R0402'| '(R0402-0201)'                 | '27'      | '1%'    | '1/16W'  | 'IO'       | 'RES CHIP 27 1/16W +-1%(0402)EF'                   | 'CHIPR0402'    | ''          | ''            | '20221222'
 '301'        | '1%'      | '1/16W'  | '0402LF'  | 'CHIP'   | 'CS13012FB10'(!)        = ''              | ''                 | 'CS13012FB10'           |'R0402'| '(R0402-0201)'                 | '301'     | '1%'    | '1/16W'  | 'DISCRETE' | 'RES CHIP 301 1/16W +-1%(0402)WTC'                 | 'CHIPR0402'    | ''          | ''            | '20221226'
 '301'        | '1%'      | '1/16W'  | '0402LF'  | 'EMPTY'  | 'CS13012FB10'(!)        = ''              | ''                 | 'CS13012FB10'           |'R0402'| '(R0402-0201)'                 | '301'     | '1%'    | '1/16W'  | 'IO'       | 'RES CHIP 301 1/16W +-1%(0402)WTC'                 | 'CHIPR0402'    | ''          | ''            | '20221226'
 '0.015'      | '0.5%'    | '7W'     | '2818LF'  | 'CHIP'   | 'CS+015LDX00'(!)        = ''              | ''                 | 'CS+015LDX00'           |'R2818XA'| '(SMR2818AW)'                  | '0.015'   | '0.5%'  | '7W'     | 'DISCRETE' | 'RES CHIP 0.015 7W +-0.5%(2818)SIL AEC'            | 'CHIPR2818'    | ''          | ''            | '20230118'
 '0.015'      | '0.5%'    | '7W'     | '2818LF'  | 'EMPTY'  | 'CS+015LDX00'(!)        = ''              | ''                 | 'CS+015LDX00'           |'R2818XA'| '(SMR2818AW)'                  | '0.015'   | '0.5%'  | '7W'     | 'IO'       | 'RES CHIP 0.015 7W +-0.5%(2818)SIL AEC'            | 'CHIPR2818'    | ''          | ''            | '20230118'
 '174K'       | '0.1%'    | '1/8W'   | '0805LF'  | 'CHIP'   | 'CS41744BA00'(!)        = ''              | ''                 | 'CS41744BA00'           |'R0805_H26'| '(SMR0805AW)'                  | '174K'    | '0.1%'  | '1/8W'   | 'DISCRETE' | 'RES CHIP 174K 1/8W +-0.1%(0805)EF'                | 'CHIPR0805'    | ''          | ''            | '20230218'
 '174K'       | '0.1%'    | '1/8W'   | '0805LF'  | 'EMPTY'  | 'CS41744BA00'(!)        = ''              | ''                 | 'CS41744BA00'           |'R0805_H26'| '(SMR0805AW)'                  | '174K'    | '0.1%'  | '1/8W'   | 'IO'       | 'RES CHIP 174K 1/8W +-0.1%(0805)EF'                | 'CHIPR0805'    | ''          | ''            | '20230218'
 '82K'        | '0.1%'    | '1/8W'   | '0805LF'  | 'CHIP'   | 'CS38204BA00'(!)        = ''              | ''                 | 'CS38204BA00'           |'R0805_H26'| '(SMR0805AW)'                  | '82K'     | '0.1%'  | '1/8W'   | 'DISCRETE' | 'RES CHIP 82K 1/8W +-0.1%(0805)EF'                 | 'CHIPR0805'    | ''          | ''            | '20230218'
 '82K'        | '0.1%'    | '1/8W'   | '0805LF'  | 'EMPTY'  | 'CS38204BA00'(!)        = ''              | ''                 | 'CS38204BA00'           |'R0805_H26'| '(SMR0805AW)'                  | '82K'     | '0.1%'  | '1/8W'   | 'IO'       | 'RES CHIP 82K 1/8W +-0.1%(0805)EF'                 | 'CHIPR0805'    | ''          | ''            | '20230218'
 '11.5K'      | '0.1%'    | '1/16W'  | '0402LF'  | 'CHIP'   | 'CS31152BB05'(!)        = ''              | ''                 | 'CS31152BB05'           |'R0402'| '(R0402-0201)'                 | '11.5K'   | '0.1%'  | '1/16W'  | 'DISCRETE' | 'RES CHIP 11.5K 1/16W +-0.1%(0402)EF'              | 'CHIPR0402'    | ''          | ''            | '20230218'
 '11.5K'      | '0.1%'    | '1/16W'  | '0402LF'  | 'EMPTY'  | 'CS31152BB05'(!)        = ''              | ''                 | 'CS31152BB05'           |'R0402'| '(R0402-0201)'                 | '11.5K'   | '0.1%'  | '1/16W'  | 'IO'       | 'RES CHIP 11.5K 1/16W +-0.1%(0402)EF'              | 'CHIPR0402'    | ''          | ''            | '20230218'
 '5.49K'      | '0.1%'    | '1/16W'  | '0402LF'  | 'CHIP'   | 'CS25492BB00'(!)        = ''              | ''                 | 'CS25492BB00'           |'R0402'| '(R0402-0201)'                 | '5.49K'   | '0.1%'  | '1/16W'  | 'DISCRETE' | 'RES CHIP 5.49K 1/16W +-0.1%(0402)EF'              | 'CHIPR0402'    | ''          | ''            | '20230218'
 '5.49K'      | '0.1%'    | '1/16W'  | '0402LF'  | 'EMPTY'  | 'CS25492BB00'(!)        = ''              | ''                 | 'CS25492BB00'           |'R0402'| '(R0402-0201)'                 | '5.49K'   | '0.1%'  | '1/16W'  | 'IO'       | 'RES CHIP 5.49K 1/16W +-0.1%(0402)EF'              | 'CHIPR0402'    | ''          | ''            | '20230218'
 '120K'       | '0.1%'    | '1/16W'  | '0402LF'  | 'CHIP'   | 'CS41202BB01'(!)        = ''              | ''                 | 'CS41202BB01'           |'R0402'| '(R0402-0201)'                 | '120K'    | '0.1%'  | '1/16W'  | 'DISCRETE' | 'RES CHIP 120K 1/16W +-0.1%(0402)EF'               | 'CHIPR0402'    | ''          | ''            | '20230218'
 '120K'       | '0.1%'    | '1/16W'  | '0402LF'  | 'EMPTY'  | 'CS41202BB01'(!)        = ''              | ''                 | 'CS41202BB01'           |'R0402'| '(R0402-0201)'                 | '120K'    | '0.1%'  | '1/16W'  | 'IO'       | 'RES CHIP 120K 1/16W +-0.1%(0402)EF'               | 'CHIPR0402'    | ''          | ''            | '20230218'
 '10.5K'      | '0.1%'    | '1/16W'  | '0402LF'  | 'CHIP'   | 'CS31052BB05'(!)        = ''              | ''                 | 'CS31052BB05'           |'R0402'| '(R0402-0201)'                 | '10.5K'   | '0.1%'  | '1/16W'  | 'DISCRETE' | 'RES CHIP 10.5K 1/16W +-0.1%(0402)EF'              | 'CHIPR0402'    | ''          | ''            | '20230218'
 '10.5K'      | '0.1%'    | '1/16W'  | '0402LF'  | 'EMPTY'  | 'CS31052BB05'(!)        = ''              | ''                 | 'CS31052BB05'           |'R0402'| '(R0402-0201)'                 | '10.5K'   | '0.1%'  | '1/16W'  | 'IO'       | 'RES CHIP 10.5K 1/16W +-0.1%(0402)EF'              | 'CHIPR0402'    | ''          | ''            | '20230218'
 '324K'       | '1%'      | '1/16W'  | '0402LF'  | 'CHIP'   | 'CS43242FB11'(!)        = 'End of Design' | 'Comp-Release Qty' | 'CS43242FB11'           |'R0402'| '(R0402-0201)'                 | '324K'    | '1%'    | '1/16W'  | 'DISCRETE' | 'RES CHIP 324K 1/16W +-1% (0402)'                  | 'CHIPR0402'    | ''          | ''            | '20230307'
 '324K'       | '1%'      | '1/16W'  | '0402LF'  | 'EMPTY'  | 'CS43242FB11'(!)        = 'End of Design' | 'Comp-Release Qty' | 'CS43242FB11'           |'R0402'| '(R0402-0201)'                 | '324K'    | '1%'    | '1/16W'  | 'IO'       | 'RES CHIP 324K 1/16W +-1% (0402)'                  | 'CHIPR0402'    | ''          | ''            | '20230307'
 '49.9'       | '1%'      | '1/20W'  | '0201LF'  | 'CHIP'   | 'CS04991FE06'(!)        = 'End of Design' | 'Comp-Approve'     | 'CS04991FE06'           |'R0201'| '(SMR0201AW)'                  | '49.9'    | '1%'    | '1/20W'  | 'DISCRETE' | 'RES CHIP 49.9 1/20W +-1%(0201)EF'                 | 'CHIPR0201'    | ''          | ''            | '20230307'
 '49.9'       | '1%'      | '1/20W'  | '0201LF'  | 'EMPTY'  | 'CS04991FE06'(!)        = 'End of Design' | 'Comp-Approve'     | 'CS04991FE06'           |'R0201'| '(SMR0201AW)'                  | '49.9'    | '1%'    | '1/20W'  | 'IO'       | 'RES CHIP 49.9 1/20W +-1%(0201)EF'                 | 'CHIPR0201'    | ''          | ''            | '20230307'
 '4.64K'      | '1%'      | '1/16W'  | '0402LF'  | 'CHIP'   | 'CS24642FB14'(!)        = 'End of Design' | 'Comp-Approve'     | 'CS24642FB14'           |'R0402'| '(R0402-0201)'                 | '4.64K'   | '1%'    | '1/16W'  | 'DISCRETE' | 'RES CHIP 4.64K 1/16W +-1% (0402)'                 | 'CHIPR0402'    | ''          | ''            | '20230316'
 '4.64K'      | '1%'      | '1/16W'  | '0402LF'  | 'EMPTY'  | 'CS24642FB14'(!)        = 'End of Design' | 'Comp-Approve'     | 'CS24642FB14'           |'R0402'| '(R0402-0201)'                 | '4.64K'   | '1%'    | '1/16W'  | 'IO'       | 'RES CHIP 4.64K 1/16W +-1% (0402)'                 | 'CHIPR0402'    | ''          | ''            | '20230316'

END_PART

END.

